(kicad_pcb
	(version 20260206)
	(generator "pcbnew")
	(generator_version "10.0")
	(general
		(thickness 1.6)
		(legacy_teardrops no)
	)
	(paper "A4")
	(layers
		(0 "F.Cu" signal "TOP")
		(4 "In1.Cu" signal "GND")
		(6 "In2.Cu" signal "IN1")
		(8 "In3.Cu" signal "VCC")
		(10 "In4.Cu" signal "VCC1")
		(12 "In5.Cu" signal "IN2")
		(14 "In6.Cu" signal "GND1")
		(2 "B.Cu" signal "BOTTOM")
		(9 "F.Adhes" user "F.Adhesive")
		(11 "B.Adhes" user "B.Adhesive")
		(13 "F.Paste" user "Package Geometry/Pastemask Top")
		(15 "B.Paste" user "Package Geometry/Pastemask Bottom")
		(5 "F.SilkS" user "Ref Des/Silkscreen Top")
		(7 "B.SilkS" user "Ref Des/Silkscreen Bottom")
		(1 "F.Mask" user "Board Geometry/Soldermask Top")
		(3 "B.Mask" user "Board Geometry/Soldermask Bottom")
		(17 "Dwgs.User" user "User.Drawings")
		(19 "Cmts.User" user "User.Comments")
		(21 "Eco1.User" user "User.Eco1")
		(23 "Eco2.User" user "User.Eco2")
		(25 "Edge.Cuts" user "Board Geometry/Outline")
		(27 "Margin" user)
		(31 "F.CrtYd" user "Package Geometry/Place Bound Top")
		(29 "B.CrtYd" user "Package Geometry/Place Bound Bottom")
		(35 "F.Fab" user "Ref Des/Assembly Top")
		(33 "B.Fab" user "Ref Des/Assembly Bottom")
	)
	(setup
		(pad_to_mask_clearance 0)
		(allow_soldermask_bridges_in_footprints no)
		(tenting
			(front yes)
			(back yes)
		)
		(covering
			(front no)
			(back no)
		)
		(plugging
			(front no)
			(back no)
		)
		(capping no)
		(filling no)
		(pcbplotparams
			(layerselection 0x00000000_00000000_55555555_5755f5ff)
			(plot_on_all_layers_selection 0x00000000_00000000_00000000_00000000)
			(disableapertmacros no)
			(usegerberextensions no)
			(usegerberattributes yes)
			(usegerberadvancedattributes yes)
			(creategerberjobfile yes)
			(dashed_line_dash_ratio 12)
			(dashed_line_gap_ratio 3)
			(svgprecision 4)
			(plotframeref no)
			(mode 1)
			(useauxorigin no)
			(pdf_front_fp_property_popups yes)
			(pdf_back_fp_property_popups yes)
			(pdf_metadata yes)
			(pdf_single_document no)
			(dxfpolygonmode yes)
			(dxfimperialunits yes)
			(dxfusepcbnewfont yes)
			(psnegative no)
			(psa4output no)
			(plot_black_and_white yes)
			(sketchpadsonfab no)
			(plotpadnumbers no)
			(hidednponfab no)
			(sketchdnponfab yes)
			(crossoutdnponfab yes)
			(subtractmaskfromsilk no)
			(outputformat 1)
			(mirror no)
			(drillshape 1)
			(scaleselection 1)
			(outputdirectory "")
		)
	)
	(footprint ""
		(layer "F.Cu")
		(at 27.639264 -285.429452 -90)
		(property "Reference" "R109"
			(at -1.498854 1.234948 90)
			(unlocked yes)
			(layer "F.SilkS")
			(effects
				(font
					(size 0.7874 0.5842)
					(thickness 0.1524)
				)
				(justify left)
			)
		)
		(property "Value" ""
			(at 0 0 270)
			(layer "F.Fab")
			(effects
				(font
					(size 1.27 1.27)
				)
			)
		)
		(duplicate_pad_numbers_are_jumpers no)
		(fp_line
			(start -0.7874 0.4064)
			(end -0.7874 -0.4064)
			(stroke
				(width 0.1524)
				(type default)
			)
			(layer "F.SilkS")
		)
		(fp_line
			(start 0.7874 0.4064)
			(end -0.7874 0.4064)
			(stroke
				(width 0.1524)
				(type default)
			)
			(layer "F.SilkS")
		)
		(fp_line
			(start -0.7874 -0.4064)
			(end 0.7874 -0.4064)
			(stroke
				(width 0.1524)
				(type default)
			)
			(layer "F.SilkS")
		)
		(fp_line
			(start 0.7874 -0.4064)
			(end 0.7874 0.4064)
			(stroke
				(width 0.1524)
				(type default)
			)
			(layer "F.SilkS")
		)
		(fp_poly
			(pts
				(xy -0.508 0.2794) (xy -0.508 0.2286) (xy -0.635 0.2286) (xy -0.635 -0.254) (xy -0.5334 -0.254)
				(xy -0.5334 -0.2794) (xy 0.5334 -0.2794) (xy 0.5334 -0.254) (xy 0.635 -0.254) (xy 0.635 0.254) (xy 0.5334 0.254)
				(xy 0.5334 0.2794)
			)
			(stroke
				(width 0)
				(type default)
			)
			(fill no)
			(layer "F.CrtYd")
		)
		(pad "1" smd rect
			(at 0.40005 0 270)
			(size 0.4572 0.508)
			(layers "F.Cu" "F.Mask" "F.Paste")
			(net "PSU4_REMOTE_N")
		)
		(pad "2" smd rect
			(at -0.40005 0 270)
			(size 0.4572 0.508)
			(layers "F.Cu" "F.Mask" "F.Paste")
			(net "PSU4_REMOTE_R_N")
		)
	)
	(footprint ""
		(layer "F.Cu")
		(at 16.599916 -118.09984)
		(property "Reference" "H10"
			(at -7.888224 -6.127242 0)
			(unlocked yes)
			(layer "F.SilkS")
			(effects
				(font
					(size 0.7874 0.5842)
					(thickness 0.1524)
				)
				(justify left)
			)
		)
		(property "Value" ""
			(at 0 0 0)
			(layer "F.Fab")
			(effects
				(font
					(size 1.27 1.27)
				)
			)
		)
		(duplicate_pad_numbers_are_jumpers no)
		(fp_circle
			(center 0 0)
			(end 7.999984 0)
			(stroke
				(width 0.1524)
				(type default)
			)
			(fill no)
			(layer "F.SilkS")
		)
		(fp_circle
			(center 0 0)
			(end 14.7066 0)
			(stroke
				(width 0.1524)
				(type default)
			)
			(fill no)
			(layer "B.SilkS")
		)
		(fp_poly
			(pts
				(arc
					(start 0 5.0038)
					(mid 0 -5.0038)
					(end 0 5.0038)
				)
			)
			(stroke
				(width 0)
				(type default)
			)
			(fill no)
			(layer "F.CrtYd")
		)
		(pad "" np_thru_hole circle
			(at 0 0)
			(size 4.0132 4.0132)
			(drill 4.0132)
			(layers "*.Cu" "*.Mask")
			(clearance 0.381)
			(thermal_gap 0.381)
		)
		(pad "2" thru_hole circle
			(at 0 -3.50012)
			(size 0.762 0.762)
			(drill 0.5588)
			(layers "*.Cu" "*.Mask")
			(remove_unused_layers no)
			(net "GND")
			(clearance 0.1524)
			(thermal_gap 0.1524)
		)
		(pad "3" thru_hole circle
			(at -2.500122 -2.500122)
			(size 0.762 0.762)
			(drill 0.5588)
			(layers "*.Cu" "*.Mask")
			(remove_unused_layers no)
			(net "GND")
			(clearance 0.1524)
			(thermal_gap 0.1524)
		)
		(pad "4" thru_hole circle
			(at -3.50012 0)
			(size 0.762 0.762)
			(drill 0.5588)
			(layers "*.Cu" "*.Mask")
			(remove_unused_layers no)
			(net "GND")
			(clearance 0.1524)
			(thermal_gap 0.1524)
		)
		(pad "5" thru_hole circle
			(at -2.500122 2.500122)
			(size 0.762 0.762)
			(drill 0.5588)
			(layers "*.Cu" "*.Mask")
			(remove_unused_layers no)
			(net "GND")
			(clearance 0.1524)
			(thermal_gap 0.1524)
		)
		(pad "6" thru_hole circle
			(at 0 3.50012)
			(size 0.762 0.762)
			(drill 0.5588)
			(layers "*.Cu" "*.Mask")
			(remove_unused_layers no)
			(net "GND")
			(clearance 0.1524)
			(thermal_gap 0.1524)
		)
		(pad "7" thru_hole circle
			(at 2.500122 2.500122)
			(size 0.762 0.762)
			(drill 0.5588)
			(layers "*.Cu" "*.Mask")
			(remove_unused_layers no)
			(net "GND")
			(clearance 0.1524)
			(thermal_gap 0.1524)
		)
		(pad "8" thru_hole circle
			(at 3.50012 0)
			(size 0.762 0.762)
			(drill 0.5588)
			(layers "*.Cu" "*.Mask")
			(remove_unused_layers no)
			(net "GND")
			(clearance 0.1524)
			(thermal_gap 0.1524)
		)
		(pad "9" thru_hole circle
			(at 2.500122 -2.500122)
			(size 0.762 0.762)
			(drill 0.5588)
			(layers "*.Cu" "*.Mask")
			(remove_unused_layers no)
			(net "GND")
			(clearance 0.1524)
			(thermal_gap 0.1524)
		)
		(zone
			(layer "F.Cu")
			(hatch none 0.5)
			(connect_pads
				(clearance 0)
			)
			(min_thickness 0.25)
			(keepout
				(tracks not_allowed)
				(vias allowed)
				(pads allowed)
				(copperpour not_allowed)
				(footprints allowed)
			)
			(placement
				(enabled no)
				(sheetname "")
			)
			(fill
				(thermal_gap 0.5)
				(thermal_bridge_width 0.5)
				(island_removal_mode 0)
			)
			(polygon
				(pts
					(arc
						(start 16.599916 -126.10084)
						(mid 8.598916 -118.09984)
						(end 16.599916 -110.09884)
					)
					(arc
						(start 16.599916 -110.09884)
						(mid 18.035016 -111.53394)
						(end 16.599916 -112.96904)
					)
					(arc
						(start 16.599916 -112.96904)
						(mid 11.469116 -118.09984)
						(end 16.599916 -123.23064)
					)
					(arc
						(start 16.599916 -123.23064)
						(mid 18.035016 -124.66574)
						(end 16.599916 -126.10084)
					)
				)
			)
		)
		(zone
			(layer "F.Cu")
			(hatch none 0.5)
			(connect_pads
				(clearance 0)
			)
			(min_thickness 0.25)
			(keepout
				(tracks not_allowed)
				(vias allowed)
				(pads allowed)
				(copperpour not_allowed)
				(footprints allowed)
			)
			(placement
				(enabled no)
				(sheetname "")
			)
			(fill
				(thermal_gap 0.5)
				(thermal_bridge_width 0.5)
				(island_removal_mode 0)
			)
			(polygon
				(pts
					(arc
						(start 16.599916 -126.10084)
						(mid 24.600916 -118.09984)
						(end 16.599916 -110.09884)
					)
					(arc
						(start 16.599916 -110.09884)
						(mid 15.164816 -111.53394)
						(end 16.599916 -112.96904)
					)
					(arc
						(start 16.599916 -112.96904)
						(mid 21.730716 -118.09984)
						(end 16.599916 -123.23064)
					)
					(arc
						(start 16.599916 -123.23064)
						(mid 15.164816 -124.66574)
						(end 16.599916 -126.10084)
					)
				)
			)
		)
		(zone
			(layers "F.Cu" "B.Cu" "In1.Cu" "In2.Cu" "In3.Cu" "In4.Cu" "In5.Cu" "In6.Cu")
			(hatch none 0.5)
			(connect_pads
				(clearance 0)
			)
			(min_thickness 0.25)
			(keepout
				(tracks not_allowed)
				(vias allowed)
				(pads allowed)
				(copperpour not_allowed)
				(footprints allowed)
			)
			(placement
				(enabled no)
				(sheetname "")
			)
			(fill
				(thermal_gap 0.5)
				(thermal_bridge_width 0.5)
				(island_removal_mode 0)
			)
			(polygon
				(pts
					(arc
						(start 16.599916 -115.58778)
						(mid 16.599916 -120.6119)
						(end 16.599916 -115.58778)
					)
				)
			)
		)
	)
	(footprint ""
		(layer "F.Cu")
		(at 27.577796 -373.032528 90)
		(property "Reference" "R129"
			(at -3.094482 -0.932942 90)
			(unlocked yes)
			(layer "F.SilkS")
			(effects
				(font
					(size 0.7874 0.5842)
					(thickness 0.1524)
				)
				(justify left)
			)
		)
		(property "Value" ""
			(at 0 0 90)
			(layer "F.Fab")
			(effects
				(font
					(size 1.27 1.27)
				)
			)
		)
		(duplicate_pad_numbers_are_jumpers no)
		(fp_line
			(start 0.7874 -0.4064)
			(end 0.7874 0.4064)
			(stroke
				(width 0.1524)
				(type default)
			)
			(layer "F.SilkS")
		)
		(fp_line
			(start -0.7874 -0.4064)
			(end 0.7874 -0.4064)
			(stroke
				(width 0.1524)
				(type default)
			)
			(layer "F.SilkS")
		)
		(fp_line
			(start 0.7874 0.4064)
			(end -0.7874 0.4064)
			(stroke
				(width 0.1524)
				(type default)
			)
			(layer "F.SilkS")
		)
		(fp_line
			(start -0.7874 0.4064)
			(end -0.7874 -0.4064)
			(stroke
				(width 0.1524)
				(type default)
			)
			(layer "F.SilkS")
		)
		(fp_poly
			(pts
				(xy -0.508 0.2794) (xy -0.508 0.2286) (xy -0.635 0.2286) (xy -0.635 -0.254) (xy -0.5334 -0.254)
				(xy -0.5334 -0.2794) (xy 0.5334 -0.2794) (xy 0.5334 -0.254) (xy 0.635 -0.254) (xy 0.635 0.254) (xy 0.5334 0.254)
				(xy 0.5334 0.2794)
			)
			(stroke
				(width 0)
				(type default)
			)
			(fill no)
			(layer "F.CrtYd")
		)
		(pad "1" smd rect
			(at 0.40005 0 90)
			(size 0.4572 0.508)
			(layers "F.Cu" "F.Mask" "F.Paste")
			(net "PSU5_REMOTE_N")
		)
		(pad "2" smd rect
			(at -0.40005 0 90)
			(size 0.4572 0.508)
			(layers "F.Cu" "F.Mask" "F.Paste")
			(net "PSU5_REMOTE_R2_N")
		)
	)
	(footprint ""
		(layer "F.Cu")
		(at 74.832718 -259.450078 90)
		(property "Reference" "C46"
			(at -4.410456 0.239268 90)
			(unlocked yes)
			(layer "F.SilkS")
			(effects
				(font
					(size 0.7874 0.5842)
					(thickness 0.1524)
				)
				(justify left)
			)
		)
		(property "Value" ""
			(at 0 0 90)
			(layer "F.Fab")
			(effects
				(font
					(size 1.27 1.27)
				)
			)
		)
		(duplicate_pad_numbers_are_jumpers no)
		(fp_line
			(start 0.7874 -0.4064)
			(end 0.7874 0.4064)
			(stroke
				(width 0.1524)
				(type default)
			)
			(layer "F.SilkS")
		)
		(fp_line
			(start -0.7874 -0.4064)
			(end 0.7874 -0.4064)
			(stroke
				(width 0.1524)
				(type default)
			)
			(layer "F.SilkS")
		)
		(fp_line
			(start 0 0.381)
			(end 0 -0.381)
			(stroke
				(width 0.1524)
				(type default)
			)
			(layer "F.SilkS")
		)
		(fp_line
			(start 0.7874 0.4064)
			(end -0.7874 0.4064)
			(stroke
				(width 0.1524)
				(type default)
			)
			(layer "F.SilkS")
		)
		(fp_line
			(start -0.7874 0.4064)
			(end -0.7874 -0.4064)
			(stroke
				(width 0.1524)
				(type default)
			)
			(layer "F.SilkS")
		)
		(fp_poly
			(pts
				(xy -0.5334 0.254) (xy -0.635 0.254) (xy -0.635 0.2286) (xy -0.635 -0.254) (xy -0.5334 -0.254) (xy -0.5334 -0.2794)
				(xy 0.5334 -0.2794) (xy 0.5334 -0.254) (xy 0.635 -0.254) (xy 0.635 0.254) (xy 0.5334 0.254) (xy 0.5334 0.2794)
				(xy -0.508 0.2794) (xy -0.5334 0.2794)
			)
			(stroke
				(width 0)
				(type default)
			)
			(fill no)
			(layer "F.CrtYd")
		)
		(pad "1" smd rect
			(at 0.40005 0 90)
			(size 0.4572 0.508)
			(layers "F.Cu" "F.Mask" "F.Paste")
			(net "P12V")
		)
		(pad "2" smd rect
			(at -0.40005 0 90)
			(size 0.4572 0.508)
			(layers "F.Cu" "F.Mask" "F.Paste")
			(net "GND")
		)
	)
	(footprint ""
		(layer "F.Cu")
		(at 25.857708 -361.78236)
		(property "Reference" "R81"
			(at -3.917442 -0.225298 0)
			(unlocked yes)
			(layer "F.SilkS")
			(effects
				(font
					(size 0.7874 0.5842)
					(thickness 0.1524)
				)
				(justify left)
			)
		)
		(property "Value" ""
			(at 0 0 0)
			(layer "F.Fab")
			(effects
				(font
					(size 1.27 1.27)
				)
			)
		)
		(duplicate_pad_numbers_are_jumpers no)
		(fp_line
			(start -0.7874 -0.4064)
			(end 0.7874 -0.4064)
			(stroke
				(width 0.1524)
				(type default)
			)
			(layer "F.SilkS")
		)
		(fp_line
			(start -0.7874 0.4064)
			(end -0.7874 -0.4064)
			(stroke
				(width 0.1524)
				(type default)
			)
			(layer "F.SilkS")
		)
		(fp_line
			(start 0.7874 -0.4064)
			(end 0.7874 0.4064)
			(stroke
				(width 0.1524)
				(type default)
			)
			(layer "F.SilkS")
		)
		(fp_line
			(start 0.7874 0.4064)
			(end -0.7874 0.4064)
			(stroke
				(width 0.1524)
				(type default)
			)
			(layer "F.SilkS")
		)
		(fp_poly
			(pts
				(xy -0.508 0.2794) (xy -0.508 0.2286) (xy -0.635 0.2286) (xy -0.635 -0.254) (xy -0.5334 -0.254)
				(xy -0.5334 -0.2794) (xy 0.5334 -0.2794) (xy 0.5334 -0.254) (xy 0.635 -0.254) (xy 0.635 0.254) (xy 0.5334 0.254)
				(xy 0.5334 0.2794)
			)
			(stroke
				(width 0)
				(type default)
			)
			(fill no)
			(layer "F.CrtYd")
		)
		(pad "1" smd rect
			(at 0.40005 0)
			(size 0.4572 0.508)
			(layers "F.Cu" "F.Mask" "F.Paste")
			(net "PSU5_RESET")
		)
		(pad "2" smd rect
			(at -0.40005 0)
			(size 0.4572 0.508)
			(layers "F.Cu" "F.Mask" "F.Paste")
			(net "GND")
		)
	)
	(footprint ""
		(layer "F.Cu")
		(at 30.45968 -348.52991)
		(property "Reference" "J4"
			(at 7.95274 12.227052 0)
			(unlocked yes)
			(layer "F.SilkS")
			(effects
				(font
					(size 0.7874 0.5842)
					(thickness 0.1524)
				)
				(justify left)
			)
		)
		(property "Value" ""
			(at 0 0 0)
			(layer "F.Fab")
			(effects
				(font
					(size 1.27 1.27)
				)
			)
		)
		(duplicate_pad_numbers_are_jumpers no)
		(fp_line
			(start -2.135124 -4.560062)
			(end -2.135124 83.300062)
			(stroke
				(width 0.1524)
				(type default)
			)
			(layer "F.SilkS")
		)
		(fp_line
			(start -2.135124 83.300062)
			(end 7.215124 83.300062)
			(stroke
				(width 0.1524)
				(type default)
			)
			(layer "F.SilkS")
		)
		(fp_line
			(start 7.215124 -4.560062)
			(end -2.135124 -4.560062)
			(stroke
				(width 0.1524)
				(type default)
			)
			(layer "F.SilkS")
		)
		(fp_line
			(start 7.215124 83.300062)
			(end 7.215124 -4.560062)
			(stroke
				(width 0.1524)
				(type default)
			)
			(layer "F.SilkS")
		)
		(fp_poly
			(pts
				(xy -2.422398 -0.000762) (xy -5.122418 -0.700786) (xy -5.122418 0.699262)
			)
			(stroke
				(width 0)
				(type default)
			)
			(fill yes)
			(layer "F.SilkS")
		)
		(fp_poly
			(pts
				(xy -2.28219 -0.127) (xy -4.98221 -0.827024) (xy -4.98221 0.573024)
			)
			(stroke
				(width 0)
				(type default)
			)
			(fill yes)
			(layer "B.SilkS")
		)
		(fp_poly
			(pts
				(xy -0.8636 -0.8636) (xy -0.8636 79.6036) (xy -0.8636 79.629) (xy 5.9436 79.629) (xy 5.9436 79.6036)
				(xy 5.9436 -0.8636) (xy 5.9436 -0.889) (xy -0.8636 -0.889)
			)
			(stroke
				(width 0)
				(type default)
			)
			(fill no)
			(layer "B.CrtYd")
		)
		(fp_rect
			(start -2.135124 -4.560062)
			(end 7.21487 83.300062)
			(stroke
				(width 0)
				(type default)
			)
			(fill no)
			(layer "F.CrtYd")
		)
		(fp_line
			(start -2.135124 -4.560062)
			(end 7.215124 -4.560062)
			(stroke
				(width 0.1)
				(type default)
			)
			(layer "F.Fab")
		)
		(fp_line
			(start -2.135124 83.300062)
			(end -2.135124 -4.560062)
			(stroke
				(width 0.1)
				(type default)
			)
			(layer "F.Fab")
		)
		(fp_line
			(start 7.215124 -4.560062)
			(end 7.215124 83.300062)
			(stroke
				(width 0.1)
				(type default)
			)
			(layer "F.Fab")
		)
		(fp_line
			(start 7.215124 83.300062)
			(end -2.135124 83.300062)
			(stroke
				(width 0.1)
				(type default)
			)
			(layer "F.Fab")
		)
		(fp_text user "32"
			(at -3.83159 78.970124 0)
			(unlocked yes)
			(layer "F.SilkS")
			(effects
				(font
					(size 0.7874 0.5842)
					(thickness 0.1524)
				)
				(justify left)
			)
		)
		(fp_text user "1"
			(at -3.299206 -1.063752 0)
			(unlocked yes)
			(layer "F.SilkS")
			(effects
				(font
					(size 0.7874 0.5842)
					(thickness 0.1524)
				)
				(justify left)
			)
		)
		(fp_text user "33"
			(at 7.548626 82.342482 0)
			(unlocked yes)
			(layer "F.SilkS")
			(effects
				(font
					(size 0.7874 0.5842)
					(thickness 0.1524)
				)
				(justify left)
			)
		)
		(fp_text user "64"
			(at 7.602728 -0.1905 0)
			(unlocked yes)
			(layer "F.SilkS")
			(effects
				(font
					(size 0.7874 0.5842)
					(thickness 0.1524)
				)
				(justify left)
			)
		)
		(fp_text user "1"
			(at -1.714246 -0.92456 0)
			(unlocked yes)
			(layer "B.SilkS")
			(effects
				(font
					(size 0.7874 0.5842)
					(thickness 0.1524)
				)
				(justify left mirror)
			)
		)
		(fp_text user "32"
			(at -0.789432 79.774796 0)
			(unlocked yes)
			(layer "B.SilkS")
			(effects
				(font
					(size 0.7874 0.5842)
					(thickness 0.1524)
				)
				(justify left mirror)
			)
		)
		(fp_text user "64"
			(at 5.867146 -1.71323 0)
			(unlocked yes)
			(layer "B.SilkS")
			(effects
				(font
					(size 0.7874 0.5842)
					(thickness 0.1524)
				)
				(justify left mirror)
			)
		)
		(fp_text user "33"
			(at 5.969508 82.246216 0)
			(unlocked yes)
			(layer "B.SilkS")
			(effects
				(font
					(size 0.7874 0.5842)
					(thickness 0.1524)
				)
				(justify left mirror)
			)
		)
		(pad "1" thru_hole rect
			(at 0 0 270)
			(size 1.6256 1.6256)
			(drill 1.1176)
			(layers "*.Cu" "*.Mask")
			(remove_unused_layers no)
			(net "P12V")
			(clearance 0)
			(padstack
				(mode front_inner_back)
				(layer "Inner"
					(shape circle)
					(size 1.6256 1.6256)
					(clearance 0)
				)
				(layer "B.Cu"
					(shape rect)
					(size 1.6256 1.6256)
					(clearance 0)
				)
			)
		)
		(pad "2" thru_hole circle
			(at 0 2.54 270)
			(size 1.6256 1.6256)
			(drill 1.1176)
			(layers "*.Cu" "*.Mask")
			(remove_unused_layers no)
			(net "P12V")
			(clearance 0)
		)
		(pad "3" thru_hole circle
			(at 0 5.08 270)
			(size 1.6256 1.6256)
			(drill 1.1176)
			(layers "*.Cu" "*.Mask")
			(remove_unused_layers no)
			(net "P12V")
			(clearance 0)
		)
		(pad "4" thru_hole circle
			(at 0 7.62 270)
			(size 1.6256 1.6256)
			(drill 1.1176)
			(layers "*.Cu" "*.Mask")
			(remove_unused_layers no)
			(net "P12V")
			(clearance 0)
		)
		(pad "5" thru_hole circle
			(at 0 10.16 270)
			(size 1.6256 1.6256)
			(drill 1.1176)
			(layers "*.Cu" "*.Mask")
			(remove_unused_layers no)
			(net "P12V")
			(clearance 0)
		)
		(pad "6" thru_hole circle
			(at 0 12.7 270)
			(size 1.6256 1.6256)
			(drill 1.1176)
			(layers "*.Cu" "*.Mask")
			(remove_unused_layers no)
			(net "P12V")
			(clearance 0)
		)
		(pad "7" thru_hole circle
			(at 0 15.24 270)
			(size 1.6256 1.6256)
			(drill 1.1176)
			(layers "*.Cu" "*.Mask")
			(remove_unused_layers no)
			(net "P12V")
			(clearance 0)
		)
		(pad "8" thru_hole circle
			(at 0 17.78 270)
			(size 1.6256 1.6256)
			(drill 1.1176)
			(layers "*.Cu" "*.Mask")
			(remove_unused_layers no)
			(net "P12V")
			(clearance 0)
		)
		(pad "9" thru_hole circle
			(at 0 20.32 270)
			(size 1.6256 1.6256)
			(drill 1.1176)
			(layers "*.Cu" "*.Mask")
			(remove_unused_layers no)
			(net "P12V")
			(clearance 0)
		)
		(pad "10" thru_hole circle
			(at 0 22.86 270)
			(size 1.6256 1.6256)
			(drill 1.1176)
			(layers "*.Cu" "*.Mask")
			(remove_unused_layers no)
			(net "P12V")
			(clearance 0)
		)
		(pad "11" thru_hole circle
			(at 0 25.4 270)
			(size 1.6256 1.6256)
			(drill 1.1176)
			(layers "*.Cu" "*.Mask")
			(remove_unused_layers no)
			(net "P12V")
			(clearance 0)
		)
		(pad "12" thru_hole circle
			(at 0 27.94 270)
			(size 1.6256 1.6256)
			(drill 1.1176)
			(layers "*.Cu" "*.Mask")
			(remove_unused_layers no)
			(net "P12V")
			(clearance 0)
		)
		(pad "13" thru_hole circle
			(at 0 30.48 270)
			(size 1.6256 1.6256)
			(drill 1.1176)
			(layers "*.Cu" "*.Mask")
			(remove_unused_layers no)
			(net "GND")
			(clearance 0)
		)
		(pad "14" thru_hole circle
			(at 0 33.02 270)
			(size 1.6256 1.6256)
			(drill 1.1176)
			(layers "*.Cu" "*.Mask")
			(remove_unused_layers no)
			(net "GND")
			(clearance 0)
		)
		(pad "15" thru_hole circle
			(at 0 35.56 270)
			(size 1.6256 1.6256)
			(drill 1.1176)
			(layers "*.Cu" "*.Mask")
			(remove_unused_layers no)
			(net "GND")
			(clearance 0)
		)
		(pad "16" thru_hole circle
			(at 0 38.1 270)
			(size 1.6256 1.6256)
			(drill 1.1176)
			(layers "*.Cu" "*.Mask")
			(remove_unused_layers no)
			(net "GND")
			(clearance 0)
		)
		(pad "17" thru_hole circle
			(at 0 40.64 270)
			(size 1.6256 1.6256)
			(drill 1.1176)
			(layers "*.Cu" "*.Mask")
			(remove_unused_layers no)
			(net "GND")
			(clearance 0)
		)
		(pad "18" thru_hole circle
			(at 0 43.18 270)
			(size 1.6256 1.6256)
			(drill 1.1176)
			(layers "*.Cu" "*.Mask")
			(remove_unused_layers no)
			(net "GND")
			(clearance 0)
		)
		(pad "19" thru_hole circle
			(at 0 45.72 270)
			(size 1.6256 1.6256)
			(drill 1.1176)
			(layers "*.Cu" "*.Mask")
			(remove_unused_layers no)
			(net "GND")
			(clearance 0)
		)
		(pad "20" thru_hole circle
			(at 0 48.26 270)
			(size 1.6256 1.6256)
			(drill 1.1176)
			(layers "*.Cu" "*.Mask")
			(remove_unused_layers no)
			(net "GND")
			(clearance 0)
		)
		(pad "21" thru_hole circle
			(at 0 50.8 270)
			(size 1.6256 1.6256)
			(drill 1.1176)
			(layers "*.Cu" "*.Mask")
			(remove_unused_layers no)
			(net "GND")
			(clearance 0)
		)
		(pad "22" thru_hole circle
			(at 0 53.34 270)
			(size 1.6256 1.6256)
			(drill 1.1176)
			(layers "*.Cu" "*.Mask")
			(remove_unused_layers no)
			(net "GND")
			(clearance 0)
		)
		(pad "23" thru_hole circle
			(at 0 55.88 270)
			(size 1.6256 1.6256)
			(drill 1.1176)
			(layers "*.Cu" "*.Mask")
			(remove_unused_layers no)
			(net "GND")
			(clearance 0)
		)
		(pad "24" thru_hole circle
			(at 0 58.42 270)
			(size 1.6256 1.6256)
			(drill 1.1176)
			(layers "*.Cu" "*.Mask")
			(remove_unused_layers no)
			(net "GND")
			(clearance 0)
		)
		(pad "25" thru_hole circle
			(at 0 60.96 270)
			(size 1.6256 1.6256)
			(drill 1.1176)
			(layers "*.Cu" "*.Mask")
			(remove_unused_layers no)
			(net "PHLOSS")
			(clearance 0)
		)
		(pad "26" thru_hole circle
			(at 0 63.5 270)
			(size 1.6256 1.6256)
			(drill 1.1176)
			(layers "*.Cu" "*.Mask")
			(remove_unused_layers no)
			(net "PSU4_REMOTE_N")
			(clearance 0)
		)
		(pad "27" thru_hole circle
			(at 0 66.04 270)
			(size 1.6256 1.6256)
			(drill 1.1176)
			(layers "*.Cu" "*.Mask")
			(remove_unused_layers no)
			(net "PSU4_AC_OK")
			(clearance 0)
		)
		(pad "28" thru_hole circle
			(at 0 68.58 270)
			(size 1.6256 1.6256)
			(drill 1.1176)
			(layers "*.Cu" "*.Mask")
			(remove_unused_layers no)
			(net "PSU4_CSAHRE")
			(clearance 0)
		)
		(pad "29" thru_hole circle
			(at 0 71.12 270)
			(size 1.6256 1.6256)
			(drill 1.1176)
			(layers "*.Cu" "*.Mask")
			(remove_unused_layers no)
			(net "PSU4_PS_ON_N")
			(clearance 0)
		)
		(pad "30" thru_hole circle
			(at 0 73.66 270)
			(size 1.6256 1.6256)
			(drill 1.1176)
			(layers "*.Cu" "*.Mask")
			(remove_unused_layers no)
			(net "PSU4_PS_KILL")
			(clearance 0)
		)
		(pad "31" thru_hole circle
			(at 0 76.2 270)
			(size 1.6256 1.6256)
			(drill 1.1176)
			(layers "*.Cu" "*.Mask")
			(remove_unused_layers no)
			(net "PSU4_RESET")
			(clearance 0)
		)
		(pad "32" thru_hole circle
			(at 0 78.74 270)
			(size 1.6256 1.6256)
			(drill 1.1176)
			(layers "*.Cu" "*.Mask")
			(remove_unused_layers no)
			(net "PSU_ALERT_N")
			(clearance 0)
		)
		(pad "33" thru_hole circle
			(at 5.08 78.74 270)
			(size 1.6256 1.6256)
			(drill 1.1176)
			(layers "*.Cu" "*.Mask")
			(remove_unused_layers no)
			(net "I2C_PSU2_SDA")
			(clearance 0)
		)
		(pad "34" thru_hole circle
			(at 5.08 76.2 270)
			(size 1.6256 1.6256)
			(drill 1.1176)
			(layers "*.Cu" "*.Mask")
			(remove_unused_layers no)
			(net "Net_427")
			(clearance 0)
		)
		(pad "35" thru_hole circle
			(at 5.08 73.66 270)
			(size 1.6256 1.6256)
			(drill 1.1176)
			(layers "*.Cu" "*.Mask")
			(remove_unused_layers no)
			(net "I2C_PSU2_SCL")
			(clearance 0)
		)
		(pad "36" thru_hole circle
			(at 5.08 71.12 270)
			(size 1.6256 1.6256)
			(drill 1.1176)
			(layers "*.Cu" "*.Mask")
			(remove_unused_layers no)
			(net "PSU4_RETURN")
			(clearance 0)
		)
		(pad "37" thru_hole circle
			(at 5.08 68.58 270)
			(size 1.6256 1.6256)
			(drill 1.1176)
			(layers "*.Cu" "*.Mask")
			(remove_unused_layers no)
			(net "PSU4_DC_OK")
			(clearance 0)
		)
		(pad "38" thru_hole circle
			(at 5.08 66.04 270)
			(size 1.6256 1.6256)
			(drill 1.1176)
			(layers "*.Cu" "*.Mask")
			(remove_unused_layers no)
			(net "PSU4_AD0")
			(clearance 0)
		)
		(pad "39" thru_hole circle
			(at 5.08 63.5 270)
			(size 1.6256 1.6256)
			(drill 1.1176)
			(layers "*.Cu" "*.Mask")
			(remove_unused_layers no)
			(net "P12V_STBY")
			(clearance 0)
		)
		(pad "40" thru_hole circle
			(at 5.08 60.96 270)
			(size 1.6256 1.6256)
			(drill 1.1176)
			(layers "*.Cu" "*.Mask")
			(remove_unused_layers no)
			(net "PSU4_REMOTE_P")
			(clearance 0)
		)
		(pad "41" thru_hole circle
			(at 5.08 58.42 270)
			(size 1.6256 1.6256)
			(drill 1.1176)
			(layers "*.Cu" "*.Mask")
			(remove_unused_layers no)
			(net "GND")
			(clearance 0)
		)
		(pad "42" thru_hole circle
			(at 5.08 55.88 270)
			(size 1.6256 1.6256)
			(drill 1.1176)
			(layers "*.Cu" "*.Mask")
			(remove_unused_layers no)
			(net "GND")
			(clearance 0)
		)
		(pad "43" thru_hole circle
			(at 5.08 53.34 270)
			(size 1.6256 1.6256)
			(drill 1.1176)
			(layers "*.Cu" "*.Mask")
			(remove_unused_layers no)
			(net "GND")
			(clearance 0)
		)
		(pad "44" thru_hole circle
			(at 5.08 50.8 270)
			(size 1.6256 1.6256)
			(drill 1.1176)
			(layers "*.Cu" "*.Mask")
			(remove_unused_layers no)
			(net "GND")
			(clearance 0)
		)
		(pad "45" thru_hole circle
			(at 5.08 48.26 270)
			(size 1.6256 1.6256)
			(drill 1.1176)
			(layers "*.Cu" "*.Mask")
			(remove_unused_layers no)
			(net "GND")
			(clearance 0)
		)
		(pad "46" thru_hole circle
			(at 5.08 45.72 270)
			(size 1.6256 1.6256)
			(drill 1.1176)
			(layers "*.Cu" "*.Mask")
			(remove_unused_layers no)
			(net "GND")
			(clearance 0)
		)
		(pad "47" thru_hole circle
			(at 5.08 43.18 270)
			(size 1.6256 1.6256)
			(drill 1.1176)
			(layers "*.Cu" "*.Mask")
			(remove_unused_layers no)
			(net "GND")
			(clearance 0)
		)
		(pad "48" thru_hole circle
			(at 5.08 40.64 270)
			(size 1.6256 1.6256)
			(drill 1.1176)
			(layers "*.Cu" "*.Mask")
			(remove_unused_layers no)
			(net "GND")
			(clearance 0)
		)
		(pad "49" thru_hole circle
			(at 5.08 38.1 270)
			(size 1.6256 1.6256)
			(drill 1.1176)
			(layers "*.Cu" "*.Mask")
			(remove_unused_layers no)
			(net "GND")
			(clearance 0)
		)
		(pad "50" thru_hole circle
			(at 5.08 35.56 270)
			(size 1.6256 1.6256)
			(drill 1.1176)
			(layers "*.Cu" "*.Mask")
			(remove_unused_layers no)
			(net "GND")
			(clearance 0)
		)
		(pad "51" thru_hole circle
			(at 5.08 33.02 270)
			(size 1.6256 1.6256)
			(drill 1.1176)
			(layers "*.Cu" "*.Mask")
			(remove_unused_layers no)
			(net "GND")
			(clearance 0)
		)
		(pad "52" thru_hole circle
			(at 5.08 30.48 270)
			(size 1.6256 1.6256)
			(drill 1.1176)
			(layers "*.Cu" "*.Mask")
			(remove_unused_layers no)
			(net "GND")
			(clearance 0)
		)
		(pad "53" thru_hole circle
			(at 5.08 27.94 270)
			(size 1.6256 1.6256)
			(drill 1.1176)
			(layers "*.Cu" "*.Mask")
			(remove_unused_layers no)
			(net "P12V")
			(clearance 0)
		)
		(pad "54" thru_hole circle
			(at 5.08 25.4 270)
			(size 1.6256 1.6256)
			(drill 1.1176)
			(layers "*.Cu" "*.Mask")
			(remove_unused_layers no)
			(net "P12V")
			(clearance 0)
		)
		(pad "55" thru_hole circle
			(at 5.08 22.86 270)
			(size 1.6256 1.6256)
			(drill 1.1176)
			(layers "*.Cu" "*.Mask")
			(remove_unused_layers no)
			(net "P12V")
			(clearance 0)
		)
		(pad "56" thru_hole circle
			(at 5.08 20.32 270)
			(size 1.6256 1.6256)
			(drill 1.1176)
			(layers "*.Cu" "*.Mask")
			(remove_unused_layers no)
			(net "P12V")
			(clearance 0)
		)
		(pad "57" thru_hole circle
			(at 5.08 17.78 270)
			(size 1.6256 1.6256)
			(drill 1.1176)
			(layers "*.Cu" "*.Mask")
			(remove_unused_layers no)
			(net "P12V")
			(clearance 0)
		)
		(pad "58" thru_hole circle
			(at 5.08 15.24 270)
			(size 1.6256 1.6256)
			(drill 1.1176)
			(layers "*.Cu" "*.Mask")
			(remove_unused_layers no)
			(net "P12V")
			(clearance 0)
		)
		(pad "59" thru_hole circle
			(at 5.08 12.7 270)
			(size 1.6256 1.6256)
			(drill 1.1176)
			(layers "*.Cu" "*.Mask")
			(remove_unused_layers no)
			(net "P12V")
			(clearance 0)
		)
		(pad "60" thru_hole circle
			(at 5.08 10.16 270)
			(size 1.6256 1.6256)
			(drill 1.1176)
			(layers "*.Cu" "*.Mask")
			(remove_unused_layers no)
			(net "P12V")
			(clearance 0)
		)
		(pad "61" thru_hole circle
			(at 5.08 7.62 270)
			(size 1.6256 1.6256)
			(drill 1.1176)
			(layers "*.Cu" "*.Mask")
			(remove_unused_layers no)
			(net "P12V")
			(clearance 0)
		)
		(pad "62" thru_hole circle
			(at 5.08 5.08 270)
			(size 1.6256 1.6256)
			(drill 1.1176)
			(layers "*.Cu" "*.Mask")
			(remove_unused_layers no)
			(net "P12V")
			(clearance 0)
		)
		(pad "63" thru_hole circle
			(at 5.08 2.54 270)
			(size 1.6256 1.6256)
			(drill 1.1176)
			(layers "*.Cu" "*.Mask")
			(remove_unused_layers no)
			(net "P12V")
			(clearance 0)
		)
		(pad "64" thru_hole circle
			(at 5.08 0 270)
			(size 1.6256 1.6256)
			(drill 1.1176)
			(layers "*.Cu" "*.Mask")
			(remove_unused_layers no)
			(net "P12V")
			(clearance 0)
		)
	)
	(footprint ""
		(layer "F.Cu")
		(at 26.928318 -196.6214)
		(property "Reference" "R6"
			(at -3.177032 0.103886 0)
			(unlocked yes)
			(layer "F.SilkS")
			(effects
				(font
					(size 0.7874 0.5842)
					(thickness 0.1524)
				)
				(justify left)
			)
		)
		(property "Value" ""
			(at 0 0 0)
			(layer "F.Fab")
			(effects
				(font
					(size 1.27 1.27)
				)
			)
		)
		(duplicate_pad_numbers_are_jumpers no)
		(fp_line
			(start -0.7874 -0.4064)
			(end 0.7874 -0.4064)
			(stroke
				(width 0.1524)
				(type default)
			)
			(layer "F.SilkS")
		)
		(fp_line
			(start -0.7874 0.4064)
			(end -0.7874 -0.4064)
			(stroke
				(width 0.1524)
				(type default)
			)
			(layer "F.SilkS")
		)
		(fp_line
			(start 0.7874 -0.4064)
			(end 0.7874 0.4064)
			(stroke
				(width 0.1524)
				(type default)
			)
			(layer "F.SilkS")
		)
		(fp_line
			(start 0.7874 0.4064)
			(end -0.7874 0.4064)
			(stroke
				(width 0.1524)
				(type default)
			)
			(layer "F.SilkS")
		)
		(fp_poly
			(pts
				(xy -0.508 0.2794) (xy -0.508 0.2286) (xy -0.635 0.2286) (xy -0.635 -0.254) (xy -0.5334 -0.254)
				(xy -0.5334 -0.2794) (xy 0.5334 -0.2794) (xy 0.5334 -0.254) (xy 0.635 -0.254) (xy 0.635 0.254) (xy 0.5334 0.254)
				(xy 0.5334 0.2794)
			)
			(stroke
				(width 0)
				(type default)
			)
			(fill no)
			(layer "F.CrtYd")
		)
		(pad "1" smd rect
			(at 0.40005 0)
			(size 0.4572 0.508)
			(layers "F.Cu" "F.Mask" "F.Paste")
			(net "PSU3_REMOTE_N")
		)
		(pad "2" smd rect
			(at -0.40005 0)
			(size 0.4572 0.508)
			(layers "F.Cu" "F.Mask" "F.Paste")
			(net "GND")
		)
	)
	(footprint ""
		(layer "F.Cu")
		(at 25.857708 -364.246414)
		(property "Reference" "R78"
			(at -3.917442 -0.225298 0)
			(unlocked yes)
			(layer "F.SilkS")
			(effects
				(font
					(size 0.7874 0.5842)
					(thickness 0.1524)
				)
				(justify left)
			)
		)
		(property "Value" ""
			(at 0 0 0)
			(layer "F.Fab")
			(effects
				(font
					(size 1.27 1.27)
				)
			)
		)
		(duplicate_pad_numbers_are_jumpers no)
		(fp_line
			(start -0.7874 -0.4064)
			(end 0.7874 -0.4064)
			(stroke
				(width 0.1524)
				(type default)
			)
			(layer "F.SilkS")
		)
		(fp_line
			(start -0.7874 0.4064)
			(end -0.7874 -0.4064)
			(stroke
				(width 0.1524)
				(type default)
			)
			(layer "F.SilkS")
		)
		(fp_line
			(start 0.7874 -0.4064)
			(end 0.7874 0.4064)
			(stroke
				(width 0.1524)
				(type default)
			)
			(layer "F.SilkS")
		)
		(fp_line
			(start 0.7874 0.4064)
			(end -0.7874 0.4064)
			(stroke
				(width 0.1524)
				(type default)
			)
			(layer "F.SilkS")
		)
		(fp_poly
			(pts
				(xy -0.508 0.2794) (xy -0.508 0.2286) (xy -0.635 0.2286) (xy -0.635 -0.254) (xy -0.5334 -0.254)
				(xy -0.5334 -0.2794) (xy 0.5334 -0.2794) (xy 0.5334 -0.254) (xy 0.635 -0.254) (xy 0.635 0.254) (xy 0.5334 0.254)
				(xy 0.5334 0.2794)
			)
			(stroke
				(width 0)
				(type default)
			)
			(fill no)
			(layer "F.CrtYd")
		)
		(pad "1" smd rect
			(at 0.40005 0)
			(size 0.4572 0.508)
			(layers "F.Cu" "F.Mask" "F.Paste")
			(net "PSU5_PS_KILL")
		)
		(pad "2" smd rect
			(at -0.40005 0)
			(size 0.4572 0.508)
			(layers "F.Cu" "F.Mask" "F.Paste")
			(net "P12V_STBY")
		)
	)
	(footprint ""
		(layer "F.Cu")
		(at 5.780024 -497.999766)
		(property "Reference" "J31"
			(at -1.9304 -3.978148 0)
			(unlocked yes)
			(layer "F.SilkS")
			(effects
				(font
					(size 0.7874 0.5842)
					(thickness 0.1524)
				)
				(justify left)
			)
		)
		(property "Value" ""
			(at 0 0 0)
			(layer "F.Fab")
			(effects
				(font
					(size 1.27 1.27)
				)
			)
		)
		(duplicate_pad_numbers_are_jumpers no)
		(fp_line
			(start -3.10007 0.199898)
			(end -3.10007 2.800096)
			(stroke
				(width 0.1524)
				(type default)
			)
			(layer "F.SilkS")
		)
		(fp_line
			(start -3.10007 2.800096)
			(end -1.89992 2.800096)
			(stroke
				(width 0.1524)
				(type default)
			)
			(layer "F.SilkS")
		)
		(fp_line
			(start -1.89992 -3.325114)
			(end -1.89992 0.199898)
			(stroke
				(width 0.1524)
				(type default)
			)
			(layer "F.SilkS")
		)
		(fp_line
			(start -1.89992 0.199898)
			(end -3.10007 0.199898)
			(stroke
				(width 0.1524)
				(type default)
			)
			(layer "F.SilkS")
		)
		(fp_line
			(start -1.89992 2.800096)
			(end -1.89992 6.325108)
			(stroke
				(width 0.1524)
				(type default)
			)
			(layer "F.SilkS")
		)
		(fp_line
			(start -1.89992 6.325108)
			(end 1.016 6.325108)
			(stroke
				(width 0.1524)
				(type default)
			)
			(layer "F.SilkS")
		)
		(fp_line
			(start 1.016 -3.325114)
			(end -1.89992 -3.325114)
			(stroke
				(width 0.1524)
				(type default)
			)
			(layer "F.SilkS")
		)
		(fp_line
			(start 2.469896 5.133594)
			(end 2.469896 -2.130806)
			(stroke
				(width 0.1524)
				(type default)
			)
			(layer "F.SilkS")
		)
		(fp_poly
			(pts
				(xy 0.8509 0.8509) (xy -0.8509 0.8509) (xy -0.8509 -0.8509) (xy 0.8509 -0.8509)
			)
			(stroke
				(width 0)
				(type default)
			)
			(fill no)
			(layer "B.CrtYd")
		)
		(fp_poly
			(pts
				(arc
					(start 0.8509 2.999994)
					(mid -0.8509 2.999994)
					(end 0.8509 2.999994)
				)
			)
			(stroke
				(width 0)
				(type default)
			)
			(fill no)
			(layer "B.CrtYd")
		)
		(fp_poly
			(pts
				(arc
					(start 2.874518 -2.999994)
					(mid 1.045718 -2.999994)
					(end 2.874518 -2.999994)
				)
			)
			(stroke
				(width 0)
				(type default)
			)
			(fill no)
			(layer "B.CrtYd")
		)
		(fp_poly
			(pts
				(arc
					(start 2.874518 5.999988)
					(mid 1.045718 5.999988)
					(end 2.874518 5.999988)
				)
			)
			(stroke
				(width 0)
				(type default)
			)
			(fill no)
			(layer "B.CrtYd")
		)
		(fp_poly
			(pts
				(xy 2.469896 5.233924) (xy 2.469896 -2.233676) (xy 2.8956 -2.233676) (xy 2.8956 -3.935476) (xy 1.0922 -3.935476)
				(xy 1.0922 -3.325114) (xy -1.89992 -3.325114) (xy -1.89992 0.199898) (xy -3.10007 0.199898) (xy -3.10007 2.800096)
				(xy -1.89992 2.800096) (xy -1.89992 6.325108) (xy 1.0922 6.325108) (xy 1.0922 6.935724) (xy 2.8956 6.935724)
				(xy 2.8956 5.233924)
			)
			(stroke
				(width 0)
				(type default)
			)
			(fill no)
			(layer "F.CrtYd")
		)
		(fp_line
			(start -3.10007 0.199898)
			(end -3.10007 2.800096)
			(stroke
				(width 0.1)
				(type default)
			)
			(layer "F.Fab")
		)
		(fp_line
			(start -3.10007 2.800096)
			(end -1.89992 2.800096)
			(stroke
				(width 0.1)
				(type default)
			)
			(layer "F.Fab")
		)
		(fp_line
			(start -1.89992 -3.325114)
			(end -1.89992 0.199898)
			(stroke
				(width 0.1)
				(type default)
			)
			(layer "F.Fab")
		)
		(fp_line
			(start -1.89992 0.199898)
			(end -3.10007 0.199898)
			(stroke
				(width 0.1)
				(type default)
			)
			(layer "F.Fab")
		)
		(fp_line
			(start -1.89992 2.800096)
			(end -1.89992 6.325108)
			(stroke
				(width 0.1)
				(type default)
			)
			(layer "F.Fab")
		)
		(fp_line
			(start -1.89992 6.325108)
			(end 2.469896 6.325108)
			(stroke
				(width 0.1)
				(type default)
			)
			(layer "F.Fab")
		)
		(fp_line
			(start 2.469896 -3.325114)
			(end -1.89992 -3.325114)
			(stroke
				(width 0.1)
				(type default)
			)
			(layer "F.Fab")
		)
		(fp_line
			(start 2.469896 6.325108)
			(end 2.469896 -3.325114)
			(stroke
				(width 0.1)
				(type default)
			)
			(layer "F.Fab")
		)
		(pad "" np_thru_hole circle
			(at 1.960118 -2.999994 90)
			(size 1.3208 1.3208)
			(drill 1.3208)
			(layers "*.Cu" "*.Mask")
			(clearance 0.381)
			(thermal_gap 0.381)
		)
		(pad "" np_thru_hole circle
			(at 1.960118 5.999988 90)
			(size 1.3208 1.3208)
			(drill 1.3208)
			(layers "*.Cu" "*.Mask")
			(clearance 0.381)
			(thermal_gap 0.381)
		)
		(pad "1" thru_hole rect
			(at 0 0 90)
			(size 1.6002 1.6002)
			(drill 1.0922)
			(layers "*.Cu" "*.Mask")
			(remove_unused_layers no)
			(net "POWER_SW2_PWR_CTR_12V")
			(clearance 0)
			(padstack
				(mode front_inner_back)
				(layer "Inner"
					(shape circle)
					(size 1.6002 1.6002)
					(clearance 0)
				)
				(layer "B.Cu"
					(shape rect)
					(size 1.6002 1.6002)
					(clearance 0)
				)
			)
		)
		(pad "2" thru_hole circle
			(at 0 2.999994 90)
			(size 1.6002 1.6002)
			(drill 1.0922)
			(layers "*.Cu" "*.Mask")
			(remove_unused_layers no)
			(net "GND")
			(clearance 0)
		)
		(zone
			(layers "F.Cu" "B.Cu" "In1.Cu" "In2.Cu" "In3.Cu" "In4.Cu" "In5.Cu" "In6.Cu")
			(hatch none 0.5)
			(connect_pads
				(clearance 0)
			)
			(min_thickness 0.25)
			(keepout
				(tracks not_allowed)
				(vias allowed)
				(pads allowed)
				(copperpour not_allowed)
				(footprints allowed)
			)
			(placement
				(enabled no)
				(sheetname "")
			)
			(fill
				(thermal_gap 0.5)
				(thermal_bridge_width 0.5)
				(island_removal_mode 0)
			)
			(polygon
				(pts
					(arc
						(start 8.806942 -500.99976)
						(mid 6.673342 -500.99976)
						(end 8.806942 -500.99976)
					)
				)
			)
		)
		(zone
			(layers "F.Cu" "B.Cu" "In1.Cu" "In2.Cu" "In3.Cu" "In4.Cu" "In5.Cu" "In6.Cu")
			(hatch none 0.5)
			(connect_pads
				(clearance 0)
			)
			(min_thickness 0.25)
			(keepout
				(tracks not_allowed)
				(vias allowed)
				(pads allowed)
				(copperpour not_allowed)
				(footprints allowed)
			)
			(placement
				(enabled no)
				(sheetname "")
			)
			(fill
				(thermal_gap 0.5)
				(thermal_bridge_width 0.5)
				(island_removal_mode 0)
			)
			(polygon
				(pts
					(arc
						(start 8.806942 -491.999778)
						(mid 6.673342 -491.999778)
						(end 8.806942 -491.999778)
					)
				)
			)
		)
	)
	(footprint ""
		(layer "F.Cu")
		(at 70.308978 -304.009806 90)
		(property "Reference" "C53"
			(at 1.017524 0.29464 90)
			(unlocked yes)
			(layer "F.SilkS")
			(effects
				(font
					(size 0.7874 0.5842)
					(thickness 0.1524)
				)
				(justify left)
			)
		)
		(property "Value" ""
			(at 0 0 90)
			(layer "F.Fab")
			(effects
				(font
					(size 1.27 1.27)
				)
			)
		)
		(duplicate_pad_numbers_are_jumpers no)
		(fp_line
			(start 0.7874 -0.4064)
			(end 0.7874 0.4064)
			(stroke
				(width 0.1524)
				(type default)
			)
			(layer "F.SilkS")
		)
		(fp_line
			(start -0.7874 -0.4064)
			(end 0.7874 -0.4064)
			(stroke
				(width 0.1524)
				(type default)
			)
			(layer "F.SilkS")
		)
		(fp_line
			(start 0 0.381)
			(end 0 -0.381)
			(stroke
				(width 0.1524)
				(type default)
			)
			(layer "F.SilkS")
		)
		(fp_line
			(start 0.7874 0.4064)
			(end -0.7874 0.4064)
			(stroke
				(width 0.1524)
				(type default)
			)
			(layer "F.SilkS")
		)
		(fp_line
			(start -0.7874 0.4064)
			(end -0.7874 -0.4064)
			(stroke
				(width 0.1524)
				(type default)
			)
			(layer "F.SilkS")
		)
		(fp_poly
			(pts
				(xy -0.5334 0.254) (xy -0.635 0.254) (xy -0.635 0.2286) (xy -0.635 -0.254) (xy -0.5334 -0.254) (xy -0.5334 -0.2794)
				(xy 0.5334 -0.2794) (xy 0.5334 -0.254) (xy 0.635 -0.254) (xy 0.635 0.254) (xy 0.5334 0.254) (xy 0.5334 0.2794)
				(xy -0.508 0.2794) (xy -0.5334 0.2794)
			)
			(stroke
				(width 0)
				(type default)
			)
			(fill no)
			(layer "F.CrtYd")
		)
		(pad "1" smd rect
			(at 0.40005 0 90)
			(size 0.4572 0.508)
			(layers "F.Cu" "F.Mask" "F.Paste")
			(net "P12V")
		)
		(pad "2" smd rect
			(at -0.40005 0 90)
			(size 0.4572 0.508)
			(layers "F.Cu" "F.Mask" "F.Paste")
			(net "GND")
		)
	)
	(footprint ""
		(layer "F.Cu")
		(at 26.102056 -274.774914)
		(property "Reference" "R74"
			(at -4.037838 -0.005334 0)
			(unlocked yes)
			(layer "F.SilkS")
			(effects
				(font
					(size 0.7874 0.5842)
					(thickness 0.1524)
				)
				(justify left)
			)
		)
		(property "Value" ""
			(at 0 0 0)
			(layer "F.Fab")
			(effects
				(font
					(size 1.27 1.27)
				)
			)
		)
		(duplicate_pad_numbers_are_jumpers no)
		(fp_line
			(start -0.7874 -0.4064)
			(end 0.7874 -0.4064)
			(stroke
				(width 0.1524)
				(type default)
			)
			(layer "F.SilkS")
		)
		(fp_line
			(start -0.7874 0.4064)
			(end -0.7874 -0.4064)
			(stroke
				(width 0.1524)
				(type default)
			)
			(layer "F.SilkS")
		)
		(fp_line
			(start 0.7874 -0.4064)
			(end 0.7874 0.4064)
			(stroke
				(width 0.1524)
				(type default)
			)
			(layer "F.SilkS")
		)
		(fp_line
			(start 0.7874 0.4064)
			(end -0.7874 0.4064)
			(stroke
				(width 0.1524)
				(type default)
			)
			(layer "F.SilkS")
		)
		(fp_poly
			(pts
				(xy -0.508 0.2794) (xy -0.508 0.2286) (xy -0.635 0.2286) (xy -0.635 -0.254) (xy -0.5334 -0.254)
				(xy -0.5334 -0.2794) (xy 0.5334 -0.2794) (xy 0.5334 -0.254) (xy 0.635 -0.254) (xy 0.635 0.254) (xy 0.5334 0.254)
				(xy 0.5334 0.2794)
			)
			(stroke
				(width 0)
				(type default)
			)
			(fill no)
			(layer "F.CrtYd")
		)
		(pad "1" smd rect
			(at 0.40005 0)
			(size 0.4572 0.508)
			(layers "F.Cu" "F.Mask" "F.Paste")
			(net "PSU4_PS_KILL")
		)
		(pad "2" smd rect
			(at -0.40005 0)
			(size 0.4572 0.508)
			(layers "F.Cu" "F.Mask" "F.Paste")
			(net "P12V_STBY")
		)
	)
	(footprint ""
		(layer "F.Cu")
		(at 26.850848 -19.859244)
		(property "Reference" "R5"
			(at -2.617978 0.04699 0)
			(unlocked yes)
			(layer "F.SilkS")
			(effects
				(font
					(size 0.7874 0.5842)
					(thickness 0.1524)
				)
				(justify left)
			)
		)
		(property "Value" ""
			(at 0 0 0)
			(layer "F.Fab")
			(effects
				(font
					(size 1.27 1.27)
				)
			)
		)
		(duplicate_pad_numbers_are_jumpers no)
		(fp_line
			(start -0.7874 -0.4064)
			(end 0.7874 -0.4064)
			(stroke
				(width 0.1524)
				(type default)
			)
			(layer "F.SilkS")
		)
		(fp_line
			(start -0.7874 0.4064)
			(end -0.7874 -0.4064)
			(stroke
				(width 0.1524)
				(type default)
			)
			(layer "F.SilkS")
		)
		(fp_line
			(start 0.7874 -0.4064)
			(end 0.7874 0.4064)
			(stroke
				(width 0.1524)
				(type default)
			)
			(layer "F.SilkS")
		)
		(fp_line
			(start 0.7874 0.4064)
			(end -0.7874 0.4064)
			(stroke
				(width 0.1524)
				(type default)
			)
			(layer "F.SilkS")
		)
		(fp_poly
			(pts
				(xy -0.508 0.2794) (xy -0.508 0.2286) (xy -0.635 0.2286) (xy -0.635 -0.254) (xy -0.5334 -0.254)
				(xy -0.5334 -0.2794) (xy 0.5334 -0.2794) (xy 0.5334 -0.254) (xy 0.635 -0.254) (xy 0.635 0.254) (xy 0.5334 0.254)
				(xy 0.5334 0.2794)
			)
			(stroke
				(width 0)
				(type default)
			)
			(fill no)
			(layer "F.CrtYd")
		)
		(pad "1" smd rect
			(at 0.40005 0)
			(size 0.4572 0.508)
			(layers "F.Cu" "F.Mask" "F.Paste")
			(net "PSU1_REMOTE_N")
		)
		(pad "2" smd rect
			(at -0.40005 0)
			(size 0.4572 0.508)
			(layers "F.Cu" "F.Mask" "F.Paste")
			(net "GND")
		)
	)
	(footprint ""
		(layer "F.Cu")
		(at 73.63333 -83.335368 90)
		(property "Reference" "C19"
			(at 1.06553 0.092202 90)
			(unlocked yes)
			(layer "F.SilkS")
			(effects
				(font
					(size 0.7874 0.5842)
					(thickness 0.1524)
				)
				(justify left)
			)
		)
		(property "Value" ""
			(at 0 0 90)
			(layer "F.Fab")
			(effects
				(font
					(size 1.27 1.27)
				)
			)
		)
		(duplicate_pad_numbers_are_jumpers no)
		(fp_line
			(start 0.7874 -0.4064)
			(end 0.7874 0.4064)
			(stroke
				(width 0.1524)
				(type default)
			)
			(layer "F.SilkS")
		)
		(fp_line
			(start -0.7874 -0.4064)
			(end 0.7874 -0.4064)
			(stroke
				(width 0.1524)
				(type default)
			)
			(layer "F.SilkS")
		)
		(fp_line
			(start 0 0.381)
			(end 0 -0.381)
			(stroke
				(width 0.1524)
				(type default)
			)
			(layer "F.SilkS")
		)
		(fp_line
			(start 0.7874 0.4064)
			(end -0.7874 0.4064)
			(stroke
				(width 0.1524)
				(type default)
			)
			(layer "F.SilkS")
		)
		(fp_line
			(start -0.7874 0.4064)
			(end -0.7874 -0.4064)
			(stroke
				(width 0.1524)
				(type default)
			)
			(layer "F.SilkS")
		)
		(fp_poly
			(pts
				(xy -0.5334 0.254) (xy -0.635 0.254) (xy -0.635 0.2286) (xy -0.635 -0.254) (xy -0.5334 -0.254) (xy -0.5334 -0.2794)
				(xy 0.5334 -0.2794) (xy 0.5334 -0.254) (xy 0.635 -0.254) (xy 0.635 0.254) (xy 0.5334 0.254) (xy 0.5334 0.2794)
				(xy -0.508 0.2794) (xy -0.5334 0.2794)
			)
			(stroke
				(width 0)
				(type default)
			)
			(fill no)
			(layer "F.CrtYd")
		)
		(pad "1" smd rect
			(at 0.40005 0 90)
			(size 0.4572 0.508)
			(layers "F.Cu" "F.Mask" "F.Paste")
			(net "P12V")
		)
		(pad "2" smd rect
			(at -0.40005 0 90)
			(size 0.4572 0.508)
			(layers "F.Cu" "F.Mask" "F.Paste")
			(net "GND")
		)
	)
	(footprint ""
		(layer "F.Cu")
		(at 39.94531 -459.16596 180)
		(property "Reference" "R26"
			(at -1.790446 -0.167386 0)
			(unlocked yes)
			(layer "F.SilkS")
			(effects
				(font
					(size 0.7874 0.5842)
					(thickness 0.1524)
				)
				(justify left)
			)
		)
		(property "Value" ""
			(at 0 0 180)
			(layer "F.Fab")
			(effects
				(font
					(size 1.27 1.27)
				)
			)
		)
		(duplicate_pad_numbers_are_jumpers no)
		(fp_line
			(start 0.7874 0.4064)
			(end -0.7874 0.4064)
			(stroke
				(width 0.1524)
				(type default)
			)
			(layer "F.SilkS")
		)
		(fp_line
			(start 0.7874 -0.4064)
			(end 0.7874 0.4064)
			(stroke
				(width 0.1524)
				(type default)
			)
			(layer "F.SilkS")
		)
		(fp_line
			(start -0.7874 0.4064)
			(end -0.7874 -0.4064)
			(stroke
				(width 0.1524)
				(type default)
			)
			(layer "F.SilkS")
		)
		(fp_line
			(start -0.7874 -0.4064)
			(end 0.7874 -0.4064)
			(stroke
				(width 0.1524)
				(type default)
			)
			(layer "F.SilkS")
		)
		(fp_poly
			(pts
				(xy -0.508 0.2794) (xy -0.508 0.2286) (xy -0.635 0.2286) (xy -0.635 -0.254) (xy -0.5334 -0.254)
				(xy -0.5334 -0.2794) (xy 0.5334 -0.2794) (xy 0.5334 -0.254) (xy 0.635 -0.254) (xy 0.635 0.254) (xy 0.5334 0.254)
				(xy 0.5334 0.2794)
			)
			(stroke
				(width 0)
				(type default)
			)
			(fill no)
			(layer "F.CrtYd")
		)
		(pad "1" smd rect
			(at 0.40005 0 180)
			(size 0.4572 0.508)
			(layers "F.Cu" "F.Mask" "F.Paste")
			(net "PSU6_RETURN")
		)
		(pad "2" smd rect
			(at -0.40005 0 180)
			(size 0.4572 0.508)
			(layers "F.Cu" "F.Mask" "F.Paste")
			(net "GND")
		)
	)
	(footprint ""
		(layer "F.Cu")
		(at 50.150268 -350.765364 180)
		(property "Reference" "CE16"
			(at -4.708906 1.983994 0)
			(unlocked yes)
			(layer "F.SilkS")
			(effects
				(font
					(size 0.7874 0.5842)
					(thickness 0.1524)
				)
				(justify left)
			)
		)
		(property "Value" ""
			(at 0 0 180)
			(layer "F.Fab")
			(effects
				(font
					(size 1.27 1.27)
				)
			)
		)
		(duplicate_pad_numbers_are_jumpers no)
		(fp_line
			(start 0 -4.2672)
			(end 0 4.2672)
			(stroke
				(width 0.1524)
				(type default)
			)
			(layer "F.SilkS")
		)
		(fp_circle
			(center 0 0)
			(end -4.2672 0)
			(stroke
				(width 0.1524)
				(type default)
			)
			(fill no)
			(layer "F.SilkS")
		)
		(fp_poly
			(pts
				(arc
					(start 0 -4.2672)
					(mid 4.2672 0)
					(end 0 4.2672)
				)
			)
			(stroke
				(width 0)
				(type default)
			)
			(fill yes)
			(layer "F.SilkS")
		)
		(fp_poly
			(pts
				(xy -2.5146 -0.762) (xy -0.9906 -0.762) (xy -0.9906 0.762) (xy -2.5146 0.762)
			)
			(stroke
				(width 0)
				(type default)
			)
			(fill no)
			(layer "B.CrtYd")
		)
		(fp_poly
			(pts
				(arc
					(start 1.7526 0.762)
					(mid 2.291415 -0.538815)
					(end 0.9906 0)
				)
				(arc
					(start 0.9906 0.0254)
					(mid 1.206345 0.546255)
					(end 1.7272 0.762)
				)
			)
			(stroke
				(width 0)
				(type default)
			)
			(fill no)
			(layer "B.CrtYd")
		)
		(fp_poly
			(pts
				(arc
					(start -4.2672 0)
					(mid 4.2672 0)
					(end -4.2672 0)
				)
			)
			(stroke
				(width 0)
				(type default)
			)
			(fill no)
			(layer "F.CrtYd")
		)
		(fp_circle
			(center 0 0)
			(end -4.2672 0)
			(stroke
				(width 0.1)
				(type default)
			)
			(fill no)
			(layer "F.Fab")
		)
		(fp_text user "+"
			(at -5.759196 -0.592582 180)
			(unlocked yes)
			(layer "F.SilkS")
			(effects
				(font
					(size 1.905 1.4224)
					(thickness 0.1524)
				)
				(justify left)
			)
		)
		(fp_text user "+"
			(at -5.6642 -0.34925 180)
			(unlocked yes)
			(layer "F.Fab")
			(effects
				(font
					(size 1.905 1.4224)
					(thickness 0.000001)
				)
				(justify left)
			)
		)
		(pad "1" thru_hole rect
			(at -1.75006 0 180)
			(size 1.397 1.397)
			(drill 0.9144)
			(layers "*.Cu" "*.Mask")
			(remove_unused_layers no)
			(net "P12V")
			(clearance 0.0127)
			(thermal_gap 0.0127)
			(padstack
				(mode front_inner_back)
				(layer "Inner"
					(shape circle)
					(size 1.397 1.397)
					(clearance 0.0127)
				)
				(layer "B.Cu"
					(shape rect)
					(size 1.397 1.397)
					(clearance 0.0127)
				)
			)
		)
		(pad "2" thru_hole circle
			(at 1.75006 0 180)
			(size 1.397 1.397)
			(drill 0.9144)
			(layers "*.Cu" "*.Mask")
			(remove_unused_layers no)
			(net "GND")
			(clearance 0.0127)
			(thermal_gap 0.0127)
		)
	)
	(footprint ""
		(layer "F.Cu")
		(at 26.068274 -184.266078)
		(property "Reference" "R72"
			(at -3.997198 0.128524 0)
			(unlocked yes)
			(layer "F.SilkS")
			(effects
				(font
					(size 0.7874 0.5842)
					(thickness 0.1524)
				)
				(justify left)
			)
		)
		(property "Value" ""
			(at 0 0 0)
			(layer "F.Fab")
			(effects
				(font
					(size 1.27 1.27)
				)
			)
		)
		(duplicate_pad_numbers_are_jumpers no)
		(fp_line
			(start -0.7874 -0.4064)
			(end 0.7874 -0.4064)
			(stroke
				(width 0.1524)
				(type default)
			)
			(layer "F.SilkS")
		)
		(fp_line
			(start -0.7874 0.4064)
			(end -0.7874 -0.4064)
			(stroke
				(width 0.1524)
				(type default)
			)
			(layer "F.SilkS")
		)
		(fp_line
			(start 0.7874 -0.4064)
			(end 0.7874 0.4064)
			(stroke
				(width 0.1524)
				(type default)
			)
			(layer "F.SilkS")
		)
		(fp_line
			(start 0.7874 0.4064)
			(end -0.7874 0.4064)
			(stroke
				(width 0.1524)
				(type default)
			)
			(layer "F.SilkS")
		)
		(fp_poly
			(pts
				(xy -0.508 0.2794) (xy -0.508 0.2286) (xy -0.635 0.2286) (xy -0.635 -0.254) (xy -0.5334 -0.254)
				(xy -0.5334 -0.2794) (xy 0.5334 -0.2794) (xy 0.5334 -0.254) (xy 0.635 -0.254) (xy 0.635 0.254) (xy 0.5334 0.254)
				(xy 0.5334 0.2794)
			)
			(stroke
				(width 0)
				(type default)
			)
			(fill no)
			(layer "F.CrtYd")
		)
		(pad "1" smd rect
			(at 0.40005 0)
			(size 0.4572 0.508)
			(layers "F.Cu" "F.Mask" "F.Paste")
			(net "PSU3_RESET")
		)
		(pad "2" smd rect
			(at -0.40005 0)
			(size 0.4572 0.508)
			(layers "F.Cu" "F.Mask" "F.Paste")
			(net "P12V_STBY")
		)
	)
	(footprint ""
		(layer "F.Cu")
		(at 50.478944 -329.972416 180)
		(property "Reference" "CE15"
			(at 1.661922 5.89026 0)
			(unlocked yes)
			(layer "F.SilkS")
			(effects
				(font
					(size 0.7874 0.5842)
					(thickness 0.1524)
				)
				(justify left)
			)
		)
		(property "Value" ""
			(at 0 0 180)
			(layer "F.Fab")
			(effects
				(font
					(size 1.27 1.27)
				)
			)
		)
		(duplicate_pad_numbers_are_jumpers no)
		(fp_line
			(start 0 -4.2672)
			(end 0 4.2672)
			(stroke
				(width 0.1524)
				(type default)
			)
			(layer "F.SilkS")
		)
		(fp_circle
			(center 0 0)
			(end -4.2672 0)
			(stroke
				(width 0.1524)
				(type default)
			)
			(fill no)
			(layer "F.SilkS")
		)
		(fp_poly
			(pts
				(arc
					(start 0 -4.2672)
					(mid 4.2672 0)
					(end 0 4.2672)
				)
			)
			(stroke
				(width 0)
				(type default)
			)
			(fill yes)
			(layer "F.SilkS")
		)
		(fp_poly
			(pts
				(xy -2.5146 -0.762) (xy -0.9906 -0.762) (xy -0.9906 0.762) (xy -2.5146 0.762)
			)
			(stroke
				(width 0)
				(type default)
			)
			(fill no)
			(layer "B.CrtYd")
		)
		(fp_poly
			(pts
				(arc
					(start 1.7526 0.762)
					(mid 2.291415 -0.538815)
					(end 0.9906 0)
				)
				(arc
					(start 0.9906 0.0254)
					(mid 1.206345 0.546255)
					(end 1.7272 0.762)
				)
			)
			(stroke
				(width 0)
				(type default)
			)
			(fill no)
			(layer "B.CrtYd")
		)
		(fp_poly
			(pts
				(arc
					(start -4.2672 0)
					(mid 4.2672 0)
					(end -4.2672 0)
				)
			)
			(stroke
				(width 0)
				(type default)
			)
			(fill no)
			(layer "F.CrtYd")
		)
		(fp_circle
			(center 0 0)
			(end -4.2672 0)
			(stroke
				(width 0.1)
				(type default)
			)
			(fill no)
			(layer "F.Fab")
		)
		(fp_text user "+"
			(at -5.60578 -0.450596 180)
			(unlocked yes)
			(layer "F.SilkS")
			(effects
				(font
					(size 1.905 1.4224)
					(thickness 0.1524)
				)
				(justify left)
			)
		)
		(fp_text user "+"
			(at -5.6642 -0.34925 180)
			(unlocked yes)
			(layer "F.Fab")
			(effects
				(font
					(size 1.905 1.4224)
					(thickness 0.000001)
				)
				(justify left)
			)
		)
		(pad "1" thru_hole rect
			(at -1.75006 0 180)
			(size 1.397 1.397)
			(drill 0.9144)
			(layers "*.Cu" "*.Mask")
			(remove_unused_layers no)
			(net "P12V")
			(clearance 0.0127)
			(thermal_gap 0.0127)
			(padstack
				(mode front_inner_back)
				(layer "Inner"
					(shape circle)
					(size 1.397 1.397)
					(clearance 0.0127)
				)
				(layer "B.Cu"
					(shape rect)
					(size 1.397 1.397)
					(clearance 0.0127)
				)
			)
		)
		(pad "2" thru_hole circle
			(at 1.75006 0 180)
			(size 1.397 1.397)
			(drill 0.9144)
			(layers "*.Cu" "*.Mask")
			(remove_unused_layers no)
			(net "GND")
			(clearance 0.0127)
			(thermal_gap 0.0127)
		)
	)
	(footprint ""
		(layer "F.Cu")
		(at 50.32756 -285.205424 180)
		(property "Reference" "CE13"
			(at -4.667758 1.872742 0)
			(unlocked yes)
			(layer "F.SilkS")
			(effects
				(font
					(size 0.7874 0.5842)
					(thickness 0.1524)
				)
				(justify left)
			)
		)
		(property "Value" ""
			(at 0 0 180)
			(layer "F.Fab")
			(effects
				(font
					(size 1.27 1.27)
				)
			)
		)
		(duplicate_pad_numbers_are_jumpers no)
		(fp_line
			(start 0 -4.2672)
			(end 0 4.2672)
			(stroke
				(width 0.1524)
				(type default)
			)
			(layer "F.SilkS")
		)
		(fp_circle
			(center 0 0)
			(end -4.2672 0)
			(stroke
				(width 0.1524)
				(type default)
			)
			(fill no)
			(layer "F.SilkS")
		)
		(fp_poly
			(pts
				(arc
					(start 0 -4.2672)
					(mid 4.2672 0)
					(end 0 4.2672)
				)
			)
			(stroke
				(width 0)
				(type default)
			)
			(fill yes)
			(layer "F.SilkS")
		)
		(fp_poly
			(pts
				(xy -2.5146 -0.762) (xy -0.9906 -0.762) (xy -0.9906 0.762) (xy -2.5146 0.762)
			)
			(stroke
				(width 0)
				(type default)
			)
			(fill no)
			(layer "B.CrtYd")
		)
		(fp_poly
			(pts
				(arc
					(start 1.7526 0.762)
					(mid 2.291415 -0.538815)
					(end 0.9906 0)
				)
				(arc
					(start 0.9906 0.0254)
					(mid 1.206345 0.546255)
					(end 1.7272 0.762)
				)
			)
			(stroke
				(width 0)
				(type default)
			)
			(fill no)
			(layer "B.CrtYd")
		)
		(fp_poly
			(pts
				(arc
					(start -4.2672 0)
					(mid 4.2672 0)
					(end -4.2672 0)
				)
			)
			(stroke
				(width 0)
				(type default)
			)
			(fill no)
			(layer "F.CrtYd")
		)
		(fp_circle
			(center 0 0)
			(end -4.2672 0)
			(stroke
				(width 0.1)
				(type default)
			)
			(fill no)
			(layer "F.Fab")
		)
		(fp_text user "+"
			(at -5.6642 -0.34925 180)
			(unlocked yes)
			(layer "F.SilkS")
			(effects
				(font
					(size 1.905 1.4224)
					(thickness 0.1524)
				)
				(justify left)
			)
		)
		(fp_text user "+"
			(at -5.6642 -0.34925 180)
			(unlocked yes)
			(layer "F.Fab")
			(effects
				(font
					(size 1.905 1.4224)
					(thickness 0.000001)
				)
				(justify left)
			)
		)
		(pad "1" thru_hole rect
			(at -1.75006 0 180)
			(size 1.397 1.397)
			(drill 0.9144)
			(layers "*.Cu" "*.Mask")
			(remove_unused_layers no)
			(net "P12V")
			(clearance 0.0127)
			(thermal_gap 0.0127)
			(padstack
				(mode front_inner_back)
				(layer "Inner"
					(shape circle)
					(size 1.397 1.397)
					(clearance 0.0127)
				)
				(layer "B.Cu"
					(shape rect)
					(size 1.397 1.397)
					(clearance 0.0127)
				)
			)
		)
		(pad "2" thru_hole circle
			(at 1.75006 0 180)
			(size 1.397 1.397)
			(drill 0.9144)
			(layers "*.Cu" "*.Mask")
			(remove_unused_layers no)
			(net "GND")
			(clearance 0.0127)
			(thermal_gap 0.0127)
		)
	)
	(footprint ""
		(layer "F.Cu")
		(at 26.25217 -454.646538 180)
		(property "Reference" "R54"
			(at 3.629406 0.859536 0)
			(unlocked yes)
			(layer "F.SilkS")
			(effects
				(font
					(size 0.7874 0.5842)
					(thickness 0.1524)
				)
				(justify left)
			)
		)
		(property "Value" ""
			(at 0 0 180)
			(layer "F.Fab")
			(effects
				(font
					(size 1.27 1.27)
				)
			)
		)
		(duplicate_pad_numbers_are_jumpers no)
		(fp_line
			(start 0.7874 0.4064)
			(end -0.7874 0.4064)
			(stroke
				(width 0.1524)
				(type default)
			)
			(layer "F.SilkS")
		)
		(fp_line
			(start 0.7874 -0.4064)
			(end 0.7874 0.4064)
			(stroke
				(width 0.1524)
				(type default)
			)
			(layer "F.SilkS")
		)
		(fp_line
			(start -0.7874 0.4064)
			(end -0.7874 -0.4064)
			(stroke
				(width 0.1524)
				(type default)
			)
			(layer "F.SilkS")
		)
		(fp_line
			(start -0.7874 -0.4064)
			(end 0.7874 -0.4064)
			(stroke
				(width 0.1524)
				(type default)
			)
			(layer "F.SilkS")
		)
		(fp_poly
			(pts
				(xy -0.508 0.2794) (xy -0.508 0.2286) (xy -0.635 0.2286) (xy -0.635 -0.254) (xy -0.5334 -0.254)
				(xy -0.5334 -0.2794) (xy 0.5334 -0.2794) (xy 0.5334 -0.254) (xy 0.635 -0.254) (xy 0.635 0.254) (xy 0.5334 0.254)
				(xy 0.5334 0.2794)
			)
			(stroke
				(width 0)
				(type default)
			)
			(fill no)
			(layer "F.CrtYd")
		)
		(pad "1" smd rect
			(at 0.40005 0 180)
			(size 0.4572 0.508)
			(layers "F.Cu" "F.Mask" "F.Paste")
			(net "GND")
		)
		(pad "2" smd rect
			(at -0.40005 0 180)
			(size 0.4572 0.508)
			(layers "F.Cu" "F.Mask" "F.Paste")
			(net "PSU6_PS_ON_N")
		)
	)
	(footprint ""
		(layer "F.Cu")
		(at 68.727066 -350.498664 90)
		(property "Reference" "C63"
			(at 1.177036 -0.368046 90)
			(unlocked yes)
			(layer "F.SilkS")
			(effects
				(font
					(size 0.7874 0.5842)
					(thickness 0.1524)
				)
				(justify left)
			)
		)
		(property "Value" ""
			(at 0 0 90)
			(layer "F.Fab")
			(effects
				(font
					(size 1.27 1.27)
				)
			)
		)
		(duplicate_pad_numbers_are_jumpers no)
		(fp_line
			(start 0.7874 -0.4064)
			(end 0.7874 0.4064)
			(stroke
				(width 0.1524)
				(type default)
			)
			(layer "F.SilkS")
		)
		(fp_line
			(start -0.7874 -0.4064)
			(end 0.7874 -0.4064)
			(stroke
				(width 0.1524)
				(type default)
			)
			(layer "F.SilkS")
		)
		(fp_line
			(start 0 0.381)
			(end 0 -0.381)
			(stroke
				(width 0.1524)
				(type default)
			)
			(layer "F.SilkS")
		)
		(fp_line
			(start 0.7874 0.4064)
			(end -0.7874 0.4064)
			(stroke
				(width 0.1524)
				(type default)
			)
			(layer "F.SilkS")
		)
		(fp_line
			(start -0.7874 0.4064)
			(end -0.7874 -0.4064)
			(stroke
				(width 0.1524)
				(type default)
			)
			(layer "F.SilkS")
		)
		(fp_poly
			(pts
				(xy -0.5334 0.254) (xy -0.635 0.254) (xy -0.635 0.2286) (xy -0.635 -0.254) (xy -0.5334 -0.254) (xy -0.5334 -0.2794)
				(xy 0.5334 -0.2794) (xy 0.5334 -0.254) (xy 0.635 -0.254) (xy 0.635 0.254) (xy 0.5334 0.254) (xy 0.5334 0.2794)
				(xy -0.508 0.2794) (xy -0.5334 0.2794)
			)
			(stroke
				(width 0)
				(type default)
			)
			(fill no)
			(layer "F.CrtYd")
		)
		(pad "1" smd rect
			(at 0.40005 0 90)
			(size 0.4572 0.508)
			(layers "F.Cu" "F.Mask" "F.Paste")
			(net "P12V")
		)
		(pad "2" smd rect
			(at -0.40005 0 90)
			(size 0.4572 0.508)
			(layers "F.Cu" "F.Mask" "F.Paste")
			(net "GND")
		)
	)
	(footprint ""
		(layer "F.Cu")
		(at 40.959024 -105.82148 -90)
		(property "Reference" "R8"
			(at 0.823722 -2.429256 90)
			(unlocked yes)
			(layer "F.SilkS")
			(effects
				(font
					(size 0.7874 0.5842)
					(thickness 0.1524)
				)
				(justify left)
			)
		)
		(property "Value" ""
			(at 0 0 270)
			(layer "F.Fab")
			(effects
				(font
					(size 1.27 1.27)
				)
			)
		)
		(duplicate_pad_numbers_are_jumpers no)
		(fp_line
			(start -0.7874 0.4064)
			(end -0.7874 -0.4064)
			(stroke
				(width 0.1524)
				(type default)
			)
			(layer "F.SilkS")
		)
		(fp_line
			(start 0.7874 0.4064)
			(end -0.7874 0.4064)
			(stroke
				(width 0.1524)
				(type default)
			)
			(layer "F.SilkS")
		)
		(fp_line
			(start -0.7874 -0.4064)
			(end 0.7874 -0.4064)
			(stroke
				(width 0.1524)
				(type default)
			)
			(layer "F.SilkS")
		)
		(fp_line
			(start 0.7874 -0.4064)
			(end 0.7874 0.4064)
			(stroke
				(width 0.1524)
				(type default)
			)
			(layer "F.SilkS")
		)
		(fp_poly
			(pts
				(xy -0.508 0.2794) (xy -0.508 0.2286) (xy -0.635 0.2286) (xy -0.635 -0.254) (xy -0.5334 -0.254)
				(xy -0.5334 -0.2794) (xy 0.5334 -0.2794) (xy 0.5334 -0.254) (xy 0.635 -0.254) (xy 0.635 0.254) (xy 0.5334 0.254)
				(xy 0.5334 0.2794)
			)
			(stroke
				(width 0)
				(type default)
			)
			(fill no)
			(layer "F.CrtYd")
		)
		(pad "1" smd rect
			(at 0.40005 0 270)
			(size 0.4572 0.508)
			(layers "F.Cu" "F.Mask" "F.Paste")
			(net "PSU2_AD0")
		)
		(pad "2" smd rect
			(at -0.40005 0 270)
			(size 0.4572 0.508)
			(layers "F.Cu" "F.Mask" "F.Paste")
			(net "GND")
		)
	)
	(footprint ""
		(layer "F.Cu")
		(at 27.243786 -285.030164)
		(property "Reference" "R20"
			(at -3.418332 0.009144 0)
			(unlocked yes)
			(layer "F.SilkS")
			(effects
				(font
					(size 0.7874 0.5842)
					(thickness 0.1524)
				)
				(justify left)
			)
		)
		(property "Value" ""
			(at 0 0 0)
			(layer "F.Fab")
			(effects
				(font
					(size 1.27 1.27)
				)
			)
		)
		(duplicate_pad_numbers_are_jumpers no)
		(fp_line
			(start -0.7874 -0.4064)
			(end 0.7874 -0.4064)
			(stroke
				(width 0.1524)
				(type default)
			)
			(layer "F.SilkS")
		)
		(fp_line
			(start -0.7874 0.4064)
			(end -0.7874 -0.4064)
			(stroke
				(width 0.1524)
				(type default)
			)
			(layer "F.SilkS")
		)
		(fp_line
			(start 0.7874 -0.4064)
			(end 0.7874 0.4064)
			(stroke
				(width 0.1524)
				(type default)
			)
			(layer "F.SilkS")
		)
		(fp_line
			(start 0.7874 0.4064)
			(end -0.7874 0.4064)
			(stroke
				(width 0.1524)
				(type default)
			)
			(layer "F.SilkS")
		)
		(fp_poly
			(pts
				(xy -0.508 0.2794) (xy -0.508 0.2286) (xy -0.635 0.2286) (xy -0.635 -0.254) (xy -0.5334 -0.254)
				(xy -0.5334 -0.2794) (xy 0.5334 -0.2794) (xy 0.5334 -0.254) (xy 0.635 -0.254) (xy 0.635 0.254) (xy 0.5334 0.254)
				(xy 0.5334 0.2794)
			)
			(stroke
				(width 0)
				(type default)
			)
			(fill no)
			(layer "F.CrtYd")
		)
		(pad "1" smd rect
			(at 0.40005 0)
			(size 0.4572 0.508)
			(layers "F.Cu" "F.Mask" "F.Paste")
			(net "PSU4_REMOTE_N")
		)
		(pad "2" smd rect
			(at -0.40005 0)
			(size 0.4572 0.508)
			(layers "F.Cu" "F.Mask" "F.Paste")
			(net "GND")
		)
	)
	(footprint ""
		(layer "F.Cu")
		(at 40.11422 -371.513354 180)
		(property "Reference" "R27"
			(at -1.756918 -0.348742 0)
			(unlocked yes)
			(layer "F.SilkS")
			(effects
				(font
					(size 0.7874 0.5842)
					(thickness 0.1524)
				)
				(justify left)
			)
		)
		(property "Value" ""
			(at 0 0 180)
			(layer "F.Fab")
			(effects
				(font
					(size 1.27 1.27)
				)
			)
		)
		(duplicate_pad_numbers_are_jumpers no)
		(fp_line
			(start 0.7874 0.4064)
			(end -0.7874 0.4064)
			(stroke
				(width 0.1524)
				(type default)
			)
			(layer "F.SilkS")
		)
		(fp_line
			(start 0.7874 -0.4064)
			(end 0.7874 0.4064)
			(stroke
				(width 0.1524)
				(type default)
			)
			(layer "F.SilkS")
		)
		(fp_line
			(start -0.7874 0.4064)
			(end -0.7874 -0.4064)
			(stroke
				(width 0.1524)
				(type default)
			)
			(layer "F.SilkS")
		)
		(fp_line
			(start -0.7874 -0.4064)
			(end 0.7874 -0.4064)
			(stroke
				(width 0.1524)
				(type default)
			)
			(layer "F.SilkS")
		)
		(fp_poly
			(pts
				(xy -0.508 0.2794) (xy -0.508 0.2286) (xy -0.635 0.2286) (xy -0.635 -0.254) (xy -0.5334 -0.254)
				(xy -0.5334 -0.2794) (xy 0.5334 -0.2794) (xy 0.5334 -0.254) (xy 0.635 -0.254) (xy 0.635 0.254) (xy 0.5334 0.254)
				(xy 0.5334 0.2794)
			)
			(stroke
				(width 0)
				(type default)
			)
			(fill no)
			(layer "F.CrtYd")
		)
		(pad "1" smd rect
			(at 0.40005 0 180)
			(size 0.4572 0.508)
			(layers "F.Cu" "F.Mask" "F.Paste")
			(net "PSU5_AD0")
		)
		(pad "2" smd rect
			(at -0.40005 0 180)
			(size 0.4572 0.508)
			(layers "F.Cu" "F.Mask" "F.Paste")
			(net "GND")
		)
	)
	(footprint ""
		(layer "F.Cu")
		(at 25.997662 -9.509252)
		(property "Reference" "R63"
			(at -3.764788 0.113792 0)
			(unlocked yes)
			(layer "F.SilkS")
			(effects
				(font
					(size 0.7874 0.5842)
					(thickness 0.1524)
				)
				(justify left)
			)
		)
		(property "Value" ""
			(at 0 0 0)
			(layer "F.Fab")
			(effects
				(font
					(size 1.27 1.27)
				)
			)
		)
		(duplicate_pad_numbers_are_jumpers no)
		(fp_line
			(start -0.7874 -0.4064)
			(end 0.7874 -0.4064)
			(stroke
				(width 0.1524)
				(type default)
			)
			(layer "F.SilkS")
		)
		(fp_line
			(start -0.7874 0.4064)
			(end -0.7874 -0.4064)
			(stroke
				(width 0.1524)
				(type default)
			)
			(layer "F.SilkS")
		)
		(fp_line
			(start 0.7874 -0.4064)
			(end 0.7874 0.4064)
			(stroke
				(width 0.1524)
				(type default)
			)
			(layer "F.SilkS")
		)
		(fp_line
			(start 0.7874 0.4064)
			(end -0.7874 0.4064)
			(stroke
				(width 0.1524)
				(type default)
			)
			(layer "F.SilkS")
		)
		(fp_poly
			(pts
				(xy -0.508 0.2794) (xy -0.508 0.2286) (xy -0.635 0.2286) (xy -0.635 -0.254) (xy -0.5334 -0.254)
				(xy -0.5334 -0.2794) (xy 0.5334 -0.2794) (xy 0.5334 -0.254) (xy 0.635 -0.254) (xy 0.635 0.254) (xy 0.5334 0.254)
				(xy 0.5334 0.2794)
			)
			(stroke
				(width 0)
				(type default)
			)
			(fill no)
			(layer "F.CrtYd")
		)
		(pad "1" smd rect
			(at 0.40005 0)
			(size 0.4572 0.508)
			(layers "F.Cu" "F.Mask" "F.Paste")
			(net "PSU1_PS_KILL")
		)
		(pad "2" smd rect
			(at -0.40005 0)
			(size 0.4572 0.508)
			(layers "F.Cu" "F.Mask" "F.Paste")
			(net "GND")
		)
	)
	(footprint ""
		(layer "F.Cu")
		(at 13.455142 -321.89166 180)
		(property "Reference" "R143"
			(at -1.706626 -0.091186 0)
			(unlocked yes)
			(layer "F.SilkS")
			(effects
				(font
					(size 0.7874 0.5842)
					(thickness 0.1524)
				)
				(justify left)
			)
		)
		(property "Value" ""
			(at 0 0 180)
			(layer "F.Fab")
			(effects
				(font
					(size 1.27 1.27)
				)
			)
		)
		(duplicate_pad_numbers_are_jumpers no)
		(fp_line
			(start 0.7874 0.4064)
			(end -0.7874 0.4064)
			(stroke
				(width 0.1524)
				(type default)
			)
			(layer "F.SilkS")
		)
		(fp_line
			(start 0.7874 -0.4064)
			(end 0.7874 0.4064)
			(stroke
				(width 0.1524)
				(type default)
			)
			(layer "F.SilkS")
		)
		(fp_line
			(start -0.7874 0.4064)
			(end -0.7874 -0.4064)
			(stroke
				(width 0.1524)
				(type default)
			)
			(layer "F.SilkS")
		)
		(fp_line
			(start -0.7874 -0.4064)
			(end 0.7874 -0.4064)
			(stroke
				(width 0.1524)
				(type default)
			)
			(layer "F.SilkS")
		)
		(fp_poly
			(pts
				(xy -0.508 0.2794) (xy -0.508 0.2286) (xy -0.635 0.2286) (xy -0.635 -0.254) (xy -0.5334 -0.254)
				(xy -0.5334 -0.2794) (xy 0.5334 -0.2794) (xy 0.5334 -0.254) (xy 0.635 -0.254) (xy 0.635 0.254) (xy 0.5334 0.254)
				(xy 0.5334 0.2794)
			)
			(stroke
				(width 0)
				(type default)
			)
			(fill no)
			(layer "F.CrtYd")
		)
		(pad "1" smd rect
			(at 0.40005 0 180)
			(size 0.4572 0.508)
			(layers "F.Cu" "F.Mask" "F.Paste")
			(net "FAN2_TACH")
		)
		(pad "2" smd rect
			(at -0.40005 0 180)
			(size 0.4572 0.508)
			(layers "F.Cu" "F.Mask" "F.Paste")
			(net "P12V")
		)
	)
	(footprint ""
		(layer "F.Cu")
		(at 25.857708 -363.01553)
		(property "Reference" "R80"
			(at -3.917442 -0.225298 0)
			(unlocked yes)
			(layer "F.SilkS")
			(effects
				(font
					(size 0.7874 0.5842)
					(thickness 0.1524)
				)
				(justify left)
			)
		)
		(property "Value" ""
			(at 0 0 0)
			(layer "F.Fab")
			(effects
				(font
					(size 1.27 1.27)
				)
			)
		)
		(duplicate_pad_numbers_are_jumpers no)
		(fp_line
			(start -0.7874 -0.4064)
			(end 0.7874 -0.4064)
			(stroke
				(width 0.1524)
				(type default)
			)
			(layer "F.SilkS")
		)
		(fp_line
			(start -0.7874 0.4064)
			(end -0.7874 -0.4064)
			(stroke
				(width 0.1524)
				(type default)
			)
			(layer "F.SilkS")
		)
		(fp_line
			(start 0.7874 -0.4064)
			(end 0.7874 0.4064)
			(stroke
				(width 0.1524)
				(type default)
			)
			(layer "F.SilkS")
		)
		(fp_line
			(start 0.7874 0.4064)
			(end -0.7874 0.4064)
			(stroke
				(width 0.1524)
				(type default)
			)
			(layer "F.SilkS")
		)
		(fp_poly
			(pts
				(xy -0.508 0.2794) (xy -0.508 0.2286) (xy -0.635 0.2286) (xy -0.635 -0.254) (xy -0.5334 -0.254)
				(xy -0.5334 -0.2794) (xy 0.5334 -0.2794) (xy 0.5334 -0.254) (xy 0.635 -0.254) (xy 0.635 0.254) (xy 0.5334 0.254)
				(xy 0.5334 0.2794)
			)
			(stroke
				(width 0)
				(type default)
			)
			(fill no)
			(layer "F.CrtYd")
		)
		(pad "1" smd rect
			(at 0.40005 0)
			(size 0.4572 0.508)
			(layers "F.Cu" "F.Mask" "F.Paste")
			(net "PSU5_RESET")
		)
		(pad "2" smd rect
			(at -0.40005 0)
			(size 0.4572 0.508)
			(layers "F.Cu" "F.Mask" "F.Paste")
			(net "P12V_STBY")
		)
	)
	(footprint ""
		(layer "F.Cu")
		(at 27.334718 -196.234304 90)
		(property "Reference" "R121"
			(at -3.838194 0.013462 90)
			(unlocked yes)
			(layer "F.SilkS")
			(effects
				(font
					(size 0.7874 0.5842)
					(thickness 0.1524)
				)
				(justify left)
			)
		)
		(property "Value" ""
			(at 0 0 90)
			(layer "F.Fab")
			(effects
				(font
					(size 1.27 1.27)
				)
			)
		)
		(duplicate_pad_numbers_are_jumpers no)
		(fp_line
			(start 0.7874 -0.4064)
			(end 0.7874 0.4064)
			(stroke
				(width 0.1524)
				(type default)
			)
			(layer "F.SilkS")
		)
		(fp_line
			(start -0.7874 -0.4064)
			(end 0.7874 -0.4064)
			(stroke
				(width 0.1524)
				(type default)
			)
			(layer "F.SilkS")
		)
		(fp_line
			(start 0.7874 0.4064)
			(end -0.7874 0.4064)
			(stroke
				(width 0.1524)
				(type default)
			)
			(layer "F.SilkS")
		)
		(fp_line
			(start -0.7874 0.4064)
			(end -0.7874 -0.4064)
			(stroke
				(width 0.1524)
				(type default)
			)
			(layer "F.SilkS")
		)
		(fp_poly
			(pts
				(xy -0.508 0.2794) (xy -0.508 0.2286) (xy -0.635 0.2286) (xy -0.635 -0.254) (xy -0.5334 -0.254)
				(xy -0.5334 -0.2794) (xy 0.5334 -0.2794) (xy 0.5334 -0.254) (xy 0.635 -0.254) (xy 0.635 0.254) (xy 0.5334 0.254)
				(xy 0.5334 0.2794)
			)
			(stroke
				(width 0)
				(type default)
			)
			(fill no)
			(layer "F.CrtYd")
		)
		(pad "1" smd rect
			(at 0.40005 0 90)
			(size 0.4572 0.508)
			(layers "F.Cu" "F.Mask" "F.Paste")
			(net "PSU3_REMOTE_N")
		)
		(pad "2" smd rect
			(at -0.40005 0 90)
			(size 0.4572 0.508)
			(layers "F.Cu" "F.Mask" "F.Paste")
			(net "PSU3_REMOTE_R2_N")
		)
	)
	(footprint ""
		(layer "F.Cu")
		(at 70.85457 -172.135546 90)
		(property "Reference" "C33"
			(at -4.154424 0.196088 90)
			(unlocked yes)
			(layer "F.SilkS")
			(effects
				(font
					(size 0.7874 0.5842)
					(thickness 0.1524)
				)
				(justify left)
			)
		)
		(property "Value" ""
			(at 0 0 90)
			(layer "F.Fab")
			(effects
				(font
					(size 1.27 1.27)
				)
			)
		)
		(duplicate_pad_numbers_are_jumpers no)
		(fp_line
			(start 0.7874 -0.4064)
			(end 0.7874 0.4064)
			(stroke
				(width 0.1524)
				(type default)
			)
			(layer "F.SilkS")
		)
		(fp_line
			(start -0.7874 -0.4064)
			(end 0.7874 -0.4064)
			(stroke
				(width 0.1524)
				(type default)
			)
			(layer "F.SilkS")
		)
		(fp_line
			(start 0 0.381)
			(end 0 -0.381)
			(stroke
				(width 0.1524)
				(type default)
			)
			(layer "F.SilkS")
		)
		(fp_line
			(start 0.7874 0.4064)
			(end -0.7874 0.4064)
			(stroke
				(width 0.1524)
				(type default)
			)
			(layer "F.SilkS")
		)
		(fp_line
			(start -0.7874 0.4064)
			(end -0.7874 -0.4064)
			(stroke
				(width 0.1524)
				(type default)
			)
			(layer "F.SilkS")
		)
		(fp_poly
			(pts
				(xy -0.5334 0.254) (xy -0.635 0.254) (xy -0.635 0.2286) (xy -0.635 -0.254) (xy -0.5334 -0.254) (xy -0.5334 -0.2794)
				(xy 0.5334 -0.2794) (xy 0.5334 -0.254) (xy 0.635 -0.254) (xy 0.635 0.254) (xy 0.5334 0.254) (xy 0.5334 0.2794)
				(xy -0.508 0.2794) (xy -0.5334 0.2794)
			)
			(stroke
				(width 0)
				(type default)
			)
			(fill no)
			(layer "F.CrtYd")
		)
		(pad "1" smd rect
			(at 0.40005 0 90)
			(size 0.4572 0.508)
			(layers "F.Cu" "F.Mask" "F.Paste")
			(net "P12V")
		)
		(pad "2" smd rect
			(at -0.40005 0 90)
			(size 0.4572 0.508)
			(layers "F.Cu" "F.Mask" "F.Paste")
			(net "GND")
		)
	)
	(footprint ""
		(layer "F.Cu")
		(at 73.199752 -285.966154 -90)
		(property "Reference" "C44"
			(at 0.870204 -4.091432 90)
			(unlocked yes)
			(layer "F.SilkS")
			(effects
				(font
					(size 0.7874 0.5842)
					(thickness 0.1524)
				)
				(justify left)
			)
		)
		(property "Value" ""
			(at 0 0 270)
			(layer "F.Fab")
			(effects
				(font
					(size 1.27 1.27)
				)
			)
		)
		(duplicate_pad_numbers_are_jumpers no)
		(fp_line
			(start -0.7874 0.4064)
			(end -0.7874 -0.4064)
			(stroke
				(width 0.1524)
				(type default)
			)
			(layer "F.SilkS")
		)
		(fp_line
			(start 0.7874 0.4064)
			(end -0.7874 0.4064)
			(stroke
				(width 0.1524)
				(type default)
			)
			(layer "F.SilkS")
		)
		(fp_line
			(start 0 0.381)
			(end 0 -0.381)
			(stroke
				(width 0.1524)
				(type default)
			)
			(layer "F.SilkS")
		)
		(fp_line
			(start -0.7874 -0.4064)
			(end 0.7874 -0.4064)
			(stroke
				(width 0.1524)
				(type default)
			)
			(layer "F.SilkS")
		)
		(fp_line
			(start 0.7874 -0.4064)
			(end 0.7874 0.4064)
			(stroke
				(width 0.1524)
				(type default)
			)
			(layer "F.SilkS")
		)
		(fp_poly
			(pts
				(xy -0.5334 0.254) (xy -0.635 0.254) (xy -0.635 0.2286) (xy -0.635 -0.254) (xy -0.5334 -0.254) (xy -0.5334 -0.2794)
				(xy 0.5334 -0.2794) (xy 0.5334 -0.254) (xy 0.635 -0.254) (xy 0.635 0.254) (xy 0.5334 0.254) (xy 0.5334 0.2794)
				(xy -0.508 0.2794) (xy -0.5334 0.2794)
			)
			(stroke
				(width 0)
				(type default)
			)
			(fill no)
			(layer "F.CrtYd")
		)
		(pad "1" smd rect
			(at 0.40005 0 270)
			(size 0.4572 0.508)
			(layers "F.Cu" "F.Mask" "F.Paste")
			(net "P12V")
		)
		(pad "2" smd rect
			(at -0.40005 0 270)
			(size 0.4572 0.508)
			(layers "F.Cu" "F.Mask" "F.Paste")
			(net "GND")
		)
	)
	(footprint ""
		(layer "F.Cu")
		(at 39.873936 -462.37144)
		(property "Reference" "R18"
			(at 1.141984 0.133096 0)
			(unlocked yes)
			(layer "F.SilkS")
			(effects
				(font
					(size 0.7874 0.5842)
					(thickness 0.1524)
				)
				(justify left)
			)
		)
		(property "Value" ""
			(at 0 0 0)
			(layer "F.Fab")
			(effects
				(font
					(size 1.27 1.27)
				)
			)
		)
		(duplicate_pad_numbers_are_jumpers no)
		(fp_line
			(start -0.7874 -0.4064)
			(end 0.7874 -0.4064)
			(stroke
				(width 0.1524)
				(type default)
			)
			(layer "F.SilkS")
		)
		(fp_line
			(start -0.7874 0.4064)
			(end -0.7874 -0.4064)
			(stroke
				(width 0.1524)
				(type default)
			)
			(layer "F.SilkS")
		)
		(fp_line
			(start 0.7874 -0.4064)
			(end 0.7874 0.4064)
			(stroke
				(width 0.1524)
				(type default)
			)
			(layer "F.SilkS")
		)
		(fp_line
			(start 0.7874 0.4064)
			(end -0.7874 0.4064)
			(stroke
				(width 0.1524)
				(type default)
			)
			(layer "F.SilkS")
		)
		(fp_poly
			(pts
				(xy -0.508 0.2794) (xy -0.508 0.2286) (xy -0.635 0.2286) (xy -0.635 -0.254) (xy -0.5334 -0.254)
				(xy -0.5334 -0.2794) (xy 0.5334 -0.2794) (xy 0.5334 -0.254) (xy 0.635 -0.254) (xy 0.635 0.254) (xy 0.5334 0.254)
				(xy 0.5334 0.2794)
			)
			(stroke
				(width 0)
				(type default)
			)
			(fill no)
			(layer "F.CrtYd")
		)
		(pad "1" smd rect
			(at 0.40005 0)
			(size 0.4572 0.508)
			(layers "F.Cu" "F.Mask" "F.Paste")
			(net "PSU6_AD0")
		)
		(pad "2" smd rect
			(at -0.40005 0)
			(size 0.4572 0.508)
			(layers "F.Cu" "F.Mask" "F.Paste")
			(net "P12V_STBY")
		)
	)
	(footprint ""
		(layer "F.Cu")
		(at 71.810118 -483.48138 90)
		(property "Reference" "C82"
			(at -4.162806 0.225044 90)
			(unlocked yes)
			(layer "F.SilkS")
			(effects
				(font
					(size 0.7874 0.5842)
					(thickness 0.1524)
				)
				(justify left)
			)
		)
		(property "Value" ""
			(at 0 0 90)
			(layer "F.Fab")
			(effects
				(font
					(size 1.27 1.27)
				)
			)
		)
		(duplicate_pad_numbers_are_jumpers no)
		(fp_line
			(start 0.7874 -0.4064)
			(end 0.7874 0.4064)
			(stroke
				(width 0.1524)
				(type default)
			)
			(layer "F.SilkS")
		)
		(fp_line
			(start -0.7874 -0.4064)
			(end 0.7874 -0.4064)
			(stroke
				(width 0.1524)
				(type default)
			)
			(layer "F.SilkS")
		)
		(fp_line
			(start 0 0.381)
			(end 0 -0.381)
			(stroke
				(width 0.1524)
				(type default)
			)
			(layer "F.SilkS")
		)
		(fp_line
			(start 0.7874 0.4064)
			(end -0.7874 0.4064)
			(stroke
				(width 0.1524)
				(type default)
			)
			(layer "F.SilkS")
		)
		(fp_line
			(start -0.7874 0.4064)
			(end -0.7874 -0.4064)
			(stroke
				(width 0.1524)
				(type default)
			)
			(layer "F.SilkS")
		)
		(fp_poly
			(pts
				(xy -0.5334 0.254) (xy -0.635 0.254) (xy -0.635 0.2286) (xy -0.635 -0.254) (xy -0.5334 -0.254) (xy -0.5334 -0.2794)
				(xy 0.5334 -0.2794) (xy 0.5334 -0.254) (xy 0.635 -0.254) (xy 0.635 0.254) (xy 0.5334 0.254) (xy 0.5334 0.2794)
				(xy -0.508 0.2794) (xy -0.5334 0.2794)
			)
			(stroke
				(width 0)
				(type default)
			)
			(fill no)
			(layer "F.CrtYd")
		)
		(pad "1" smd rect
			(at 0.40005 0 90)
			(size 0.4572 0.508)
			(layers "F.Cu" "F.Mask" "F.Paste")
			(net "P12V")
		)
		(pad "2" smd rect
			(at -0.40005 0 90)
			(size 0.4572 0.508)
			(layers "F.Cu" "F.Mask" "F.Paste")
			(net "GND")
		)
	)
	(footprint ""
		(layer "F.Cu")
		(at 76.120498 -18.749772 -90)
		(property "Reference" "C2"
			(at -1.75133 0.044704 90)
			(unlocked yes)
			(layer "F.SilkS")
			(effects
				(font
					(size 0.7874 0.5842)
					(thickness 0.1524)
				)
				(justify left)
			)
		)
		(property "Value" ""
			(at 0 0 270)
			(layer "F.Fab")
			(effects
				(font
					(size 1.27 1.27)
				)
			)
		)
		(duplicate_pad_numbers_are_jumpers no)
		(fp_line
			(start -0.7874 0.4064)
			(end -0.7874 -0.4064)
			(stroke
				(width 0.1524)
				(type default)
			)
			(layer "F.SilkS")
		)
		(fp_line
			(start 0.7874 0.4064)
			(end -0.7874 0.4064)
			(stroke
				(width 0.1524)
				(type default)
			)
			(layer "F.SilkS")
		)
		(fp_line
			(start 0 0.381)
			(end 0 -0.381)
			(stroke
				(width 0.1524)
				(type default)
			)
			(layer "F.SilkS")
		)
		(fp_line
			(start -0.7874 -0.4064)
			(end 0.7874 -0.4064)
			(stroke
				(width 0.1524)
				(type default)
			)
			(layer "F.SilkS")
		)
		(fp_line
			(start 0.7874 -0.4064)
			(end 0.7874 0.4064)
			(stroke
				(width 0.1524)
				(type default)
			)
			(layer "F.SilkS")
		)
		(fp_poly
			(pts
				(xy -0.5334 0.254) (xy -0.635 0.254) (xy -0.635 0.2286) (xy -0.635 -0.254) (xy -0.5334 -0.254) (xy -0.5334 -0.2794)
				(xy 0.5334 -0.2794) (xy 0.5334 -0.254) (xy 0.635 -0.254) (xy 0.635 0.254) (xy 0.5334 0.254) (xy 0.5334 0.2794)
				(xy -0.508 0.2794) (xy -0.5334 0.2794)
			)
			(stroke
				(width 0)
				(type default)
			)
			(fill no)
			(layer "F.CrtYd")
		)
		(pad "1" smd rect
			(at 0.40005 0 270)
			(size 0.4572 0.508)
			(layers "F.Cu" "F.Mask" "F.Paste")
			(net "P12V")
		)
		(pad "2" smd rect
			(at -0.40005 0 270)
			(size 0.4572 0.508)
			(layers "F.Cu" "F.Mask" "F.Paste")
			(net "GND")
		)
	)
	(footprint ""
		(layer "F.Cu")
		(at 40.303958 -370.099336 180)
		(property "Reference" "R24"
			(at -1.863598 -0.010922 0)
			(unlocked yes)
			(layer "F.SilkS")
			(effects
				(font
					(size 0.7874 0.5842)
					(thickness 0.1524)
				)
				(justify left)
			)
		)
		(property "Value" ""
			(at 0 0 180)
			(layer "F.Fab")
			(effects
				(font
					(size 1.27 1.27)
				)
			)
		)
		(duplicate_pad_numbers_are_jumpers no)
		(fp_line
			(start 0.7874 0.4064)
			(end -0.7874 0.4064)
			(stroke
				(width 0.1524)
				(type default)
			)
			(layer "F.SilkS")
		)
		(fp_line
			(start 0.7874 -0.4064)
			(end 0.7874 0.4064)
			(stroke
				(width 0.1524)
				(type default)
			)
			(layer "F.SilkS")
		)
		(fp_line
			(start -0.7874 0.4064)
			(end -0.7874 -0.4064)
			(stroke
				(width 0.1524)
				(type default)
			)
			(layer "F.SilkS")
		)
		(fp_line
			(start -0.7874 -0.4064)
			(end 0.7874 -0.4064)
			(stroke
				(width 0.1524)
				(type default)
			)
			(layer "F.SilkS")
		)
		(fp_poly
			(pts
				(xy -0.508 0.2794) (xy -0.508 0.2286) (xy -0.635 0.2286) (xy -0.635 -0.254) (xy -0.5334 -0.254)
				(xy -0.5334 -0.2794) (xy 0.5334 -0.2794) (xy 0.5334 -0.254) (xy 0.635 -0.254) (xy 0.635 0.254) (xy 0.5334 0.254)
				(xy 0.5334 0.2794)
			)
			(stroke
				(width 0)
				(type default)
			)
			(fill no)
			(layer "F.CrtYd")
		)
		(pad "1" smd rect
			(at 0.40005 0 180)
			(size 0.4572 0.508)
			(layers "F.Cu" "F.Mask" "F.Paste")
			(net "PSU5_RETURN")
		)
		(pad "2" smd rect
			(at -0.40005 0 180)
			(size 0.4572 0.508)
			(layers "F.Cu" "F.Mask" "F.Paste")
			(net "GND")
		)
	)
	(footprint ""
		(layer "F.Cu")
		(at 74.0537 -463.542634 -90)
		(property "Reference" "C73"
			(at -2.840736 0.630936 90)
			(unlocked yes)
			(layer "F.SilkS")
			(effects
				(font
					(size 0.7874 0.5842)
					(thickness 0.1524)
				)
				(justify left)
			)
		)
		(property "Value" ""
			(at 0 0 270)
			(layer "F.Fab")
			(effects
				(font
					(size 1.27 1.27)
				)
			)
		)
		(duplicate_pad_numbers_are_jumpers no)
		(fp_line
			(start -0.7874 0.4064)
			(end -0.7874 -0.4064)
			(stroke
				(width 0.1524)
				(type default)
			)
			(layer "F.SilkS")
		)
		(fp_line
			(start 0.7874 0.4064)
			(end -0.7874 0.4064)
			(stroke
				(width 0.1524)
				(type default)
			)
			(layer "F.SilkS")
		)
		(fp_line
			(start 0 0.381)
			(end 0 -0.381)
			(stroke
				(width 0.1524)
				(type default)
			)
			(layer "F.SilkS")
		)
		(fp_line
			(start -0.7874 -0.4064)
			(end 0.7874 -0.4064)
			(stroke
				(width 0.1524)
				(type default)
			)
			(layer "F.SilkS")
		)
		(fp_line
			(start 0.7874 -0.4064)
			(end 0.7874 0.4064)
			(stroke
				(width 0.1524)
				(type default)
			)
			(layer "F.SilkS")
		)
		(fp_poly
			(pts
				(xy -0.5334 0.254) (xy -0.635 0.254) (xy -0.635 0.2286) (xy -0.635 -0.254) (xy -0.5334 -0.254) (xy -0.5334 -0.2794)
				(xy 0.5334 -0.2794) (xy 0.5334 -0.254) (xy 0.635 -0.254) (xy 0.635 0.254) (xy 0.5334 0.254) (xy 0.5334 0.2794)
				(xy -0.508 0.2794) (xy -0.5334 0.2794)
			)
			(stroke
				(width 0)
				(type default)
			)
			(fill no)
			(layer "F.CrtYd")
		)
		(pad "1" smd rect
			(at 0.40005 0 270)
			(size 0.4572 0.508)
			(layers "F.Cu" "F.Mask" "F.Paste")
			(net "P12V")
		)
		(pad "2" smd rect
			(at -0.40005 0 270)
			(size 0.4572 0.508)
			(layers "F.Cu" "F.Mask" "F.Paste")
			(net "GND")
		)
	)
	(footprint ""
		(layer "F.Cu")
		(at 72.635364 -242.026694 -90)
		(property "Reference" "C36"
			(at 0.16256 -3.77825 90)
			(unlocked yes)
			(layer "F.SilkS")
			(effects
				(font
					(size 0.7874 0.5842)
					(thickness 0.1524)
				)
			)
		)
		(property "Value" ""
			(at 0 0 270)
			(layer "F.Fab")
			(effects
				(font
					(size 1.27 1.27)
				)
			)
		)
		(duplicate_pad_numbers_are_jumpers no)
		(fp_line
			(start -1.2954 0.5842)
			(end -1.2954 -0.5842)
			(stroke
				(width 0.1524)
				(type default)
			)
			(layer "F.SilkS")
		)
		(fp_line
			(start 1.2954 0.5842)
			(end -1.2954 0.5842)
			(stroke
				(width 0.1524)
				(type default)
			)
			(layer "F.SilkS")
		)
		(fp_line
			(start -1.2954 -0.5842)
			(end 1.2954 -0.5842)
			(stroke
				(width 0.1524)
				(type default)
			)
			(layer "F.SilkS")
		)
		(fp_line
			(start 0 -0.5842)
			(end 0 0.5842)
			(stroke
				(width 0.1524)
				(type default)
			)
			(layer "F.SilkS")
		)
		(fp_line
			(start 1.2954 -0.5842)
			(end 1.2954 0.5842)
			(stroke
				(width 0.1524)
				(type default)
			)
			(layer "F.SilkS")
		)
		(fp_poly
			(pts
				(xy 0.8636 -0.4572) (xy 0.8636 -0.3556) (xy 1.143 -0.3556) (xy 1.143 0.3556) (xy 0.8636 0.3556)
				(xy 0.8636 0.4572) (xy -0.8636 0.4572) (xy -0.8636 0.3556) (xy -1.143 0.3556) (xy -1.143 -0.3556)
				(xy -0.8636 -0.3556) (xy -0.8636 -0.4572)
			)
			(stroke
				(width 0)
				(type default)
			)
			(fill no)
			(layer "F.CrtYd")
		)
		(fp_line
			(start -0.884936 0.504952)
			(end -0.884936 -0.504952)
			(stroke
				(width 0.1)
				(type default)
			)
			(layer "F.Fab")
		)
		(fp_line
			(start 0.884936 0.504952)
			(end -0.884936 0.504952)
			(stroke
				(width 0.1)
				(type default)
			)
			(layer "F.Fab")
		)
		(fp_line
			(start -0.884936 -0.504952)
			(end 0.884936 -0.504952)
			(stroke
				(width 0.1)
				(type default)
			)
			(layer "F.Fab")
		)
		(fp_line
			(start 0.884936 -0.504952)
			(end 0.884936 0.504952)
			(stroke
				(width 0.1)
				(type default)
			)
			(layer "F.Fab")
		)
		(pad "1" smd rect
			(at 0.7366 0)
			(size 0.7112 0.8128)
			(layers "F.Cu" "F.Mask" "F.Paste")
			(net "P12V")
		)
		(pad "2" smd rect
			(at -0.7366 0)
			(size 0.7112 0.8128)
			(layers "F.Cu" "F.Mask" "F.Paste")
			(net "GND")
		)
	)
	(footprint ""
		(layer "F.Cu")
		(at 69.073522 -38.821106 90)
		(property "Reference" "C12"
			(at 1.173988 -0.101854 90)
			(unlocked yes)
			(layer "F.SilkS")
			(effects
				(font
					(size 0.7874 0.5842)
					(thickness 0.1524)
				)
				(justify left)
			)
		)
		(property "Value" ""
			(at 0 0 90)
			(layer "F.Fab")
			(effects
				(font
					(size 1.27 1.27)
				)
			)
		)
		(duplicate_pad_numbers_are_jumpers no)
		(fp_line
			(start 0.7874 -0.4064)
			(end 0.7874 0.4064)
			(stroke
				(width 0.1524)
				(type default)
			)
			(layer "F.SilkS")
		)
		(fp_line
			(start -0.7874 -0.4064)
			(end 0.7874 -0.4064)
			(stroke
				(width 0.1524)
				(type default)
			)
			(layer "F.SilkS")
		)
		(fp_line
			(start 0 0.381)
			(end 0 -0.381)
			(stroke
				(width 0.1524)
				(type default)
			)
			(layer "F.SilkS")
		)
		(fp_line
			(start 0.7874 0.4064)
			(end -0.7874 0.4064)
			(stroke
				(width 0.1524)
				(type default)
			)
			(layer "F.SilkS")
		)
		(fp_line
			(start -0.7874 0.4064)
			(end -0.7874 -0.4064)
			(stroke
				(width 0.1524)
				(type default)
			)
			(layer "F.SilkS")
		)
		(fp_poly
			(pts
				(xy -0.5334 0.254) (xy -0.635 0.254) (xy -0.635 0.2286) (xy -0.635 -0.254) (xy -0.5334 -0.254) (xy -0.5334 -0.2794)
				(xy 0.5334 -0.2794) (xy 0.5334 -0.254) (xy 0.635 -0.254) (xy 0.635 0.254) (xy 0.5334 0.254) (xy 0.5334 0.2794)
				(xy -0.508 0.2794) (xy -0.5334 0.2794)
			)
			(stroke
				(width 0)
				(type default)
			)
			(fill no)
			(layer "F.CrtYd")
		)
		(pad "1" smd rect
			(at 0.40005 0 90)
			(size 0.4572 0.508)
			(layers "F.Cu" "F.Mask" "F.Paste")
			(net "P12V")
		)
		(pad "2" smd rect
			(at -0.40005 0 90)
			(size 0.4572 0.508)
			(layers "F.Cu" "F.Mask" "F.Paste")
			(net "GND")
		)
	)
	(footprint ""
		(layer "F.Cu")
		(at 2.772156 -145.957544 -90)
		(property "Reference" "R148"
			(at 1.076452 1.187704 90)
			(unlocked yes)
			(layer "F.SilkS")
			(effects
				(font
					(size 0.7874 0.5842)
					(thickness 0.1524)
				)
				(justify left)
			)
		)
		(property "Value" ""
			(at 0 0 270)
			(layer "F.Fab")
			(effects
				(font
					(size 1.27 1.27)
				)
			)
		)
		(duplicate_pad_numbers_are_jumpers no)
		(fp_line
			(start -0.7874 0.4064)
			(end -0.7874 -0.4064)
			(stroke
				(width 0.1524)
				(type default)
			)
			(layer "F.SilkS")
		)
		(fp_line
			(start 0.7874 0.4064)
			(end -0.7874 0.4064)
			(stroke
				(width 0.1524)
				(type default)
			)
			(layer "F.SilkS")
		)
		(fp_line
			(start -0.7874 -0.4064)
			(end 0.7874 -0.4064)
			(stroke
				(width 0.1524)
				(type default)
			)
			(layer "F.SilkS")
		)
		(fp_line
			(start 0.7874 -0.4064)
			(end 0.7874 0.4064)
			(stroke
				(width 0.1524)
				(type default)
			)
			(layer "F.SilkS")
		)
		(fp_poly
			(pts
				(xy -0.508 0.2794) (xy -0.508 0.2286) (xy -0.635 0.2286) (xy -0.635 -0.254) (xy -0.5334 -0.254)
				(xy -0.5334 -0.2794) (xy 0.5334 -0.2794) (xy 0.5334 -0.254) (xy 0.635 -0.254) (xy 0.635 0.254) (xy 0.5334 0.254)
				(xy 0.5334 0.2794)
			)
			(stroke
				(width 0)
				(type default)
			)
			(fill no)
			(layer "F.CrtYd")
		)
		(pad "1" smd rect
			(at 0.40005 0 270)
			(size 0.4572 0.508)
			(layers "F.Cu" "F.Mask" "F.Paste")
			(net "N42126673")
		)
		(pad "2" smd rect
			(at -0.40005 0 270)
			(size 0.4572 0.508)
			(layers "F.Cu" "F.Mask" "F.Paste")
			(net "GND")
		)
	)
	(footprint ""
		(layer "F.Cu")
		(at 49.949608 -18.56867 180)
		(property "Reference" "CE1"
			(at -4.548124 -1.308608 0)
			(unlocked yes)
			(layer "F.SilkS")
			(effects
				(font
					(size 0.7874 0.5842)
					(thickness 0.1524)
				)
				(justify left)
			)
		)
		(property "Value" ""
			(at 0 0 180)
			(layer "F.Fab")
			(effects
				(font
					(size 1.27 1.27)
				)
			)
		)
		(duplicate_pad_numbers_are_jumpers no)
		(fp_line
			(start 0 -4.2672)
			(end 0 4.2672)
			(stroke
				(width 0.1524)
				(type default)
			)
			(layer "F.SilkS")
		)
		(fp_circle
			(center 0 0)
			(end -4.2672 0)
			(stroke
				(width 0.1524)
				(type default)
			)
			(fill no)
			(layer "F.SilkS")
		)
		(fp_poly
			(pts
				(arc
					(start 0 -4.2672)
					(mid 4.2672 0)
					(end 0 4.2672)
				)
			)
			(stroke
				(width 0)
				(type default)
			)
			(fill yes)
			(layer "F.SilkS")
		)
		(fp_poly
			(pts
				(xy -2.5146 -0.762) (xy -0.9906 -0.762) (xy -0.9906 0.762) (xy -2.5146 0.762)
			)
			(stroke
				(width 0)
				(type default)
			)
			(fill no)
			(layer "B.CrtYd")
		)
		(fp_poly
			(pts
				(arc
					(start 1.7526 0.762)
					(mid 2.291415 -0.538815)
					(end 0.9906 0)
				)
				(arc
					(start 0.9906 0.0254)
					(mid 1.206345 0.546255)
					(end 1.7272 0.762)
				)
			)
			(stroke
				(width 0)
				(type default)
			)
			(fill no)
			(layer "B.CrtYd")
		)
		(fp_poly
			(pts
				(arc
					(start -4.2672 0)
					(mid 4.2672 0)
					(end -4.2672 0)
				)
			)
			(stroke
				(width 0)
				(type default)
			)
			(fill no)
			(layer "F.CrtYd")
		)
		(fp_circle
			(center 0 0)
			(end -4.2672 0)
			(stroke
				(width 0.1)
				(type default)
			)
			(fill no)
			(layer "F.Fab")
		)
		(fp_text user "+"
			(at -5.15239 -2.911348 180)
			(unlocked yes)
			(layer "F.SilkS")
			(effects
				(font
					(size 1.905 1.4224)
					(thickness 0.1524)
				)
				(justify left)
			)
		)
		(fp_text user "+"
			(at -5.6642 -0.34925 180)
			(unlocked yes)
			(layer "F.Fab")
			(effects
				(font
					(size 1.905 1.4224)
					(thickness 0.000001)
				)
				(justify left)
			)
		)
		(pad "1" thru_hole rect
			(at -1.75006 0 180)
			(size 1.397 1.397)
			(drill 0.9144)
			(layers "*.Cu" "*.Mask")
			(remove_unused_layers no)
			(net "P12V")
			(clearance 0.0127)
			(thermal_gap 0.0127)
			(padstack
				(mode front_inner_back)
				(layer "Inner"
					(shape circle)
					(size 1.397 1.397)
					(clearance 0.0127)
				)
				(layer "B.Cu"
					(shape rect)
					(size 1.397 1.397)
					(clearance 0.0127)
				)
			)
		)
		(pad "2" thru_hole circle
			(at 1.75006 0 180)
			(size 1.397 1.397)
			(drill 0.9144)
			(layers "*.Cu" "*.Mask")
			(remove_unused_layers no)
			(net "GND")
			(clearance 0.0127)
			(thermal_gap 0.0127)
		)
	)
	(footprint ""
		(layer "F.Cu")
		(at 27.244802 -19.46402 90)
		(property "Reference" "R113"
			(at -3.094482 -0.932688 90)
			(unlocked yes)
			(layer "F.SilkS")
			(effects
				(font
					(size 0.7874 0.5842)
					(thickness 0.1524)
				)
				(justify left)
			)
		)
		(property "Value" ""
			(at 0 0 90)
			(layer "F.Fab")
			(effects
				(font
					(size 1.27 1.27)
				)
			)
		)
		(duplicate_pad_numbers_are_jumpers no)
		(fp_line
			(start 0.7874 -0.4064)
			(end 0.7874 0.4064)
			(stroke
				(width 0.1524)
				(type default)
			)
			(layer "F.SilkS")
		)
		(fp_line
			(start -0.7874 -0.4064)
			(end 0.7874 -0.4064)
			(stroke
				(width 0.1524)
				(type default)
			)
			(layer "F.SilkS")
		)
		(fp_line
			(start 0.7874 0.4064)
			(end -0.7874 0.4064)
			(stroke
				(width 0.1524)
				(type default)
			)
			(layer "F.SilkS")
		)
		(fp_line
			(start -0.7874 0.4064)
			(end -0.7874 -0.4064)
			(stroke
				(width 0.1524)
				(type default)
			)
			(layer "F.SilkS")
		)
		(fp_poly
			(pts
				(xy -0.508 0.2794) (xy -0.508 0.2286) (xy -0.635 0.2286) (xy -0.635 -0.254) (xy -0.5334 -0.254)
				(xy -0.5334 -0.2794) (xy 0.5334 -0.2794) (xy 0.5334 -0.254) (xy 0.635 -0.254) (xy 0.635 0.254) (xy 0.5334 0.254)
				(xy 0.5334 0.2794)
			)
			(stroke
				(width 0)
				(type default)
			)
			(fill no)
			(layer "F.CrtYd")
		)
		(pad "1" smd rect
			(at 0.40005 0 90)
			(size 0.4572 0.508)
			(layers "F.Cu" "F.Mask" "F.Paste")
			(net "PSU1_REMOTE_N")
		)
		(pad "2" smd rect
			(at -0.40005 0 90)
			(size 0.4572 0.508)
			(layers "F.Cu" "F.Mask" "F.Paste")
			(net "PSU1_REMOTE_R2_N")
		)
	)
	(footprint ""
		(layer "F.Cu")
		(at 81.78927 -18.749772 -90)
		(property "Reference" "C7"
			(at -1.75133 -0.093726 90)
			(unlocked yes)
			(layer "F.SilkS")
			(effects
				(font
					(size 0.7874 0.5842)
					(thickness 0.1524)
				)
				(justify left)
			)
		)
		(property "Value" ""
			(at 0 0 270)
			(layer "F.Fab")
			(effects
				(font
					(size 1.27 1.27)
				)
			)
		)
		(duplicate_pad_numbers_are_jumpers no)
		(fp_line
			(start -0.7874 0.4064)
			(end -0.7874 -0.4064)
			(stroke
				(width 0.1524)
				(type default)
			)
			(layer "F.SilkS")
		)
		(fp_line
			(start 0.7874 0.4064)
			(end -0.7874 0.4064)
			(stroke
				(width 0.1524)
				(type default)
			)
			(layer "F.SilkS")
		)
		(fp_line
			(start 0 0.381)
			(end 0 -0.381)
			(stroke
				(width 0.1524)
				(type default)
			)
			(layer "F.SilkS")
		)
		(fp_line
			(start -0.7874 -0.4064)
			(end 0.7874 -0.4064)
			(stroke
				(width 0.1524)
				(type default)
			)
			(layer "F.SilkS")
		)
		(fp_line
			(start 0.7874 -0.4064)
			(end 0.7874 0.4064)
			(stroke
				(width 0.1524)
				(type default)
			)
			(layer "F.SilkS")
		)
		(fp_poly
			(pts
				(xy -0.5334 0.254) (xy -0.635 0.254) (xy -0.635 0.2286) (xy -0.635 -0.254) (xy -0.5334 -0.254) (xy -0.5334 -0.2794)
				(xy 0.5334 -0.2794) (xy 0.5334 -0.254) (xy 0.635 -0.254) (xy 0.635 0.254) (xy 0.5334 0.254) (xy 0.5334 0.2794)
				(xy -0.508 0.2794) (xy -0.5334 0.2794)
			)
			(stroke
				(width 0)
				(type default)
			)
			(fill no)
			(layer "F.CrtYd")
		)
		(pad "1" smd rect
			(at 0.40005 0 270)
			(size 0.4572 0.508)
			(layers "F.Cu" "F.Mask" "F.Paste")
			(net "P12V")
		)
		(pad "2" smd rect
			(at -0.40005 0 270)
			(size 0.4572 0.508)
			(layers "F.Cu" "F.Mask" "F.Paste")
			(net "GND")
		)
	)
	(footprint ""
		(layer "F.Cu")
		(at 74.804524 -83.335368 90)
		(property "Reference" "C18"
			(at 1.011428 0.19177 90)
			(unlocked yes)
			(layer "F.SilkS")
			(effects
				(font
					(size 0.7874 0.5842)
					(thickness 0.1524)
				)
				(justify left)
			)
		)
		(property "Value" ""
			(at 0 0 90)
			(layer "F.Fab")
			(effects
				(font
					(size 1.27 1.27)
				)
			)
		)
		(duplicate_pad_numbers_are_jumpers no)
		(fp_line
			(start 0.7874 -0.4064)
			(end 0.7874 0.4064)
			(stroke
				(width 0.1524)
				(type default)
			)
			(layer "F.SilkS")
		)
		(fp_line
			(start -0.7874 -0.4064)
			(end 0.7874 -0.4064)
			(stroke
				(width 0.1524)
				(type default)
			)
			(layer "F.SilkS")
		)
		(fp_line
			(start 0 0.381)
			(end 0 -0.381)
			(stroke
				(width 0.1524)
				(type default)
			)
			(layer "F.SilkS")
		)
		(fp_line
			(start 0.7874 0.4064)
			(end -0.7874 0.4064)
			(stroke
				(width 0.1524)
				(type default)
			)
			(layer "F.SilkS")
		)
		(fp_line
			(start -0.7874 0.4064)
			(end -0.7874 -0.4064)
			(stroke
				(width 0.1524)
				(type default)
			)
			(layer "F.SilkS")
		)
		(fp_poly
			(pts
				(xy -0.5334 0.254) (xy -0.635 0.254) (xy -0.635 0.2286) (xy -0.635 -0.254) (xy -0.5334 -0.254) (xy -0.5334 -0.2794)
				(xy 0.5334 -0.2794) (xy 0.5334 -0.254) (xy 0.635 -0.254) (xy 0.635 0.254) (xy 0.5334 0.254) (xy 0.5334 0.2794)
				(xy -0.508 0.2794) (xy -0.5334 0.2794)
			)
			(stroke
				(width 0)
				(type default)
			)
			(fill no)
			(layer "F.CrtYd")
		)
		(pad "1" smd rect
			(at 0.40005 0 90)
			(size 0.4572 0.508)
			(layers "F.Cu" "F.Mask" "F.Paste")
			(net "P12V")
		)
		(pad "2" smd rect
			(at -0.40005 0 90)
			(size 0.4572 0.508)
			(layers "F.Cu" "F.Mask" "F.Paste")
			(net "GND")
		)
	)
	(footprint ""
		(layer "F.Cu")
		(at 5.780024 -477.17202)
		(property "Reference" "J30"
			(at -1.9304 -3.978148 0)
			(unlocked yes)
			(layer "F.SilkS")
			(effects
				(font
					(size 0.7874 0.5842)
					(thickness 0.1524)
				)
				(justify left)
			)
		)
		(property "Value" ""
			(at 0 0 0)
			(layer "F.Fab")
			(effects
				(font
					(size 1.27 1.27)
				)
			)
		)
		(duplicate_pad_numbers_are_jumpers no)
		(fp_line
			(start -3.10007 0.199898)
			(end -3.10007 2.800096)
			(stroke
				(width 0.1524)
				(type default)
			)
			(layer "F.SilkS")
		)
		(fp_line
			(start -3.10007 2.800096)
			(end -1.89992 2.800096)
			(stroke
				(width 0.1524)
				(type default)
			)
			(layer "F.SilkS")
		)
		(fp_line
			(start -1.89992 -3.325114)
			(end -1.89992 0.199898)
			(stroke
				(width 0.1524)
				(type default)
			)
			(layer "F.SilkS")
		)
		(fp_line
			(start -1.89992 0.199898)
			(end -3.10007 0.199898)
			(stroke
				(width 0.1524)
				(type default)
			)
			(layer "F.SilkS")
		)
		(fp_line
			(start -1.89992 2.800096)
			(end -1.89992 6.325108)
			(stroke
				(width 0.1524)
				(type default)
			)
			(layer "F.SilkS")
		)
		(fp_line
			(start -1.89992 6.325108)
			(end 1.016 6.325108)
			(stroke
				(width 0.1524)
				(type default)
			)
			(layer "F.SilkS")
		)
		(fp_line
			(start 1.016 -3.325114)
			(end -1.89992 -3.325114)
			(stroke
				(width 0.1524)
				(type default)
			)
			(layer "F.SilkS")
		)
		(fp_line
			(start 2.469896 5.133594)
			(end 2.469896 -2.130806)
			(stroke
				(width 0.1524)
				(type default)
			)
			(layer "F.SilkS")
		)
		(fp_poly
			(pts
				(xy 0.8509 0.8509) (xy -0.8509 0.8509) (xy -0.8509 -0.8509) (xy 0.8509 -0.8509)
			)
			(stroke
				(width 0)
				(type default)
			)
			(fill no)
			(layer "B.CrtYd")
		)
		(fp_poly
			(pts
				(arc
					(start 0.8509 2.999994)
					(mid -0.8509 2.999994)
					(end 0.8509 2.999994)
				)
			)
			(stroke
				(width 0)
				(type default)
			)
			(fill no)
			(layer "B.CrtYd")
		)
		(fp_poly
			(pts
				(arc
					(start 2.874518 -2.999994)
					(mid 1.045718 -2.999994)
					(end 2.874518 -2.999994)
				)
			)
			(stroke
				(width 0)
				(type default)
			)
			(fill no)
			(layer "B.CrtYd")
		)
		(fp_poly
			(pts
				(arc
					(start 2.874518 5.999988)
					(mid 1.045718 5.999988)
					(end 2.874518 5.999988)
				)
			)
			(stroke
				(width 0)
				(type default)
			)
			(fill no)
			(layer "B.CrtYd")
		)
		(fp_poly
			(pts
				(xy 2.469896 5.233924) (xy 2.469896 -2.233676) (xy 2.8956 -2.233676) (xy 2.8956 -3.935476) (xy 1.0922 -3.935476)
				(xy 1.0922 -3.325114) (xy -1.89992 -3.325114) (xy -1.89992 0.199898) (xy -3.10007 0.199898) (xy -3.10007 2.800096)
				(xy -1.89992 2.800096) (xy -1.89992 6.325108) (xy 1.0922 6.325108) (xy 1.0922 6.935724) (xy 2.8956 6.935724)
				(xy 2.8956 5.233924)
			)
			(stroke
				(width 0)
				(type default)
			)
			(fill no)
			(layer "F.CrtYd")
		)
		(fp_line
			(start -3.10007 0.199898)
			(end -3.10007 2.800096)
			(stroke
				(width 0.1)
				(type default)
			)
			(layer "F.Fab")
		)
		(fp_line
			(start -3.10007 2.800096)
			(end -1.89992 2.800096)
			(stroke
				(width 0.1)
				(type default)
			)
			(layer "F.Fab")
		)
		(fp_line
			(start -1.89992 -3.325114)
			(end -1.89992 0.199898)
			(stroke
				(width 0.1)
				(type default)
			)
			(layer "F.Fab")
		)
		(fp_line
			(start -1.89992 0.199898)
			(end -3.10007 0.199898)
			(stroke
				(width 0.1)
				(type default)
			)
			(layer "F.Fab")
		)
		(fp_line
			(start -1.89992 2.800096)
			(end -1.89992 6.325108)
			(stroke
				(width 0.1)
				(type default)
			)
			(layer "F.Fab")
		)
		(fp_line
			(start -1.89992 6.325108)
			(end 2.469896 6.325108)
			(stroke
				(width 0.1)
				(type default)
			)
			(layer "F.Fab")
		)
		(fp_line
			(start 2.469896 -3.325114)
			(end -1.89992 -3.325114)
			(stroke
				(width 0.1)
				(type default)
			)
			(layer "F.Fab")
		)
		(fp_line
			(start 2.469896 6.325108)
			(end 2.469896 -3.325114)
			(stroke
				(width 0.1)
				(type default)
			)
			(layer "F.Fab")
		)
		(pad "" np_thru_hole circle
			(at 1.960118 -2.999994 90)
			(size 1.3208 1.3208)
			(drill 1.3208)
			(layers "*.Cu" "*.Mask")
			(clearance 0.381)
			(thermal_gap 0.381)
		)
		(pad "" np_thru_hole circle
			(at 1.960118 5.999988 90)
			(size 1.3208 1.3208)
			(drill 1.3208)
			(layers "*.Cu" "*.Mask")
			(clearance 0.381)
			(thermal_gap 0.381)
		)
		(pad "1" thru_hole rect
			(at 0 0 90)
			(size 1.6002 1.6002)
			(drill 1.0922)
			(layers "*.Cu" "*.Mask")
			(remove_unused_layers no)
			(net "POWER_SW3_PWR_CTR_12V")
			(clearance 0)
			(padstack
				(mode front_inner_back)
				(layer "Inner"
					(shape circle)
					(size 1.6002 1.6002)
					(clearance 0)
				)
				(layer "B.Cu"
					(shape rect)
					(size 1.6002 1.6002)
					(clearance 0)
				)
			)
		)
		(pad "2" thru_hole circle
			(at 0 2.999994 90)
			(size 1.6002 1.6002)
			(drill 1.0922)
			(layers "*.Cu" "*.Mask")
			(remove_unused_layers no)
			(net "GND")
			(clearance 0)
		)
		(zone
			(layers "F.Cu" "B.Cu" "In1.Cu" "In2.Cu" "In3.Cu" "In4.Cu" "In5.Cu" "In6.Cu")
			(hatch none 0.5)
			(connect_pads
				(clearance 0)
			)
			(min_thickness 0.25)
			(keepout
				(tracks not_allowed)
				(vias allowed)
				(pads allowed)
				(copperpour not_allowed)
				(footprints allowed)
			)
			(placement
				(enabled no)
				(sheetname "")
			)
			(fill
				(thermal_gap 0.5)
				(thermal_bridge_width 0.5)
				(island_removal_mode 0)
			)
			(polygon
				(pts
					(arc
						(start 8.806942 -480.172014)
						(mid 6.673342 -480.172014)
						(end 8.806942 -480.172014)
					)
				)
			)
		)
		(zone
			(layers "F.Cu" "B.Cu" "In1.Cu" "In2.Cu" "In3.Cu" "In4.Cu" "In5.Cu" "In6.Cu")
			(hatch none 0.5)
			(connect_pads
				(clearance 0)
			)
			(min_thickness 0.25)
			(keepout
				(tracks not_allowed)
				(vias allowed)
				(pads allowed)
				(copperpour not_allowed)
				(footprints allowed)
			)
			(placement
				(enabled no)
				(sheetname "")
			)
			(fill
				(thermal_gap 0.5)
				(thermal_bridge_width 0.5)
				(island_removal_mode 0)
			)
			(polygon
				(pts
					(arc
						(start 8.806942 -471.172032)
						(mid 6.673342 -471.172032)
						(end 8.806942 -471.172032)
					)
				)
			)
		)
	)
	(footprint ""
		(layer "F.Cu")
		(at 16.599916 -384.79984)
		(property "Reference" "H6"
			(at -6.4516 -7.127748 0)
			(unlocked yes)
			(layer "F.SilkS")
			(effects
				(font
					(size 0.7874 0.5842)
					(thickness 0.1524)
				)
				(justify left)
			)
		)
		(property "Value" ""
			(at 0 0 0)
			(layer "F.Fab")
			(effects
				(font
					(size 1.27 1.27)
				)
			)
		)
		(duplicate_pad_numbers_are_jumpers no)
		(fp_circle
			(center 0 0)
			(end 7.999984 0)
			(stroke
				(width 0.1524)
				(type default)
			)
			(fill no)
			(layer "F.SilkS")
		)
		(fp_circle
			(center 0 0)
			(end 14.7066 0)
			(stroke
				(width 0.1524)
				(type default)
			)
			(fill no)
			(layer "B.SilkS")
		)
		(fp_poly
			(pts
				(arc
					(start 0 5.0038)
					(mid 0 -5.0038)
					(end 0 5.0038)
				)
			)
			(stroke
				(width 0)
				(type default)
			)
			(fill no)
			(layer "F.CrtYd")
		)
		(pad "" np_thru_hole circle
			(at 0 0)
			(size 4.0132 4.0132)
			(drill 4.0132)
			(layers "*.Cu" "*.Mask")
			(clearance 0.381)
			(thermal_gap 0.381)
		)
		(pad "2" thru_hole circle
			(at 0 -3.50012)
			(size 0.762 0.762)
			(drill 0.5588)
			(layers "*.Cu" "*.Mask")
			(remove_unused_layers no)
			(net "GND")
			(clearance 0.1524)
			(thermal_gap 0.1524)
		)
		(pad "3" thru_hole circle
			(at -2.500122 -2.500122)
			(size 0.762 0.762)
			(drill 0.5588)
			(layers "*.Cu" "*.Mask")
			(remove_unused_layers no)
			(net "GND")
			(clearance 0.1524)
			(thermal_gap 0.1524)
		)
		(pad "4" thru_hole circle
			(at -3.50012 0)
			(size 0.762 0.762)
			(drill 0.5588)
			(layers "*.Cu" "*.Mask")
			(remove_unused_layers no)
			(net "GND")
			(clearance 0.1524)
			(thermal_gap 0.1524)
		)
		(pad "5" thru_hole circle
			(at -2.500122 2.500122)
			(size 0.762 0.762)
			(drill 0.5588)
			(layers "*.Cu" "*.Mask")
			(remove_unused_layers no)
			(net "GND")
			(clearance 0.1524)
			(thermal_gap 0.1524)
		)
		(pad "6" thru_hole circle
			(at 0 3.50012)
			(size 0.762 0.762)
			(drill 0.5588)
			(layers "*.Cu" "*.Mask")
			(remove_unused_layers no)
			(net "GND")
			(clearance 0.1524)
			(thermal_gap 0.1524)
		)
		(pad "7" thru_hole circle
			(at 2.500122 2.500122)
			(size 0.762 0.762)
			(drill 0.5588)
			(layers "*.Cu" "*.Mask")
			(remove_unused_layers no)
			(net "GND")
			(clearance 0.1524)
			(thermal_gap 0.1524)
		)
		(pad "8" thru_hole circle
			(at 3.50012 0)
			(size 0.762 0.762)
			(drill 0.5588)
			(layers "*.Cu" "*.Mask")
			(remove_unused_layers no)
			(net "GND")
			(clearance 0.1524)
			(thermal_gap 0.1524)
		)
		(pad "9" thru_hole circle
			(at 2.500122 -2.500122)
			(size 0.762 0.762)
			(drill 0.5588)
			(layers "*.Cu" "*.Mask")
			(remove_unused_layers no)
			(net "GND")
			(clearance 0.1524)
			(thermal_gap 0.1524)
		)
		(zone
			(layer "F.Cu")
			(hatch none 0.5)
			(connect_pads
				(clearance 0)
			)
			(min_thickness 0.25)
			(keepout
				(tracks not_allowed)
				(vias allowed)
				(pads allowed)
				(copperpour not_allowed)
				(footprints allowed)
			)
			(placement
				(enabled no)
				(sheetname "")
			)
			(fill
				(thermal_gap 0.5)
				(thermal_bridge_width 0.5)
				(island_removal_mode 0)
			)
			(polygon
				(pts
					(arc
						(start 16.599916 -392.80084)
						(mid 8.598916 -384.79984)
						(end 16.599916 -376.79884)
					)
					(arc
						(start 16.599916 -376.79884)
						(mid 18.035016 -378.23394)
						(end 16.599916 -379.66904)
					)
					(arc
						(start 16.599916 -379.66904)
						(mid 11.469116 -384.79984)
						(end 16.599916 -389.93064)
					)
					(arc
						(start 16.599916 -389.93064)
						(mid 18.035016 -391.36574)
						(end 16.599916 -392.80084)
					)
				)
			)
		)
		(zone
			(layer "F.Cu")
			(hatch none 0.5)
			(connect_pads
				(clearance 0)
			)
			(min_thickness 0.25)
			(keepout
				(tracks not_allowed)
				(vias allowed)
				(pads allowed)
				(copperpour not_allowed)
				(footprints allowed)
			)
			(placement
				(enabled no)
				(sheetname "")
			)
			(fill
				(thermal_gap 0.5)
				(thermal_bridge_width 0.5)
				(island_removal_mode 0)
			)
			(polygon
				(pts
					(arc
						(start 16.599916 -392.80084)
						(mid 24.600916 -384.79984)
						(end 16.599916 -376.79884)
					)
					(arc
						(start 16.599916 -376.79884)
						(mid 15.164816 -378.23394)
						(end 16.599916 -379.66904)
					)
					(arc
						(start 16.599916 -379.66904)
						(mid 21.730716 -384.79984)
						(end 16.599916 -389.93064)
					)
					(arc
						(start 16.599916 -389.93064)
						(mid 15.164816 -391.36574)
						(end 16.599916 -392.80084)
					)
				)
			)
		)
		(zone
			(layers "F.Cu" "B.Cu" "In1.Cu" "In2.Cu" "In3.Cu" "In4.Cu" "In5.Cu" "In6.Cu")
			(hatch none 0.5)
			(connect_pads
				(clearance 0)
			)
			(min_thickness 0.25)
			(keepout
				(tracks not_allowed)
				(vias allowed)
				(pads allowed)
				(copperpour not_allowed)
				(footprints allowed)
			)
			(placement
				(enabled no)
				(sheetname "")
			)
			(fill
				(thermal_gap 0.5)
				(thermal_bridge_width 0.5)
				(island_removal_mode 0)
			)
			(polygon
				(pts
					(arc
						(start 16.599916 -382.28778)
						(mid 16.599916 -387.3119)
						(end 16.599916 -382.28778)
					)
				)
			)
		)
	)
	(footprint ""
		(layer "F.Cu")
		(at 39.436802 -287.17748 90)
		(property "Reference" "R122"
			(at -3.06705 1.662938 90)
			(unlocked yes)
			(layer "F.SilkS")
			(effects
				(font
					(size 0.7874 0.5842)
					(thickness 0.1524)
				)
				(justify left)
			)
		)
		(property "Value" ""
			(at 0 0 90)
			(layer "F.Fab")
			(effects
				(font
					(size 1.27 1.27)
				)
			)
		)
		(duplicate_pad_numbers_are_jumpers no)
		(fp_line
			(start 0.7874 -0.4064)
			(end 0.7874 0.4064)
			(stroke
				(width 0.1524)
				(type default)
			)
			(layer "F.SilkS")
		)
		(fp_line
			(start -0.7874 -0.4064)
			(end 0.7874 -0.4064)
			(stroke
				(width 0.1524)
				(type default)
			)
			(layer "F.SilkS")
		)
		(fp_line
			(start 0.7874 0.4064)
			(end -0.7874 0.4064)
			(stroke
				(width 0.1524)
				(type default)
			)
			(layer "F.SilkS")
		)
		(fp_line
			(start -0.7874 0.4064)
			(end -0.7874 -0.4064)
			(stroke
				(width 0.1524)
				(type default)
			)
			(layer "F.SilkS")
		)
		(fp_poly
			(pts
				(xy -0.508 0.2794) (xy -0.508 0.2286) (xy -0.635 0.2286) (xy -0.635 -0.254) (xy -0.5334 -0.254)
				(xy -0.5334 -0.2794) (xy 0.5334 -0.2794) (xy 0.5334 -0.254) (xy 0.635 -0.254) (xy 0.635 0.254) (xy 0.5334 0.254)
				(xy 0.5334 0.2794)
			)
			(stroke
				(width 0)
				(type default)
			)
			(fill no)
			(layer "F.CrtYd")
		)
		(pad "1" smd rect
			(at 0.40005 0 90)
			(size 0.4572 0.508)
			(layers "F.Cu" "F.Mask" "F.Paste")
			(net "PSU4_REMOTE_P")
		)
		(pad "2" smd rect
			(at -0.40005 0 90)
			(size 0.4572 0.508)
			(layers "F.Cu" "F.Mask" "F.Paste")
			(net "PSU4_REMOTE_R2_P")
		)
	)
	(footprint ""
		(layer "F.Cu")
		(at 25.931622 -100.590096)
		(property "Reference" "R67"
			(at -4.080256 -0.075692 0)
			(unlocked yes)
			(layer "F.SilkS")
			(effects
				(font
					(size 0.7874 0.5842)
					(thickness 0.1524)
				)
				(justify left)
			)
		)
		(property "Value" ""
			(at 0 0 0)
			(layer "F.Fab")
			(effects
				(font
					(size 1.27 1.27)
				)
			)
		)
		(duplicate_pad_numbers_are_jumpers no)
		(fp_line
			(start -0.7874 -0.4064)
			(end 0.7874 -0.4064)
			(stroke
				(width 0.1524)
				(type default)
			)
			(layer "F.SilkS")
		)
		(fp_line
			(start -0.7874 0.4064)
			(end -0.7874 -0.4064)
			(stroke
				(width 0.1524)
				(type default)
			)
			(layer "F.SilkS")
		)
		(fp_line
			(start 0.7874 -0.4064)
			(end 0.7874 0.4064)
			(stroke
				(width 0.1524)
				(type default)
			)
			(layer "F.SilkS")
		)
		(fp_line
			(start 0.7874 0.4064)
			(end -0.7874 0.4064)
			(stroke
				(width 0.1524)
				(type default)
			)
			(layer "F.SilkS")
		)
		(fp_poly
			(pts
				(xy -0.508 0.2794) (xy -0.508 0.2286) (xy -0.635 0.2286) (xy -0.635 -0.254) (xy -0.5334 -0.254)
				(xy -0.5334 -0.2794) (xy 0.5334 -0.2794) (xy 0.5334 -0.254) (xy 0.635 -0.254) (xy 0.635 0.254) (xy 0.5334 0.254)
				(xy 0.5334 0.2794)
			)
			(stroke
				(width 0)
				(type default)
			)
			(fill no)
			(layer "F.CrtYd")
		)
		(pad "1" smd rect
			(at 0.40005 0)
			(size 0.4572 0.508)
			(layers "F.Cu" "F.Mask" "F.Paste")
			(net "PSU2_PS_KILL")
		)
		(pad "2" smd rect
			(at -0.40005 0)
			(size 0.4572 0.508)
			(layers "F.Cu" "F.Mask" "F.Paste")
			(net "GND")
		)
	)
	(footprint ""
		(layer "F.Cu")
		(at 21.471382 -177.804572 90)
		(property "Reference" "R159"
			(at -1.067054 -4.480814 90)
			(unlocked yes)
			(layer "F.SilkS")
			(effects
				(font
					(size 0.7874 0.5842)
					(thickness 0.1524)
				)
				(justify left)
			)
		)
		(property "Value" ""
			(at 0 0 90)
			(layer "F.Fab")
			(effects
				(font
					(size 1.27 1.27)
				)
			)
		)
		(duplicate_pad_numbers_are_jumpers no)
		(fp_line
			(start 0.7874 -0.4064)
			(end 0.7874 0.4064)
			(stroke
				(width 0.1524)
				(type default)
			)
			(layer "F.SilkS")
		)
		(fp_line
			(start -0.7874 -0.4064)
			(end 0.7874 -0.4064)
			(stroke
				(width 0.1524)
				(type default)
			)
			(layer "F.SilkS")
		)
		(fp_line
			(start 0.7874 0.4064)
			(end -0.7874 0.4064)
			(stroke
				(width 0.1524)
				(type default)
			)
			(layer "F.SilkS")
		)
		(fp_line
			(start -0.7874 0.4064)
			(end -0.7874 -0.4064)
			(stroke
				(width 0.1524)
				(type default)
			)
			(layer "F.SilkS")
		)
		(fp_poly
			(pts
				(xy -0.508 0.2794) (xy -0.508 0.2286) (xy -0.635 0.2286) (xy -0.635 -0.254) (xy -0.5334 -0.254)
				(xy -0.5334 -0.2794) (xy 0.5334 -0.2794) (xy 0.5334 -0.254) (xy 0.635 -0.254) (xy 0.635 0.254) (xy 0.5334 0.254)
				(xy 0.5334 0.2794)
			)
			(stroke
				(width 0)
				(type default)
			)
			(fill no)
			(layer "F.CrtYd")
		)
		(pad "1" smd rect
			(at 0.40005 0 90)
			(size 0.4572 0.508)
			(layers "F.Cu" "F.Mask" "F.Paste")
			(net "N42263600")
		)
		(pad "2" smd rect
			(at -0.40005 0 90)
			(size 0.4572 0.508)
			(layers "F.Cu" "F.Mask" "F.Paste")
			(net "N42264085")
		)
	)
	(footprint ""
		(layer "F.Cu")
		(at 27.28468 -4.025138)
		(property "Reference" "R65"
			(at -1.676146 2.569972 0)
			(unlocked yes)
			(layer "F.SilkS")
			(effects
				(font
					(size 0.7874 0.5842)
					(thickness 0.1524)
				)
				(justify left)
			)
		)
		(property "Value" ""
			(at 0 0 0)
			(layer "F.Fab")
			(effects
				(font
					(size 1.27 1.27)
				)
			)
		)
		(duplicate_pad_numbers_are_jumpers no)
		(fp_line
			(start -0.7874 -0.4064)
			(end 0.7874 -0.4064)
			(stroke
				(width 0.1524)
				(type default)
			)
			(layer "F.SilkS")
		)
		(fp_line
			(start -0.7874 0.4064)
			(end -0.7874 -0.4064)
			(stroke
				(width 0.1524)
				(type default)
			)
			(layer "F.SilkS")
		)
		(fp_line
			(start 0.7874 -0.4064)
			(end 0.7874 0.4064)
			(stroke
				(width 0.1524)
				(type default)
			)
			(layer "F.SilkS")
		)
		(fp_line
			(start 0.7874 0.4064)
			(end -0.7874 0.4064)
			(stroke
				(width 0.1524)
				(type default)
			)
			(layer "F.SilkS")
		)
		(fp_poly
			(pts
				(xy -0.508 0.2794) (xy -0.508 0.2286) (xy -0.635 0.2286) (xy -0.635 -0.254) (xy -0.5334 -0.254)
				(xy -0.5334 -0.2794) (xy 0.5334 -0.2794) (xy 0.5334 -0.254) (xy 0.635 -0.254) (xy 0.635 0.254) (xy 0.5334 0.254)
				(xy 0.5334 0.2794)
			)
			(stroke
				(width 0)
				(type default)
			)
			(fill no)
			(layer "F.CrtYd")
		)
		(pad "1" smd rect
			(at 0.40005 0)
			(size 0.4572 0.508)
			(layers "F.Cu" "F.Mask" "F.Paste")
			(net "PSU1_RESET")
		)
		(pad "2" smd rect
			(at -0.40005 0)
			(size 0.4572 0.508)
			(layers "F.Cu" "F.Mask" "F.Paste")
			(net "GND")
		)
	)
	(footprint ""
		(layer "F.Cu")
		(at 39.458392 -110.374176 90)
		(property "Reference" "R114"
			(at -2.70256 2.149348 90)
			(unlocked yes)
			(layer "F.SilkS")
			(effects
				(font
					(size 0.7874 0.5842)
					(thickness 0.1524)
				)
				(justify left)
			)
		)
		(property "Value" ""
			(at 0 0 90)
			(layer "F.Fab")
			(effects
				(font
					(size 1.27 1.27)
				)
			)
		)
		(duplicate_pad_numbers_are_jumpers no)
		(fp_line
			(start 0.7874 -0.4064)
			(end 0.7874 0.4064)
			(stroke
				(width 0.1524)
				(type default)
			)
			(layer "F.SilkS")
		)
		(fp_line
			(start -0.7874 -0.4064)
			(end 0.7874 -0.4064)
			(stroke
				(width 0.1524)
				(type default)
			)
			(layer "F.SilkS")
		)
		(fp_line
			(start 0.7874 0.4064)
			(end -0.7874 0.4064)
			(stroke
				(width 0.1524)
				(type default)
			)
			(layer "F.SilkS")
		)
		(fp_line
			(start -0.7874 0.4064)
			(end -0.7874 -0.4064)
			(stroke
				(width 0.1524)
				(type default)
			)
			(layer "F.SilkS")
		)
		(fp_poly
			(pts
				(xy -0.508 0.2794) (xy -0.508 0.2286) (xy -0.635 0.2286) (xy -0.635 -0.254) (xy -0.5334 -0.254)
				(xy -0.5334 -0.2794) (xy 0.5334 -0.2794) (xy 0.5334 -0.254) (xy 0.635 -0.254) (xy 0.635 0.254) (xy 0.5334 0.254)
				(xy 0.5334 0.2794)
			)
			(stroke
				(width 0)
				(type default)
			)
			(fill no)
			(layer "F.CrtYd")
		)
		(pad "1" smd rect
			(at 0.40005 0 90)
			(size 0.4572 0.508)
			(layers "F.Cu" "F.Mask" "F.Paste")
			(net "PSU2_REMOTE_P")
		)
		(pad "2" smd rect
			(at -0.40005 0 90)
			(size 0.4572 0.508)
			(layers "F.Cu" "F.Mask" "F.Paste")
			(net "PSU2_REMOTE_R2_P")
		)
	)
	(footprint ""
		(layer "F.Cu")
		(at 22.510496 -446.145158 -90)
		(property "Reference" "R157"
			(at 8.648192 -1.43637 90)
			(unlocked yes)
			(layer "F.SilkS")
			(effects
				(font
					(size 0.7874 0.5842)
					(thickness 0.1524)
				)
				(justify left)
			)
		)
		(property "Value" ""
			(at 0 0 270)
			(layer "F.Fab")
			(effects
				(font
					(size 1.27 1.27)
				)
			)
		)
		(duplicate_pad_numbers_are_jumpers no)
		(fp_line
			(start -0.7874 0.4064)
			(end -0.7874 -0.4064)
			(stroke
				(width 0.1524)
				(type default)
			)
			(layer "F.SilkS")
		)
		(fp_line
			(start 0.7874 0.4064)
			(end -0.7874 0.4064)
			(stroke
				(width 0.1524)
				(type default)
			)
			(layer "F.SilkS")
		)
		(fp_line
			(start -0.7874 -0.4064)
			(end 0.7874 -0.4064)
			(stroke
				(width 0.1524)
				(type default)
			)
			(layer "F.SilkS")
		)
		(fp_line
			(start 0.7874 -0.4064)
			(end 0.7874 0.4064)
			(stroke
				(width 0.1524)
				(type default)
			)
			(layer "F.SilkS")
		)
		(fp_poly
			(pts
				(xy -0.508 0.2794) (xy -0.508 0.2286) (xy -0.635 0.2286) (xy -0.635 -0.254) (xy -0.5334 -0.254)
				(xy -0.5334 -0.2794) (xy 0.5334 -0.2794) (xy 0.5334 -0.254) (xy 0.635 -0.254) (xy 0.635 0.254) (xy 0.5334 0.254)
				(xy 0.5334 0.2794)
			)
			(stroke
				(width 0)
				(type default)
			)
			(fill no)
			(layer "F.CrtYd")
		)
		(pad "1" smd rect
			(at 0.40005 0 270)
			(size 0.4572 0.508)
			(layers "F.Cu" "F.Mask" "F.Paste")
			(net "N42242090")
		)
		(pad "2" smd rect
			(at -0.40005 0 270)
			(size 0.4572 0.508)
			(layers "F.Cu" "F.Mask" "F.Paste")
			(net "GND")
		)
	)
	(footprint ""
		(layer "F.Cu")
		(at 66.891916 -29.351986 180)
		(property "Reference" "R112"
			(at 1.430782 -1.257046 0)
			(unlocked yes)
			(layer "F.SilkS")
			(effects
				(font
					(size 0.7874 0.5842)
					(thickness 0.1524)
				)
				(justify left)
			)
		)
		(property "Value" ""
			(at 0 0 180)
			(layer "F.Fab")
			(effects
				(font
					(size 1.27 1.27)
				)
			)
		)
		(duplicate_pad_numbers_are_jumpers no)
		(fp_line
			(start 0.7874 0.4064)
			(end -0.7874 0.4064)
			(stroke
				(width 0.1524)
				(type default)
			)
			(layer "F.SilkS")
		)
		(fp_line
			(start 0.7874 -0.4064)
			(end 0.7874 0.4064)
			(stroke
				(width 0.1524)
				(type default)
			)
			(layer "F.SilkS")
		)
		(fp_line
			(start -0.7874 0.4064)
			(end -0.7874 -0.4064)
			(stroke
				(width 0.1524)
				(type default)
			)
			(layer "F.SilkS")
		)
		(fp_line
			(start -0.7874 -0.4064)
			(end 0.7874 -0.4064)
			(stroke
				(width 0.1524)
				(type default)
			)
			(layer "F.SilkS")
		)
		(fp_poly
			(pts
				(xy -0.508 0.2794) (xy -0.508 0.2286) (xy -0.635 0.2286) (xy -0.635 -0.254) (xy -0.5334 -0.254)
				(xy -0.5334 -0.2794) (xy 0.5334 -0.2794) (xy 0.5334 -0.254) (xy 0.635 -0.254) (xy 0.635 0.254) (xy 0.5334 0.254)
				(xy 0.5334 0.2794)
			)
			(stroke
				(width 0)
				(type default)
			)
			(fill no)
			(layer "F.CrtYd")
		)
		(pad "1" smd rect
			(at 0.40005 0 180)
			(size 0.4572 0.508)
			(layers "F.Cu" "F.Mask" "F.Paste")
			(net "PSU1_REMOTE_R2_N")
		)
		(pad "2" smd rect
			(at -0.40005 0 180)
			(size 0.4572 0.508)
			(layers "F.Cu" "F.Mask" "F.Paste")
			(net "GND")
		)
	)
	(footprint ""
		(layer "F.Cu")
		(at 27.29357 -280.04389)
		(property "Reference" "R137"
			(at -3.851402 0.175768 0)
			(unlocked yes)
			(layer "F.SilkS")
			(effects
				(font
					(size 0.7874 0.5842)
					(thickness 0.1524)
				)
				(justify left)
			)
		)
		(property "Value" ""
			(at 0 0 0)
			(layer "F.Fab")
			(effects
				(font
					(size 1.27 1.27)
				)
			)
		)
		(duplicate_pad_numbers_are_jumpers no)
		(fp_line
			(start -0.7874 -0.4064)
			(end 0.7874 -0.4064)
			(stroke
				(width 0.1524)
				(type default)
			)
			(layer "F.SilkS")
		)
		(fp_line
			(start -0.7874 0.4064)
			(end -0.7874 -0.4064)
			(stroke
				(width 0.1524)
				(type default)
			)
			(layer "F.SilkS")
		)
		(fp_line
			(start 0.7874 -0.4064)
			(end 0.7874 0.4064)
			(stroke
				(width 0.1524)
				(type default)
			)
			(layer "F.SilkS")
		)
		(fp_line
			(start 0.7874 0.4064)
			(end -0.7874 0.4064)
			(stroke
				(width 0.1524)
				(type default)
			)
			(layer "F.SilkS")
		)
		(fp_poly
			(pts
				(xy -0.508 0.2794) (xy -0.508 0.2286) (xy -0.635 0.2286) (xy -0.635 -0.254) (xy -0.5334 -0.254)
				(xy -0.5334 -0.2794) (xy 0.5334 -0.2794) (xy 0.5334 -0.254) (xy 0.635 -0.254) (xy 0.635 0.254) (xy 0.5334 0.254)
				(xy 0.5334 0.2794)
			)
			(stroke
				(width 0)
				(type default)
			)
			(fill no)
			(layer "F.CrtYd")
		)
		(pad "1" smd rect
			(at 0.40005 0)
			(size 0.4572 0.508)
			(layers "F.Cu" "F.Mask" "F.Paste")
			(net "PSU4_CSAHRE")
		)
		(pad "2" smd rect
			(at -0.40005 0)
			(size 0.4572 0.508)
			(layers "F.Cu" "F.Mask" "F.Paste")
			(net "PSU_CSAHRE")
		)
	)
	(footprint ""
		(layer "F.Cu")
		(at 46.36516 -256.467102 180)
		(property "Reference" "R108"
			(at -1.033272 -0.247396 0)
			(unlocked yes)
			(layer "F.SilkS")
			(effects
				(font
					(size 0.7874 0.5842)
					(thickness 0.1524)
				)
				(justify left)
			)
		)
		(property "Value" ""
			(at 0 0 180)
			(layer "F.Fab")
			(effects
				(font
					(size 1.27 1.27)
				)
			)
		)
		(duplicate_pad_numbers_are_jumpers no)
		(fp_line
			(start 0.7874 0.4064)
			(end -0.7874 0.4064)
			(stroke
				(width 0.1524)
				(type default)
			)
			(layer "F.SilkS")
		)
		(fp_line
			(start 0.7874 -0.4064)
			(end 0.7874 0.4064)
			(stroke
				(width 0.1524)
				(type default)
			)
			(layer "F.SilkS")
		)
		(fp_line
			(start -0.7874 0.4064)
			(end -0.7874 -0.4064)
			(stroke
				(width 0.1524)
				(type default)
			)
			(layer "F.SilkS")
		)
		(fp_line
			(start -0.7874 -0.4064)
			(end 0.7874 -0.4064)
			(stroke
				(width 0.1524)
				(type default)
			)
			(layer "F.SilkS")
		)
		(fp_poly
			(pts
				(xy -0.508 0.2794) (xy -0.508 0.2286) (xy -0.635 0.2286) (xy -0.635 -0.254) (xy -0.5334 -0.254)
				(xy -0.5334 -0.2794) (xy 0.5334 -0.2794) (xy 0.5334 -0.254) (xy 0.635 -0.254) (xy 0.635 0.254) (xy 0.5334 0.254)
				(xy 0.5334 0.2794)
			)
			(stroke
				(width 0)
				(type default)
			)
			(fill no)
			(layer "F.CrtYd")
		)
		(pad "1" smd rect
			(at 0.40005 0 180)
			(size 0.4572 0.508)
			(layers "F.Cu" "F.Mask" "F.Paste")
			(net "PSU4_REMOTE_R_P")
		)
		(pad "2" smd rect
			(at -0.40005 0 180)
			(size 0.4572 0.508)
			(layers "F.Cu" "F.Mask" "F.Paste")
			(net "P12V")
		)
	)
	(footprint ""
		(layer "F.Cu")
		(at 77.999844 -121.19991)
		(property "Reference" "H9"
			(at -9.877298 -3.685032 0)
			(unlocked yes)
			(layer "F.SilkS")
			(effects
				(font
					(size 0.7874 0.5842)
					(thickness 0.1524)
				)
				(justify left)
			)
		)
		(property "Value" ""
			(at 0 0 0)
			(layer "F.Fab")
			(effects
				(font
					(size 1.27 1.27)
				)
			)
		)
		(duplicate_pad_numbers_are_jumpers no)
		(fp_circle
			(center 0 0)
			(end 7.999984 0)
			(stroke
				(width 0.1524)
				(type default)
			)
			(fill no)
			(layer "F.SilkS")
		)
		(fp_arc
			(start 10.063734 10.724134)
			(mid -13.496547 -5.843072)
			(end 14.7066 0)
			(stroke
				(width 0.1524)
				(type default)
			)
			(layer "B.SilkS")
		)
		(fp_arc
			(start 14.7066 0)
			(mid 13.809901 5.056557)
			(end 11.22934 9.496552)
			(stroke
				(width 0.1524)
				(type default)
			)
			(layer "B.SilkS")
		)
		(fp_poly
			(pts
				(arc
					(start 5.0038 0)
					(mid -5.0038 0)
					(end 5.0038 0)
				)
			)
			(stroke
				(width 0)
				(type default)
			)
			(fill no)
			(layer "F.CrtYd")
		)
		(pad "" np_thru_hole circle
			(at 0 0)
			(size 4.0132 4.0132)
			(drill 4.0132)
			(layers "*.Cu" "*.Mask")
			(clearance 0.381)
			(thermal_gap 0.381)
		)
		(pad "2" thru_hole circle
			(at 0 -3.50012)
			(size 0.762 0.762)
			(drill 0.5588)
			(layers "*.Cu" "*.Mask")
			(remove_unused_layers no)
			(net "GND")
			(clearance 0.1524)
			(thermal_gap 0.1524)
		)
		(pad "3" thru_hole circle
			(at -2.500122 -2.500122)
			(size 0.762 0.762)
			(drill 0.5588)
			(layers "*.Cu" "*.Mask")
			(remove_unused_layers no)
			(net "GND")
			(clearance 0.1524)
			(thermal_gap 0.1524)
		)
		(pad "4" thru_hole circle
			(at -3.50012 0)
			(size 0.762 0.762)
			(drill 0.5588)
			(layers "*.Cu" "*.Mask")
			(remove_unused_layers no)
			(net "GND")
			(clearance 0.1524)
			(thermal_gap 0.1524)
		)
		(pad "5" thru_hole circle
			(at -2.500122 2.500122)
			(size 0.762 0.762)
			(drill 0.5588)
			(layers "*.Cu" "*.Mask")
			(remove_unused_layers no)
			(net "GND")
			(clearance 0.1524)
			(thermal_gap 0.1524)
		)
		(pad "6" thru_hole circle
			(at 0 3.50012)
			(size 0.762 0.762)
			(drill 0.5588)
			(layers "*.Cu" "*.Mask")
			(remove_unused_layers no)
			(net "GND")
			(clearance 0.1524)
			(thermal_gap 0.1524)
		)
		(pad "7" thru_hole circle
			(at 2.500122 2.500122)
			(size 0.762 0.762)
			(drill 0.5588)
			(layers "*.Cu" "*.Mask")
			(remove_unused_layers no)
			(net "GND")
			(clearance 0.1524)
			(thermal_gap 0.1524)
		)
		(pad "8" thru_hole circle
			(at 3.50012 0)
			(size 0.762 0.762)
			(drill 0.5588)
			(layers "*.Cu" "*.Mask")
			(remove_unused_layers no)
			(net "GND")
			(clearance 0.1524)
			(thermal_gap 0.1524)
		)
		(pad "9" thru_hole circle
			(at 2.500122 -2.500122)
			(size 0.762 0.762)
			(drill 0.5588)
			(layers "*.Cu" "*.Mask")
			(remove_unused_layers no)
			(net "GND")
			(clearance 0.1524)
			(thermal_gap 0.1524)
		)
		(zone
			(layer "F.Cu")
			(hatch none 0.5)
			(connect_pads
				(clearance 0)
			)
			(min_thickness 0.25)
			(keepout
				(tracks not_allowed)
				(vias allowed)
				(pads allowed)
				(copperpour not_allowed)
				(footprints allowed)
			)
			(placement
				(enabled no)
				(sheetname "")
			)
			(fill
				(thermal_gap 0.5)
				(thermal_bridge_width 0.5)
				(island_removal_mode 0)
			)
			(polygon
				(pts
					(arc
						(start 77.999844 -129.20091)
						(mid 69.998844 -121.19991)
						(end 77.999844 -113.19891)
					)
					(arc
						(start 77.999844 -113.19891)
						(mid 79.434944 -114.63401)
						(end 77.999844 -116.06911)
					)
					(arc
						(start 77.999844 -116.06911)
						(mid 72.869044 -121.19991)
						(end 77.999844 -126.33071)
					)
					(arc
						(start 77.999844 -126.33071)
						(mid 79.434944 -127.76581)
						(end 77.999844 -129.20091)
					)
				)
			)
		)
		(zone
			(layer "F.Cu")
			(hatch none 0.5)
			(connect_pads
				(clearance 0)
			)
			(min_thickness 0.25)
			(keepout
				(tracks not_allowed)
				(vias allowed)
				(pads allowed)
				(copperpour not_allowed)
				(footprints allowed)
			)
			(placement
				(enabled no)
				(sheetname "")
			)
			(fill
				(thermal_gap 0.5)
				(thermal_bridge_width 0.5)
				(island_removal_mode 0)
			)
			(polygon
				(pts
					(arc
						(start 77.999844 -129.20091)
						(mid 86.000844 -121.19991)
						(end 77.999844 -113.19891)
					)
					(arc
						(start 77.999844 -113.19891)
						(mid 76.564744 -114.63401)
						(end 77.999844 -116.06911)
					)
					(arc
						(start 77.999844 -116.06911)
						(mid 83.130644 -121.19991)
						(end 77.999844 -126.33071)
					)
					(arc
						(start 77.999844 -126.33071)
						(mid 76.564744 -127.76581)
						(end 77.999844 -129.20091)
					)
				)
			)
		)
		(zone
			(layers "F.Cu" "B.Cu" "In1.Cu" "In2.Cu" "In3.Cu" "In4.Cu" "In5.Cu" "In6.Cu")
			(hatch none 0.5)
			(connect_pads
				(clearance 0)
			)
			(min_thickness 0.25)
			(keepout
				(tracks not_allowed)
				(vias allowed)
				(pads allowed)
				(copperpour not_allowed)
				(footprints allowed)
			)
			(placement
				(enabled no)
				(sheetname "")
			)
			(fill
				(thermal_gap 0.5)
				(thermal_bridge_width 0.5)
				(island_removal_mode 0)
			)
			(polygon
				(pts
					(arc
						(start 80.511904 -121.19991)
						(mid 75.487784 -121.19991)
						(end 80.511904 -121.19991)
					)
				)
			)
		)
	)
	(footprint ""
		(layer "F.Cu")
		(at 72.81291 -108.56976 -90)
		(property "Reference" "C16"
			(at -2.68224 0.11684 90)
			(unlocked yes)
			(layer "F.SilkS")
			(effects
				(font
					(size 0.7874 0.5842)
					(thickness 0.1524)
				)
				(justify left)
			)
		)
		(property "Value" ""
			(at 0 0 270)
			(layer "F.Fab")
			(effects
				(font
					(size 1.27 1.27)
				)
			)
		)
		(duplicate_pad_numbers_are_jumpers no)
		(fp_line
			(start -0.7874 0.4064)
			(end -0.7874 -0.4064)
			(stroke
				(width 0.1524)
				(type default)
			)
			(layer "F.SilkS")
		)
		(fp_line
			(start 0.7874 0.4064)
			(end -0.7874 0.4064)
			(stroke
				(width 0.1524)
				(type default)
			)
			(layer "F.SilkS")
		)
		(fp_line
			(start 0 0.381)
			(end 0 -0.381)
			(stroke
				(width 0.1524)
				(type default)
			)
			(layer "F.SilkS")
		)
		(fp_line
			(start -0.7874 -0.4064)
			(end 0.7874 -0.4064)
			(stroke
				(width 0.1524)
				(type default)
			)
			(layer "F.SilkS")
		)
		(fp_line
			(start 0.7874 -0.4064)
			(end 0.7874 0.4064)
			(stroke
				(width 0.1524)
				(type default)
			)
			(layer "F.SilkS")
		)
		(fp_poly
			(pts
				(xy -0.5334 0.254) (xy -0.635 0.254) (xy -0.635 0.2286) (xy -0.635 -0.254) (xy -0.5334 -0.254) (xy -0.5334 -0.2794)
				(xy 0.5334 -0.2794) (xy 0.5334 -0.254) (xy 0.635 -0.254) (xy 0.635 0.254) (xy 0.5334 0.254) (xy 0.5334 0.2794)
				(xy -0.508 0.2794) (xy -0.5334 0.2794)
			)
			(stroke
				(width 0)
				(type default)
			)
			(fill no)
			(layer "F.CrtYd")
		)
		(pad "1" smd rect
			(at 0.40005 0 270)
			(size 0.4572 0.508)
			(layers "F.Cu" "F.Mask" "F.Paste")
			(net "P12V")
		)
		(pad "2" smd rect
			(at -0.40005 0 270)
			(size 0.4572 0.508)
			(layers "F.Cu" "F.Mask" "F.Paste")
			(net "GND")
		)
	)
	(footprint ""
		(layer "F.Cu")
		(at 4.059936 -145.974308 -90)
		(property "Reference" "R149"
			(at 1.193292 -1.277366 90)
			(unlocked yes)
			(layer "F.SilkS")
			(effects
				(font
					(size 0.7874 0.5842)
					(thickness 0.1524)
				)
				(justify left)
			)
		)
		(property "Value" ""
			(at 0 0 270)
			(layer "F.Fab")
			(effects
				(font
					(size 1.27 1.27)
				)
			)
		)
		(duplicate_pad_numbers_are_jumpers no)
		(fp_line
			(start -0.7874 0.4064)
			(end -0.7874 -0.4064)
			(stroke
				(width 0.1524)
				(type default)
			)
			(layer "F.SilkS")
		)
		(fp_line
			(start 0.7874 0.4064)
			(end -0.7874 0.4064)
			(stroke
				(width 0.1524)
				(type default)
			)
			(layer "F.SilkS")
		)
		(fp_line
			(start -0.7874 -0.4064)
			(end 0.7874 -0.4064)
			(stroke
				(width 0.1524)
				(type default)
			)
			(layer "F.SilkS")
		)
		(fp_line
			(start 0.7874 -0.4064)
			(end 0.7874 0.4064)
			(stroke
				(width 0.1524)
				(type default)
			)
			(layer "F.SilkS")
		)
		(fp_poly
			(pts
				(xy -0.508 0.2794) (xy -0.508 0.2286) (xy -0.635 0.2286) (xy -0.635 -0.254) (xy -0.5334 -0.254)
				(xy -0.5334 -0.2794) (xy 0.5334 -0.2794) (xy 0.5334 -0.254) (xy 0.635 -0.254) (xy 0.635 0.254) (xy 0.5334 0.254)
				(xy 0.5334 0.2794)
			)
			(stroke
				(width 0)
				(type default)
			)
			(fill no)
			(layer "F.CrtYd")
		)
		(pad "1" smd rect
			(at 0.40005 0 270)
			(size 0.4572 0.508)
			(layers "F.Cu" "F.Mask" "F.Paste")
			(net "N42126764")
		)
		(pad "2" smd rect
			(at -0.40005 0 270)
			(size 0.4572 0.508)
			(layers "F.Cu" "F.Mask" "F.Paste")
			(net "GND")
		)
	)
	(footprint ""
		(layer "F.Cu")
		(at 39.437056 -287.977326 -90)
		(property "Reference" "R106"
			(at -1.168146 -0.000762 90)
			(unlocked yes)
			(layer "F.SilkS")
			(effects
				(font
					(size 0.7874 0.5842)
					(thickness 0.1524)
				)
				(justify left)
			)
		)
		(property "Value" ""
			(at 0 0 270)
			(layer "F.Fab")
			(effects
				(font
					(size 1.27 1.27)
				)
			)
		)
		(duplicate_pad_numbers_are_jumpers no)
		(fp_line
			(start -0.7874 0.4064)
			(end -0.7874 -0.4064)
			(stroke
				(width 0.1524)
				(type default)
			)
			(layer "F.SilkS")
		)
		(fp_line
			(start 0.7874 0.4064)
			(end -0.7874 0.4064)
			(stroke
				(width 0.1524)
				(type default)
			)
			(layer "F.SilkS")
		)
		(fp_line
			(start -0.7874 -0.4064)
			(end 0.7874 -0.4064)
			(stroke
				(width 0.1524)
				(type default)
			)
			(layer "F.SilkS")
		)
		(fp_line
			(start 0.7874 -0.4064)
			(end 0.7874 0.4064)
			(stroke
				(width 0.1524)
				(type default)
			)
			(layer "F.SilkS")
		)
		(fp_poly
			(pts
				(xy -0.508 0.2794) (xy -0.508 0.2286) (xy -0.635 0.2286) (xy -0.635 -0.254) (xy -0.5334 -0.254)
				(xy -0.5334 -0.2794) (xy 0.5334 -0.2794) (xy 0.5334 -0.254) (xy 0.635 -0.254) (xy 0.635 0.254) (xy 0.5334 0.254)
				(xy 0.5334 0.2794)
			)
			(stroke
				(width 0)
				(type default)
			)
			(fill no)
			(layer "F.CrtYd")
		)
		(pad "1" smd rect
			(at 0.40005 0 270)
			(size 0.4572 0.508)
			(layers "F.Cu" "F.Mask" "F.Paste")
			(net "PSU4_REMOTE_P")
		)
		(pad "2" smd rect
			(at -0.40005 0 270)
			(size 0.4572 0.508)
			(layers "F.Cu" "F.Mask" "F.Paste")
			(net "PSU4_REMOTE_R_P")
		)
	)
	(footprint ""
		(layer "F.Cu")
		(at 26.102056 -276.12213)
		(property "Reference" "R75"
			(at -4.037838 -0.005334 0)
			(unlocked yes)
			(layer "F.SilkS")
			(effects
				(font
					(size 0.7874 0.5842)
					(thickness 0.1524)
				)
				(justify left)
			)
		)
		(property "Value" ""
			(at 0 0 0)
			(layer "F.Fab")
			(effects
				(font
					(size 1.27 1.27)
				)
			)
		)
		(duplicate_pad_numbers_are_jumpers no)
		(fp_line
			(start -0.7874 -0.4064)
			(end 0.7874 -0.4064)
			(stroke
				(width 0.1524)
				(type default)
			)
			(layer "F.SilkS")
		)
		(fp_line
			(start -0.7874 0.4064)
			(end -0.7874 -0.4064)
			(stroke
				(width 0.1524)
				(type default)
			)
			(layer "F.SilkS")
		)
		(fp_line
			(start 0.7874 -0.4064)
			(end 0.7874 0.4064)
			(stroke
				(width 0.1524)
				(type default)
			)
			(layer "F.SilkS")
		)
		(fp_line
			(start 0.7874 0.4064)
			(end -0.7874 0.4064)
			(stroke
				(width 0.1524)
				(type default)
			)
			(layer "F.SilkS")
		)
		(fp_poly
			(pts
				(xy -0.508 0.2794) (xy -0.508 0.2286) (xy -0.635 0.2286) (xy -0.635 -0.254) (xy -0.5334 -0.254)
				(xy -0.5334 -0.2794) (xy 0.5334 -0.2794) (xy 0.5334 -0.254) (xy 0.635 -0.254) (xy 0.635 0.254) (xy 0.5334 0.254)
				(xy 0.5334 0.2794)
			)
			(stroke
				(width 0)
				(type default)
			)
			(fill no)
			(layer "F.CrtYd")
		)
		(pad "1" smd rect
			(at 0.40005 0)
			(size 0.4572 0.508)
			(layers "F.Cu" "F.Mask" "F.Paste")
			(net "PSU4_PS_KILL")
		)
		(pad "2" smd rect
			(at -0.40005 0)
			(size 0.4572 0.508)
			(layers "F.Cu" "F.Mask" "F.Paste")
			(net "GND")
		)
	)
	(footprint ""
		(layer "F.Cu")
		(at 49.949354 -107.119928 180)
		(property "Reference" "CE5"
			(at -5.215128 0.67437 0)
			(unlocked yes)
			(layer "F.SilkS")
			(effects
				(font
					(size 0.7874 0.5842)
					(thickness 0.1524)
				)
				(justify left)
			)
		)
		(property "Value" ""
			(at 0 0 180)
			(layer "F.Fab")
			(effects
				(font
					(size 1.27 1.27)
				)
			)
		)
		(duplicate_pad_numbers_are_jumpers no)
		(fp_line
			(start 0 -4.2672)
			(end 0 4.2672)
			(stroke
				(width 0.1524)
				(type default)
			)
			(layer "F.SilkS")
		)
		(fp_circle
			(center 0 0)
			(end -4.2672 0)
			(stroke
				(width 0.1524)
				(type default)
			)
			(fill no)
			(layer "F.SilkS")
		)
		(fp_poly
			(pts
				(arc
					(start 0 -4.2672)
					(mid 4.2672 0)
					(end 0 4.2672)
				)
			)
			(stroke
				(width 0)
				(type default)
			)
			(fill yes)
			(layer "F.SilkS")
		)
		(fp_poly
			(pts
				(xy -2.5146 -0.762) (xy -0.9906 -0.762) (xy -0.9906 0.762) (xy -2.5146 0.762)
			)
			(stroke
				(width 0)
				(type default)
			)
			(fill no)
			(layer "B.CrtYd")
		)
		(fp_poly
			(pts
				(arc
					(start 1.7526 0.762)
					(mid 2.291415 -0.538815)
					(end 0.9906 0)
				)
				(arc
					(start 0.9906 0.0254)
					(mid 1.206345 0.546255)
					(end 1.7272 0.762)
				)
			)
			(stroke
				(width 0)
				(type default)
			)
			(fill no)
			(layer "B.CrtYd")
		)
		(fp_poly
			(pts
				(arc
					(start -4.2672 0)
					(mid 4.2672 0)
					(end -4.2672 0)
				)
			)
			(stroke
				(width 0)
				(type default)
			)
			(fill no)
			(layer "F.CrtYd")
		)
		(fp_circle
			(center 0 0)
			(end -4.2672 0)
			(stroke
				(width 0.1)
				(type default)
			)
			(fill no)
			(layer "F.Fab")
		)
		(fp_text user "+"
			(at -6.30936 -1.69926 180)
			(unlocked yes)
			(layer "F.SilkS")
			(effects
				(font
					(size 1.905 1.4224)
					(thickness 0.1524)
				)
				(justify left)
			)
		)
		(fp_text user "+"
			(at -5.6642 -0.34925 180)
			(unlocked yes)
			(layer "F.Fab")
			(effects
				(font
					(size 1.905 1.4224)
					(thickness 0.000001)
				)
				(justify left)
			)
		)
		(pad "1" thru_hole rect
			(at -1.75006 0 180)
			(size 1.397 1.397)
			(drill 0.9144)
			(layers "*.Cu" "*.Mask")
			(remove_unused_layers no)
			(net "P12V")
			(clearance 0.0127)
			(thermal_gap 0.0127)
			(padstack
				(mode front_inner_back)
				(layer "Inner"
					(shape circle)
					(size 1.397 1.397)
					(clearance 0.0127)
				)
				(layer "B.Cu"
					(shape rect)
					(size 1.397 1.397)
					(clearance 0.0127)
				)
			)
		)
		(pad "2" thru_hole circle
			(at 1.75006 0 180)
			(size 1.397 1.397)
			(drill 0.9144)
			(layers "*.Cu" "*.Mask")
			(remove_unused_layers no)
			(net "GND")
			(clearance 0.0127)
			(thermal_gap 0.0127)
		)
	)
	(footprint ""
		(layer "F.Cu")
		(at 73.687178 -259.450078 90)
		(property "Reference" "C47"
			(at -4.374134 0.10795 90)
			(unlocked yes)
			(layer "F.SilkS")
			(effects
				(font
					(size 0.7874 0.5842)
					(thickness 0.1524)
				)
				(justify left)
			)
		)
		(property "Value" ""
			(at 0 0 90)
			(layer "F.Fab")
			(effects
				(font
					(size 1.27 1.27)
				)
			)
		)
		(duplicate_pad_numbers_are_jumpers no)
		(fp_line
			(start 0.7874 -0.4064)
			(end 0.7874 0.4064)
			(stroke
				(width 0.1524)
				(type default)
			)
			(layer "F.SilkS")
		)
		(fp_line
			(start -0.7874 -0.4064)
			(end 0.7874 -0.4064)
			(stroke
				(width 0.1524)
				(type default)
			)
			(layer "F.SilkS")
		)
		(fp_line
			(start 0 0.381)
			(end 0 -0.381)
			(stroke
				(width 0.1524)
				(type default)
			)
			(layer "F.SilkS")
		)
		(fp_line
			(start 0.7874 0.4064)
			(end -0.7874 0.4064)
			(stroke
				(width 0.1524)
				(type default)
			)
			(layer "F.SilkS")
		)
		(fp_line
			(start -0.7874 0.4064)
			(end -0.7874 -0.4064)
			(stroke
				(width 0.1524)
				(type default)
			)
			(layer "F.SilkS")
		)
		(fp_poly
			(pts
				(xy -0.5334 0.254) (xy -0.635 0.254) (xy -0.635 0.2286) (xy -0.635 -0.254) (xy -0.5334 -0.254) (xy -0.5334 -0.2794)
				(xy 0.5334 -0.2794) (xy 0.5334 -0.254) (xy 0.635 -0.254) (xy 0.635 0.254) (xy 0.5334 0.254) (xy 0.5334 0.2794)
				(xy -0.508 0.2794) (xy -0.5334 0.2794)
			)
			(stroke
				(width 0)
				(type default)
			)
			(fill no)
			(layer "F.CrtYd")
		)
		(pad "1" smd rect
			(at 0.40005 0 90)
			(size 0.4572 0.508)
			(layers "F.Cu" "F.Mask" "F.Paste")
			(net "P12V")
		)
		(pad "2" smd rect
			(at -0.40005 0 90)
			(size 0.4572 0.508)
			(layers "F.Cu" "F.Mask" "F.Paste")
			(net "GND")
		)
	)
	(footprint ""
		(layer "F.Cu")
		(at 91.399868 -64.46012)
		(property "Reference" "H16"
			(at -5.1308 -5.23113 0)
			(unlocked yes)
			(layer "F.SilkS")
			(effects
				(font
					(size 0.7874 0.5842)
					(thickness 0.1524)
				)
				(justify left)
			)
		)
		(property "Value" ""
			(at 0 0 0)
			(layer "F.Fab")
			(effects
				(font
					(size 1.27 1.27)
				)
			)
		)
		(duplicate_pad_numbers_are_jumpers no)
		(fp_circle
			(center 0 0)
			(end 4.826 0)
			(stroke
				(width 0.1524)
				(type default)
			)
			(fill no)
			(layer "F.SilkS")
		)
		(fp_circle
			(center 0 0)
			(end 4.826 0)
			(stroke
				(width 0.1524)
				(type default)
			)
			(fill no)
			(layer "B.SilkS")
		)
		(fp_poly
			(pts
				(arc
					(start 0 4.0132)
					(mid 0 -4.0132)
					(end 0 4.0132)
				)
			)
			(stroke
				(width 0)
				(type default)
			)
			(fill no)
			(layer "F.CrtYd")
		)
		(pad "" np_thru_hole circle
			(at 0 0)
			(size 8.001 8.001)
			(drill 8.001)
			(layers "*.Cu" "*.Mask")
			(clearance 0.381)
			(thermal_gap 0.381)
		)
		(zone
			(layers "F.Cu" "B.Cu" "In1.Cu" "In2.Cu" "In3.Cu" "In4.Cu" "In5.Cu" "In6.Cu")
			(hatch none 0.5)
			(connect_pads
				(clearance 0)
			)
			(min_thickness 0.25)
			(keepout
				(tracks not_allowed)
				(vias allowed)
				(pads allowed)
				(copperpour not_allowed)
				(footprints allowed)
			)
			(placement
				(enabled no)
				(sheetname "")
			)
			(fill
				(thermal_gap 0.5)
				(thermal_bridge_width 0.5)
				(island_removal_mode 0)
			)
			(polygon
				(pts
					(arc
						(start 91.399868 -59.93892)
						(mid 91.399868 -68.98132)
						(end 91.399868 -59.93892)
					)
				)
			)
		)
	)
	(footprint ""
		(layer "F.Cu")
		(at 70.558152 -216.615772 90)
		(property "Reference" "C39"
			(at 1.151128 0.12319 90)
			(unlocked yes)
			(layer "F.SilkS")
			(effects
				(font
					(size 0.7874 0.5842)
					(thickness 0.1524)
				)
				(justify left)
			)
		)
		(property "Value" ""
			(at 0 0 90)
			(layer "F.Fab")
			(effects
				(font
					(size 1.27 1.27)
				)
			)
		)
		(duplicate_pad_numbers_are_jumpers no)
		(fp_line
			(start 0.7874 -0.4064)
			(end 0.7874 0.4064)
			(stroke
				(width 0.1524)
				(type default)
			)
			(layer "F.SilkS")
		)
		(fp_line
			(start -0.7874 -0.4064)
			(end 0.7874 -0.4064)
			(stroke
				(width 0.1524)
				(type default)
			)
			(layer "F.SilkS")
		)
		(fp_line
			(start 0 0.381)
			(end 0 -0.381)
			(stroke
				(width 0.1524)
				(type default)
			)
			(layer "F.SilkS")
		)
		(fp_line
			(start 0.7874 0.4064)
			(end -0.7874 0.4064)
			(stroke
				(width 0.1524)
				(type default)
			)
			(layer "F.SilkS")
		)
		(fp_line
			(start -0.7874 0.4064)
			(end -0.7874 -0.4064)
			(stroke
				(width 0.1524)
				(type default)
			)
			(layer "F.SilkS")
		)
		(fp_poly
			(pts
				(xy -0.5334 0.254) (xy -0.635 0.254) (xy -0.635 0.2286) (xy -0.635 -0.254) (xy -0.5334 -0.254) (xy -0.5334 -0.2794)
				(xy 0.5334 -0.2794) (xy 0.5334 -0.254) (xy 0.635 -0.254) (xy 0.635 0.254) (xy 0.5334 0.254) (xy 0.5334 0.2794)
				(xy -0.508 0.2794) (xy -0.5334 0.2794)
			)
			(stroke
				(width 0)
				(type default)
			)
			(fill no)
			(layer "F.CrtYd")
		)
		(pad "1" smd rect
			(at 0.40005 0 90)
			(size 0.4572 0.508)
			(layers "F.Cu" "F.Mask" "F.Paste")
			(net "P12V")
		)
		(pad "2" smd rect
			(at -0.40005 0 90)
			(size 0.4572 0.508)
			(layers "F.Cu" "F.Mask" "F.Paste")
			(net "GND")
		)
	)
	(footprint ""
		(layer "F.Cu")
		(at 13.265658 -340.460838 -90)
		(property "Reference" "R41"
			(at -1.347724 -0.199136 90)
			(unlocked yes)
			(layer "F.SilkS")
			(effects
				(font
					(size 0.7874 0.5842)
					(thickness 0.1524)
				)
				(justify left)
			)
		)
		(property "Value" ""
			(at 0 0 270)
			(layer "F.Fab")
			(effects
				(font
					(size 1.27 1.27)
				)
			)
		)
		(duplicate_pad_numbers_are_jumpers no)
		(fp_line
			(start -0.7874 0.4064)
			(end -0.7874 -0.4064)
			(stroke
				(width 0.1524)
				(type default)
			)
			(layer "F.SilkS")
		)
		(fp_line
			(start 0.7874 0.4064)
			(end -0.7874 0.4064)
			(stroke
				(width 0.1524)
				(type default)
			)
			(layer "F.SilkS")
		)
		(fp_line
			(start -0.7874 -0.4064)
			(end 0.7874 -0.4064)
			(stroke
				(width 0.1524)
				(type default)
			)
			(layer "F.SilkS")
		)
		(fp_line
			(start 0.7874 -0.4064)
			(end 0.7874 0.4064)
			(stroke
				(width 0.1524)
				(type default)
			)
			(layer "F.SilkS")
		)
		(fp_poly
			(pts
				(xy -0.508 0.2794) (xy -0.508 0.2286) (xy -0.635 0.2286) (xy -0.635 -0.254) (xy -0.5334 -0.254)
				(xy -0.5334 -0.2794) (xy 0.5334 -0.2794) (xy 0.5334 -0.254) (xy 0.635 -0.254) (xy 0.635 0.254) (xy 0.5334 0.254)
				(xy 0.5334 0.2794)
			)
			(stroke
				(width 0)
				(type default)
			)
			(fill no)
			(layer "F.CrtYd")
		)
		(pad "1" smd rect
			(at 0.40005 0 270)
			(size 0.4572 0.508)
			(layers "F.Cu" "F.Mask" "F.Paste")
			(net "P3V3")
		)
		(pad "2" smd rect
			(at -0.40005 0 270)
			(size 0.4572 0.508)
			(layers "F.Cu" "F.Mask" "F.Paste")
			(net "FRU_WP")
		)
	)
	(footprint ""
		(layer "F.Cu")
		(at 39.51478 -464.77047 -90)
		(property "Reference" "R98"
			(at -1.157224 -0.122428 90)
			(unlocked yes)
			(layer "F.SilkS")
			(effects
				(font
					(size 0.7874 0.5842)
					(thickness 0.1524)
				)
				(justify left)
			)
		)
		(property "Value" ""
			(at 0 0 270)
			(layer "F.Fab")
			(effects
				(font
					(size 1.27 1.27)
				)
			)
		)
		(duplicate_pad_numbers_are_jumpers no)
		(fp_line
			(start -0.7874 0.4064)
			(end -0.7874 -0.4064)
			(stroke
				(width 0.1524)
				(type default)
			)
			(layer "F.SilkS")
		)
		(fp_line
			(start 0.7874 0.4064)
			(end -0.7874 0.4064)
			(stroke
				(width 0.1524)
				(type default)
			)
			(layer "F.SilkS")
		)
		(fp_line
			(start -0.7874 -0.4064)
			(end 0.7874 -0.4064)
			(stroke
				(width 0.1524)
				(type default)
			)
			(layer "F.SilkS")
		)
		(fp_line
			(start 0.7874 -0.4064)
			(end 0.7874 0.4064)
			(stroke
				(width 0.1524)
				(type default)
			)
			(layer "F.SilkS")
		)
		(fp_poly
			(pts
				(xy -0.508 0.2794) (xy -0.508 0.2286) (xy -0.635 0.2286) (xy -0.635 -0.254) (xy -0.5334 -0.254)
				(xy -0.5334 -0.2794) (xy 0.5334 -0.2794) (xy 0.5334 -0.254) (xy 0.635 -0.254) (xy 0.635 0.254) (xy 0.5334 0.254)
				(xy 0.5334 0.2794)
			)
			(stroke
				(width 0)
				(type default)
			)
			(fill no)
			(layer "F.CrtYd")
		)
		(pad "1" smd rect
			(at 0.40005 0 270)
			(size 0.4572 0.508)
			(layers "F.Cu" "F.Mask" "F.Paste")
			(net "PSU6_REMOTE_P")
		)
		(pad "2" smd rect
			(at -0.40005 0 270)
			(size 0.4572 0.508)
			(layers "F.Cu" "F.Mask" "F.Paste")
			(net "PSU6_REMOTE_R_P")
		)
	)
	(footprint ""
		(layer "F.Cu")
		(at 39.874952 -461.170274 180)
		(property "Reference" "R23"
			(at -1.982978 -0.229108 0)
			(unlocked yes)
			(layer "F.SilkS")
			(effects
				(font
					(size 0.7874 0.5842)
					(thickness 0.1524)
				)
				(justify left)
			)
		)
		(property "Value" ""
			(at 0 0 180)
			(layer "F.Fab")
			(effects
				(font
					(size 1.27 1.27)
				)
			)
		)
		(duplicate_pad_numbers_are_jumpers no)
		(fp_line
			(start 0.7874 0.4064)
			(end -0.7874 0.4064)
			(stroke
				(width 0.1524)
				(type default)
			)
			(layer "F.SilkS")
		)
		(fp_line
			(start 0.7874 -0.4064)
			(end 0.7874 0.4064)
			(stroke
				(width 0.1524)
				(type default)
			)
			(layer "F.SilkS")
		)
		(fp_line
			(start -0.7874 0.4064)
			(end -0.7874 -0.4064)
			(stroke
				(width 0.1524)
				(type default)
			)
			(layer "F.SilkS")
		)
		(fp_line
			(start -0.7874 -0.4064)
			(end 0.7874 -0.4064)
			(stroke
				(width 0.1524)
				(type default)
			)
			(layer "F.SilkS")
		)
		(fp_poly
			(pts
				(xy -0.508 0.2794) (xy -0.508 0.2286) (xy -0.635 0.2286) (xy -0.635 -0.254) (xy -0.5334 -0.254)
				(xy -0.5334 -0.2794) (xy 0.5334 -0.2794) (xy 0.5334 -0.254) (xy 0.635 -0.254) (xy 0.635 0.254) (xy 0.5334 0.254)
				(xy 0.5334 0.2794)
			)
			(stroke
				(width 0)
				(type default)
			)
			(fill no)
			(layer "F.CrtYd")
		)
		(pad "1" smd rect
			(at 0.40005 0 180)
			(size 0.4572 0.508)
			(layers "F.Cu" "F.Mask" "F.Paste")
			(net "PSU6_AD0")
		)
		(pad "2" smd rect
			(at -0.40005 0 180)
			(size 0.4572 0.508)
			(layers "F.Cu" "F.Mask" "F.Paste")
			(net "GND")
		)
	)
	(footprint ""
		(layer "F.Cu")
		(at 50.350928 -306.383182 180)
		(property "Reference" "CE14"
			(at 8.029448 2.021078 0)
			(unlocked yes)
			(layer "F.SilkS")
			(effects
				(font
					(size 0.7874 0.5842)
					(thickness 0.1524)
				)
				(justify left)
			)
		)
		(property "Value" ""
			(at 0 0 180)
			(layer "F.Fab")
			(effects
				(font
					(size 1.27 1.27)
				)
			)
		)
		(duplicate_pad_numbers_are_jumpers no)
		(fp_line
			(start 0 -4.2672)
			(end 0 4.2672)
			(stroke
				(width 0.1524)
				(type default)
			)
			(layer "F.SilkS")
		)
		(fp_circle
			(center 0 0)
			(end -4.2672 0)
			(stroke
				(width 0.1524)
				(type default)
			)
			(fill no)
			(layer "F.SilkS")
		)
		(fp_poly
			(pts
				(arc
					(start 0 -4.2672)
					(mid 4.2672 0)
					(end 0 4.2672)
				)
			)
			(stroke
				(width 0)
				(type default)
			)
			(fill yes)
			(layer "F.SilkS")
		)
		(fp_poly
			(pts
				(xy -2.5146 -0.762) (xy -0.9906 -0.762) (xy -0.9906 0.762) (xy -2.5146 0.762)
			)
			(stroke
				(width 0)
				(type default)
			)
			(fill no)
			(layer "B.CrtYd")
		)
		(fp_poly
			(pts
				(arc
					(start 1.7526 0.762)
					(mid 2.291415 -0.538815)
					(end 0.9906 0)
				)
				(arc
					(start 0.9906 0.0254)
					(mid 1.206345 0.546255)
					(end 1.7272 0.762)
				)
			)
			(stroke
				(width 0)
				(type default)
			)
			(fill no)
			(layer "B.CrtYd")
		)
		(fp_poly
			(pts
				(arc
					(start -4.2672 0)
					(mid 4.2672 0)
					(end -4.2672 0)
				)
			)
			(stroke
				(width 0)
				(type default)
			)
			(fill no)
			(layer "F.CrtYd")
		)
		(fp_circle
			(center 0 0)
			(end -4.2672 0)
			(stroke
				(width 0.1)
				(type default)
			)
			(fill no)
			(layer "F.Fab")
		)
		(fp_text user "+"
			(at -5.6642 -0.34925 180)
			(unlocked yes)
			(layer "F.SilkS")
			(effects
				(font
					(size 1.905 1.4224)
					(thickness 0.1524)
				)
				(justify left)
			)
		)
		(fp_text user "+"
			(at -5.6642 -0.34925 180)
			(unlocked yes)
			(layer "F.Fab")
			(effects
				(font
					(size 1.905 1.4224)
					(thickness 0.000001)
				)
				(justify left)
			)
		)
		(pad "1" thru_hole rect
			(at -1.75006 0 180)
			(size 1.397 1.397)
			(drill 0.9144)
			(layers "*.Cu" "*.Mask")
			(remove_unused_layers no)
			(net "P12V")
			(clearance 0.0127)
			(thermal_gap 0.0127)
			(padstack
				(mode front_inner_back)
				(layer "Inner"
					(shape circle)
					(size 1.397 1.397)
					(clearance 0.0127)
				)
				(layer "B.Cu"
					(shape rect)
					(size 1.397 1.397)
					(clearance 0.0127)
				)
			)
		)
		(pad "2" thru_hole circle
			(at 1.75006 0 180)
			(size 1.397 1.397)
			(drill 0.9144)
			(layers "*.Cu" "*.Mask")
			(remove_unused_layers no)
			(net "GND")
			(clearance 0.0127)
			(thermal_gap 0.0127)
		)
	)
	(footprint ""
		(layer "F.Cu")
		(at 5.70992 -86.47684)
		(property "Reference" "J34"
			(at -2.0066 -4.028948 0)
			(unlocked yes)
			(layer "F.SilkS")
			(effects
				(font
					(size 0.7874 0.5842)
					(thickness 0.1524)
				)
				(justify left)
			)
		)
		(property "Value" ""
			(at 0 0 0)
			(layer "F.Fab")
			(effects
				(font
					(size 1.27 1.27)
				)
			)
		)
		(duplicate_pad_numbers_are_jumpers no)
		(fp_line
			(start -3.10007 1.700022)
			(end -3.10007 4.299966)
			(stroke
				(width 0.1524)
				(type default)
			)
			(layer "F.SilkS")
		)
		(fp_line
			(start -3.10007 4.299966)
			(end -1.89992 4.299966)
			(stroke
				(width 0.1524)
				(type default)
			)
			(layer "F.SilkS")
		)
		(fp_line
			(start -1.89992 -3.325114)
			(end -1.89992 1.700022)
			(stroke
				(width 0.1524)
				(type default)
			)
			(layer "F.SilkS")
		)
		(fp_line
			(start -1.89992 1.700022)
			(end -3.10007 1.700022)
			(stroke
				(width 0.1524)
				(type default)
			)
			(layer "F.SilkS")
		)
		(fp_line
			(start -1.89992 4.299966)
			(end -1.89992 9.325102)
			(stroke
				(width 0.1524)
				(type default)
			)
			(layer "F.SilkS")
		)
		(fp_line
			(start -1.89992 9.325102)
			(end 1.016 9.325102)
			(stroke
				(width 0.1524)
				(type default)
			)
			(layer "F.SilkS")
		)
		(fp_line
			(start 1.016 -3.325114)
			(end -1.89992 -3.325114)
			(stroke
				(width 0.1524)
				(type default)
			)
			(layer "F.SilkS")
		)
		(fp_line
			(start 2.469896 8.133588)
			(end 2.469896 -2.128012)
			(stroke
				(width 0.1524)
				(type default)
			)
			(layer "F.SilkS")
		)
		(fp_poly
			(pts
				(xy -3.435604 0.672338) (xy -3.435604 -0.672338) (xy -2.090928 0)
			)
			(stroke
				(width 0)
				(type default)
			)
			(fill yes)
			(layer "F.SilkS")
		)
		(fp_poly
			(pts
				(xy -0.8636 6.860794) (xy 0.8636 6.860794) (xy 0.8636 -0.860806) (xy -0.8636 -0.860806)
			)
			(stroke
				(width 0)
				(type default)
			)
			(fill no)
			(layer "B.CrtYd")
		)
		(fp_poly
			(pts
				(arc
					(start 2.874518 -2.999994)
					(mid 1.045718 -2.999994)
					(end 2.874518 -2.999994)
				)
			)
			(stroke
				(width 0)
				(type default)
			)
			(fill no)
			(layer "B.CrtYd")
		)
		(fp_poly
			(pts
				(arc
					(start 2.874518 8.999982)
					(mid 1.045718 8.999982)
					(end 2.874518 8.999982)
				)
			)
			(stroke
				(width 0)
				(type default)
			)
			(fill no)
			(layer "B.CrtYd")
		)
		(fp_poly
			(pts
				(xy 2.469896 8.232394) (xy 2.469896 -2.232406) (xy 2.8956 -2.232406) (xy 2.8956 -3.934206) (xy 1.0922 -3.934206)
				(xy 1.0922 -3.325114) (xy -1.89992 -3.325114) (xy -1.89992 1.700022) (xy -3.10007 1.700022) (xy -3.10007 4.299966)
				(xy -1.89992 4.299966) (xy -1.89992 9.325102) (xy 1.0922 9.325102) (xy 1.0922 9.934194) (xy 2.8956 9.934194)
				(xy 2.8956 8.232394)
			)
			(stroke
				(width 0)
				(type default)
			)
			(fill no)
			(layer "F.CrtYd")
		)
		(fp_line
			(start -3.10007 1.700022)
			(end -3.10007 4.299966)
			(stroke
				(width 0.1)
				(type default)
			)
			(layer "F.Fab")
		)
		(fp_line
			(start -3.10007 4.299966)
			(end -1.89992 4.299966)
			(stroke
				(width 0.1)
				(type default)
			)
			(layer "F.Fab")
		)
		(fp_line
			(start -1.89992 -3.325114)
			(end -1.89992 1.700022)
			(stroke
				(width 0.1)
				(type default)
			)
			(layer "F.Fab")
		)
		(fp_line
			(start -1.89992 1.700022)
			(end -3.10007 1.700022)
			(stroke
				(width 0.1)
				(type default)
			)
			(layer "F.Fab")
		)
		(fp_line
			(start -1.89992 4.299966)
			(end -1.89992 9.325102)
			(stroke
				(width 0.1)
				(type default)
			)
			(layer "F.Fab")
		)
		(fp_line
			(start -1.89992 9.325102)
			(end 2.469896 9.325102)
			(stroke
				(width 0.1)
				(type default)
			)
			(layer "F.Fab")
		)
		(fp_line
			(start 2.469896 -3.325114)
			(end -1.89992 -3.325114)
			(stroke
				(width 0.1)
				(type default)
			)
			(layer "F.Fab")
		)
		(fp_line
			(start 2.469896 9.325102)
			(end 2.469896 -3.325114)
			(stroke
				(width 0.1)
				(type default)
			)
			(layer "F.Fab")
		)
		(fp_poly
			(pts
				(xy -3.435604 0.672338) (xy -3.435604 -0.672338) (xy -2.090928 0)
			)
			(stroke
				(width 0)
				(type default)
			)
			(fill yes)
			(layer "F.Fab")
		)
		(fp_text user "3"
			(at -2.504948 5.999988 90)
			(unlocked yes)
			(layer "F.SilkS")
			(effects
				(font
					(size 0.7874 0.5842)
					(thickness 0.1524)
				)
			)
		)
		(fp_text user "1"
			(at 0.035052 -1.188212 90)
			(unlocked yes)
			(layer "B.SilkS")
			(effects
				(font
					(size 0.7874 0.5842)
					(thickness 0.1524)
				)
				(justify mirror)
			)
		)
		(fp_text user "3"
			(at 0.035052 7.193788 90)
			(unlocked yes)
			(layer "B.SilkS")
			(effects
				(font
					(size 0.7874 0.5842)
					(thickness 0.1524)
				)
				(justify mirror)
			)
		)
		(fp_text user "1"
			(at 0.035052 -1.188212 90)
			(unlocked yes)
			(layer "B.Fab")
			(effects
				(font
					(size 0.7874 0.5842)
					(thickness 0.1524)
				)
				(justify mirror)
			)
		)
		(fp_text user "3"
			(at 0.035052 7.193788 90)
			(unlocked yes)
			(layer "B.Fab")
			(effects
				(font
					(size 0.7874 0.5842)
					(thickness 0.1524)
				)
				(justify mirror)
			)
		)
		(fp_text user "3"
			(at -2.504948 5.999988 90)
			(unlocked yes)
			(layer "F.Fab")
			(effects
				(font
					(size 0.7874 0.5842)
					(thickness 0.1524)
				)
			)
		)
		(pad "" np_thru_hole circle
			(at 1.960118 -2.999994 90)
			(size 1.3208 1.3208)
			(drill 1.3208)
			(layers "*.Cu" "*.Mask")
			(clearance 0.381)
			(thermal_gap 0.381)
		)
		(pad "" np_thru_hole circle
			(at 1.960118 8.999982 90)
			(size 1.3208 1.3208)
			(drill 1.3208)
			(layers "*.Cu" "*.Mask")
			(clearance 0.381)
			(thermal_gap 0.381)
		)
		(pad "1" thru_hole rect
			(at 0 0 90)
			(size 1.6002 1.6002)
			(drill 1.0922)
			(layers "*.Cu" "*.Mask")
			(remove_unused_layers no)
			(net "GND")
			(clearance 0)
			(padstack
				(mode front_inner_back)
				(layer "Inner"
					(shape circle)
					(size 1.6002 1.6002)
					(clearance 0)
				)
				(layer "B.Cu"
					(shape rect)
					(size 1.6002 1.6002)
					(clearance 0)
				)
			)
		)
		(pad "2" thru_hole circle
			(at 0 2.999994 90)
			(size 1.6002 1.6002)
			(drill 1.0922)
			(layers "*.Cu" "*.Mask")
			(remove_unused_layers no)
			(net "P12V")
			(clearance 0)
		)
		(pad "3" thru_hole circle
			(at 0 5.999988 90)
			(size 1.6002 1.6002)
			(drill 1.0922)
			(layers "*.Cu" "*.Mask")
			(remove_unused_layers no)
			(net "GND")
			(clearance 0)
		)
		(zone
			(layers "F.Cu" "B.Cu" "In1.Cu" "In2.Cu" "In3.Cu" "In4.Cu" "In5.Cu" "In6.Cu")
			(hatch none 0.5)
			(connect_pads
				(clearance 0)
			)
			(min_thickness 0.25)
			(keepout
				(tracks not_allowed)
				(vias allowed)
				(pads allowed)
				(copperpour not_allowed)
				(footprints allowed)
			)
			(placement
				(enabled no)
				(sheetname "")
			)
			(fill
				(thermal_gap 0.5)
				(thermal_bridge_width 0.5)
				(island_removal_mode 0)
			)
			(polygon
				(pts
					(arc
						(start 8.736838 -89.476834)
						(mid 6.603238 -89.476834)
						(end 8.736838 -89.476834)
					)
				)
			)
		)
		(zone
			(layers "F.Cu" "B.Cu" "In1.Cu" "In2.Cu" "In3.Cu" "In4.Cu" "In5.Cu" "In6.Cu")
			(hatch none 0.5)
			(connect_pads
				(clearance 0)
			)
			(min_thickness 0.25)
			(keepout
				(tracks not_allowed)
				(vias allowed)
				(pads allowed)
				(copperpour not_allowed)
				(footprints allowed)
			)
			(placement
				(enabled no)
				(sheetname "")
			)
			(fill
				(thermal_gap 0.5)
				(thermal_bridge_width 0.5)
				(island_removal_mode 0)
			)
			(polygon
				(pts
					(arc
						(start 8.736838 -77.476858)
						(mid 6.603238 -77.476858)
						(end 8.736838 -77.476858)
					)
				)
			)
		)
	)
	(footprint ""
		(layer "F.Cu")
		(at 46.425612 -253.125732 180)
		(property "Reference" "R99"
			(at 2.224278 1.16205 0)
			(unlocked yes)
			(layer "F.SilkS")
			(effects
				(font
					(size 0.7874 0.5842)
					(thickness 0.1524)
				)
				(justify left)
			)
		)
		(property "Value" ""
			(at 0 0 180)
			(layer "F.Fab")
			(effects
				(font
					(size 1.27 1.27)
				)
			)
		)
		(duplicate_pad_numbers_are_jumpers no)
		(fp_line
			(start 0.7874 0.4064)
			(end -0.7874 0.4064)
			(stroke
				(width 0.1524)
				(type default)
			)
			(layer "F.SilkS")
		)
		(fp_line
			(start 0.7874 -0.4064)
			(end 0.7874 0.4064)
			(stroke
				(width 0.1524)
				(type default)
			)
			(layer "F.SilkS")
		)
		(fp_line
			(start -0.7874 0.4064)
			(end -0.7874 -0.4064)
			(stroke
				(width 0.1524)
				(type default)
			)
			(layer "F.SilkS")
		)
		(fp_line
			(start -0.7874 -0.4064)
			(end 0.7874 -0.4064)
			(stroke
				(width 0.1524)
				(type default)
			)
			(layer "F.SilkS")
		)
		(fp_poly
			(pts
				(xy -0.508 0.2794) (xy -0.508 0.2286) (xy -0.635 0.2286) (xy -0.635 -0.254) (xy -0.5334 -0.254)
				(xy -0.5334 -0.2794) (xy 0.5334 -0.2794) (xy 0.5334 -0.254) (xy 0.635 -0.254) (xy 0.635 0.254) (xy 0.5334 0.254)
				(xy 0.5334 0.2794)
			)
			(stroke
				(width 0)
				(type default)
			)
			(fill no)
			(layer "F.CrtYd")
		)
		(pad "1" smd rect
			(at 0.40005 0 180)
			(size 0.4572 0.508)
			(layers "F.Cu" "F.Mask" "F.Paste")
			(net "PSU6_REMOTE_R_N")
		)
		(pad "2" smd rect
			(at -0.40005 0 180)
			(size 0.4572 0.508)
			(layers "F.Cu" "F.Mask" "F.Paste")
			(net "GND")
		)
	)
	(footprint ""
		(layer "F.Cu")
		(at 91.399868 -242.26012)
		(property "Reference" "H18"
			(at -5.1308 -5.23113 0)
			(unlocked yes)
			(layer "F.SilkS")
			(effects
				(font
					(size 0.7874 0.5842)
					(thickness 0.1524)
				)
				(justify left)
			)
		)
		(property "Value" ""
			(at 0 0 0)
			(layer "F.Fab")
			(effects
				(font
					(size 1.27 1.27)
				)
			)
		)
		(duplicate_pad_numbers_are_jumpers no)
		(fp_circle
			(center 0 0)
			(end 4.826 0)
			(stroke
				(width 0.1524)
				(type default)
			)
			(fill no)
			(layer "F.SilkS")
		)
		(fp_circle
			(center 0 0)
			(end 4.826 0)
			(stroke
				(width 0.1524)
				(type default)
			)
			(fill no)
			(layer "B.SilkS")
		)
		(fp_poly
			(pts
				(arc
					(start 0 4.0132)
					(mid 0 -4.0132)
					(end 0 4.0132)
				)
			)
			(stroke
				(width 0)
				(type default)
			)
			(fill no)
			(layer "F.CrtYd")
		)
		(pad "" np_thru_hole circle
			(at 0 0)
			(size 8.001 8.001)
			(drill 8.001)
			(layers "*.Cu" "*.Mask")
			(clearance 0.381)
			(thermal_gap 0.381)
		)
		(zone
			(layers "F.Cu" "B.Cu" "In1.Cu" "In2.Cu" "In3.Cu" "In4.Cu" "In5.Cu" "In6.Cu")
			(hatch none 0.5)
			(connect_pads
				(clearance 0)
			)
			(min_thickness 0.25)
			(keepout
				(tracks not_allowed)
				(vias allowed)
				(pads allowed)
				(copperpour not_allowed)
				(footprints allowed)
			)
			(placement
				(enabled no)
				(sheetname "")
			)
			(fill
				(thermal_gap 0.5)
				(thermal_bridge_width 0.5)
				(island_removal_mode 0)
			)
			(polygon
				(pts
					(arc
						(start 91.399868 -237.73892)
						(mid 91.399868 -246.78132)
						(end 91.399868 -237.73892)
					)
				)
			)
		)
	)
	(footprint ""
		(layer "F.Cu")
		(at 13.420852 -318.358012 180)
		(property "Reference" "R140"
			(at -2.29235 -0.183642 0)
			(unlocked yes)
			(layer "F.SilkS")
			(effects
				(font
					(size 0.7874 0.5842)
					(thickness 0.1524)
				)
				(justify left)
			)
		)
		(property "Value" ""
			(at 0 0 180)
			(layer "F.Fab")
			(effects
				(font
					(size 1.27 1.27)
				)
			)
		)
		(duplicate_pad_numbers_are_jumpers no)
		(fp_line
			(start 0.7874 0.4064)
			(end -0.7874 0.4064)
			(stroke
				(width 0.1524)
				(type default)
			)
			(layer "F.SilkS")
		)
		(fp_line
			(start 0.7874 -0.4064)
			(end 0.7874 0.4064)
			(stroke
				(width 0.1524)
				(type default)
			)
			(layer "F.SilkS")
		)
		(fp_line
			(start -0.7874 0.4064)
			(end -0.7874 -0.4064)
			(stroke
				(width 0.1524)
				(type default)
			)
			(layer "F.SilkS")
		)
		(fp_line
			(start -0.7874 -0.4064)
			(end 0.7874 -0.4064)
			(stroke
				(width 0.1524)
				(type default)
			)
			(layer "F.SilkS")
		)
		(fp_poly
			(pts
				(xy -0.508 0.2794) (xy -0.508 0.2286) (xy -0.635 0.2286) (xy -0.635 -0.254) (xy -0.5334 -0.254)
				(xy -0.5334 -0.2794) (xy 0.5334 -0.2794) (xy 0.5334 -0.254) (xy 0.635 -0.254) (xy 0.635 0.254) (xy 0.5334 0.254)
				(xy 0.5334 0.2794)
			)
			(stroke
				(width 0)
				(type default)
			)
			(fill no)
			(layer "F.CrtYd")
		)
		(pad "1" smd rect
			(at 0.40005 0 180)
			(size 0.4572 0.508)
			(layers "F.Cu" "F.Mask" "F.Paste")
			(net "FAN_PWM")
		)
		(pad "2" smd rect
			(at -0.40005 0 180)
			(size 0.4572 0.508)
			(layers "F.Cu" "F.Mask" "F.Paste")
			(net "GND")
		)
	)
	(footprint ""
		(layer "F.Cu")
		(at 73.914508 -108.56976 -90)
		(property "Reference" "C17"
			(at -2.68224 -0.080772 90)
			(unlocked yes)
			(layer "F.SilkS")
			(effects
				(font
					(size 0.7874 0.5842)
					(thickness 0.1524)
				)
				(justify left)
			)
		)
		(property "Value" ""
			(at 0 0 270)
			(layer "F.Fab")
			(effects
				(font
					(size 1.27 1.27)
				)
			)
		)
		(duplicate_pad_numbers_are_jumpers no)
		(fp_line
			(start -0.7874 0.4064)
			(end -0.7874 -0.4064)
			(stroke
				(width 0.1524)
				(type default)
			)
			(layer "F.SilkS")
		)
		(fp_line
			(start 0.7874 0.4064)
			(end -0.7874 0.4064)
			(stroke
				(width 0.1524)
				(type default)
			)
			(layer "F.SilkS")
		)
		(fp_line
			(start 0 0.381)
			(end 0 -0.381)
			(stroke
				(width 0.1524)
				(type default)
			)
			(layer "F.SilkS")
		)
		(fp_line
			(start -0.7874 -0.4064)
			(end 0.7874 -0.4064)
			(stroke
				(width 0.1524)
				(type default)
			)
			(layer "F.SilkS")
		)
		(fp_line
			(start 0.7874 -0.4064)
			(end 0.7874 0.4064)
			(stroke
				(width 0.1524)
				(type default)
			)
			(layer "F.SilkS")
		)
		(fp_poly
			(pts
				(xy -0.5334 0.254) (xy -0.635 0.254) (xy -0.635 0.2286) (xy -0.635 -0.254) (xy -0.5334 -0.254) (xy -0.5334 -0.2794)
				(xy 0.5334 -0.2794) (xy 0.5334 -0.254) (xy 0.635 -0.254) (xy 0.635 0.254) (xy 0.5334 0.254) (xy 0.5334 0.2794)
				(xy -0.508 0.2794) (xy -0.5334 0.2794)
			)
			(stroke
				(width 0)
				(type default)
			)
			(fill no)
			(layer "F.CrtYd")
		)
		(pad "1" smd rect
			(at 0.40005 0 270)
			(size 0.4572 0.508)
			(layers "F.Cu" "F.Mask" "F.Paste")
			(net "P12V")
		)
		(pad "2" smd rect
			(at -0.40005 0 270)
			(size 0.4572 0.508)
			(layers "F.Cu" "F.Mask" "F.Paste")
			(net "GND")
		)
	)
	(footprint ""
		(layer "F.Cu")
		(at 66.74104 -206.29118 180)
		(property "Reference" "R120"
			(at -0.150876 -1.42875 0)
			(unlocked yes)
			(layer "F.SilkS")
			(effects
				(font
					(size 0.7874 0.5842)
					(thickness 0.1524)
				)
				(justify left)
			)
		)
		(property "Value" ""
			(at 0 0 180)
			(layer "F.Fab")
			(effects
				(font
					(size 1.27 1.27)
				)
			)
		)
		(duplicate_pad_numbers_are_jumpers no)
		(fp_line
			(start 0.7874 0.4064)
			(end -0.7874 0.4064)
			(stroke
				(width 0.1524)
				(type default)
			)
			(layer "F.SilkS")
		)
		(fp_line
			(start 0.7874 -0.4064)
			(end 0.7874 0.4064)
			(stroke
				(width 0.1524)
				(type default)
			)
			(layer "F.SilkS")
		)
		(fp_line
			(start -0.7874 0.4064)
			(end -0.7874 -0.4064)
			(stroke
				(width 0.1524)
				(type default)
			)
			(layer "F.SilkS")
		)
		(fp_line
			(start -0.7874 -0.4064)
			(end 0.7874 -0.4064)
			(stroke
				(width 0.1524)
				(type default)
			)
			(layer "F.SilkS")
		)
		(fp_poly
			(pts
				(xy -0.508 0.2794) (xy -0.508 0.2286) (xy -0.635 0.2286) (xy -0.635 -0.254) (xy -0.5334 -0.254)
				(xy -0.5334 -0.2794) (xy 0.5334 -0.2794) (xy 0.5334 -0.254) (xy 0.635 -0.254) (xy 0.635 0.254) (xy 0.5334 0.254)
				(xy 0.5334 0.2794)
			)
			(stroke
				(width 0)
				(type default)
			)
			(fill no)
			(layer "F.CrtYd")
		)
		(pad "1" smd rect
			(at 0.40005 0 180)
			(size 0.4572 0.508)
			(layers "F.Cu" "F.Mask" "F.Paste")
			(net "PSU3_REMOTE_R2_N")
		)
		(pad "2" smd rect
			(at -0.40005 0 180)
			(size 0.4572 0.508)
			(layers "F.Cu" "F.Mask" "F.Paste")
			(net "GND")
		)
	)
	(footprint ""
		(layer "F.Cu")
		(at 39.512494 -463.972148 90)
		(property "Reference" "R130"
			(at -0.669544 1.862074 0)
			(unlocked yes)
			(layer "F.SilkS")
			(effects
				(font
					(size 0.7874 0.5842)
					(thickness 0.1524)
				)
				(justify left)
			)
		)
		(property "Value" ""
			(at 0 0 90)
			(layer "F.Fab")
			(effects
				(font
					(size 1.27 1.27)
				)
			)
		)
		(duplicate_pad_numbers_are_jumpers no)
		(fp_line
			(start 0.7874 -0.4064)
			(end 0.7874 0.4064)
			(stroke
				(width 0.1524)
				(type default)
			)
			(layer "F.SilkS")
		)
		(fp_line
			(start -0.7874 -0.4064)
			(end 0.7874 -0.4064)
			(stroke
				(width 0.1524)
				(type default)
			)
			(layer "F.SilkS")
		)
		(fp_line
			(start 0.7874 0.4064)
			(end -0.7874 0.4064)
			(stroke
				(width 0.1524)
				(type default)
			)
			(layer "F.SilkS")
		)
		(fp_line
			(start -0.7874 0.4064)
			(end -0.7874 -0.4064)
			(stroke
				(width 0.1524)
				(type default)
			)
			(layer "F.SilkS")
		)
		(fp_poly
			(pts
				(xy -0.508 0.2794) (xy -0.508 0.2286) (xy -0.635 0.2286) (xy -0.635 -0.254) (xy -0.5334 -0.254)
				(xy -0.5334 -0.2794) (xy 0.5334 -0.2794) (xy 0.5334 -0.254) (xy 0.635 -0.254) (xy 0.635 0.254) (xy 0.5334 0.254)
				(xy 0.5334 0.2794)
			)
			(stroke
				(width 0)
				(type default)
			)
			(fill no)
			(layer "F.CrtYd")
		)
		(pad "1" smd rect
			(at 0.40005 0 90)
			(size 0.4572 0.508)
			(layers "F.Cu" "F.Mask" "F.Paste")
			(net "PSU6_REMOTE_P")
		)
		(pad "2" smd rect
			(at -0.40005 0 90)
			(size 0.4572 0.508)
			(layers "F.Cu" "F.Mask" "F.Paste")
			(net "PSU6_REMOTE_R2_P")
		)
	)
	(footprint ""
		(layer "F.Cu")
		(at 39.705534 -105.822242 -90)
		(property "Reference" "R4"
			(at 0.830326 -2.570734 90)
			(unlocked yes)
			(layer "F.SilkS")
			(effects
				(font
					(size 0.7874 0.5842)
					(thickness 0.1524)
				)
				(justify left)
			)
		)
		(property "Value" ""
			(at 0 0 270)
			(layer "F.Fab")
			(effects
				(font
					(size 1.27 1.27)
				)
			)
		)
		(duplicate_pad_numbers_are_jumpers no)
		(fp_line
			(start -0.7874 0.4064)
			(end -0.7874 -0.4064)
			(stroke
				(width 0.1524)
				(type default)
			)
			(layer "F.SilkS")
		)
		(fp_line
			(start 0.7874 0.4064)
			(end -0.7874 0.4064)
			(stroke
				(width 0.1524)
				(type default)
			)
			(layer "F.SilkS")
		)
		(fp_line
			(start -0.7874 -0.4064)
			(end 0.7874 -0.4064)
			(stroke
				(width 0.1524)
				(type default)
			)
			(layer "F.SilkS")
		)
		(fp_line
			(start 0.7874 -0.4064)
			(end 0.7874 0.4064)
			(stroke
				(width 0.1524)
				(type default)
			)
			(layer "F.SilkS")
		)
		(fp_poly
			(pts
				(xy -0.508 0.2794) (xy -0.508 0.2286) (xy -0.635 0.2286) (xy -0.635 -0.254) (xy -0.5334 -0.254)
				(xy -0.5334 -0.2794) (xy 0.5334 -0.2794) (xy 0.5334 -0.254) (xy 0.635 -0.254) (xy 0.635 0.254) (xy 0.5334 0.254)
				(xy 0.5334 0.2794)
			)
			(stroke
				(width 0)
				(type default)
			)
			(fill no)
			(layer "F.CrtYd")
		)
		(pad "1" smd rect
			(at 0.40005 0 270)
			(size 0.4572 0.508)
			(layers "F.Cu" "F.Mask" "F.Paste")
			(net "PSU2_AD0")
		)
		(pad "2" smd rect
			(at -0.40005 0 270)
			(size 0.4572 0.508)
			(layers "F.Cu" "F.Mask" "F.Paste")
			(net "P12V_STBY")
		)
	)
	(footprint ""
		(layer "F.Cu")
		(at 50.478944 -196.729604 180)
		(property "Reference" "CE10"
			(at -4.974844 0.065278 0)
			(unlocked yes)
			(layer "F.SilkS")
			(effects
				(font
					(size 0.7874 0.5842)
					(thickness 0.1524)
				)
				(justify left)
			)
		)
		(property "Value" ""
			(at 0 0 180)
			(layer "F.Fab")
			(effects
				(font
					(size 1.27 1.27)
				)
			)
		)
		(duplicate_pad_numbers_are_jumpers no)
		(fp_line
			(start 0 -4.2672)
			(end 0 4.2672)
			(stroke
				(width 0.1524)
				(type default)
			)
			(layer "F.SilkS")
		)
		(fp_circle
			(center 0 0)
			(end -4.2672 0)
			(stroke
				(width 0.1524)
				(type default)
			)
			(fill no)
			(layer "F.SilkS")
		)
		(fp_poly
			(pts
				(arc
					(start 0 -4.2672)
					(mid 4.2672 0)
					(end 0 4.2672)
				)
			)
			(stroke
				(width 0)
				(type default)
			)
			(fill yes)
			(layer "F.SilkS")
		)
		(fp_poly
			(pts
				(xy -2.5146 -0.762) (xy -0.9906 -0.762) (xy -0.9906 0.762) (xy -2.5146 0.762)
			)
			(stroke
				(width 0)
				(type default)
			)
			(fill no)
			(layer "B.CrtYd")
		)
		(fp_poly
			(pts
				(arc
					(start 1.7526 0.762)
					(mid 2.291415 -0.538815)
					(end 0.9906 0)
				)
				(arc
					(start 0.9906 0.0254)
					(mid 1.206345 0.546255)
					(end 1.7272 0.762)
				)
			)
			(stroke
				(width 0)
				(type default)
			)
			(fill no)
			(layer "B.CrtYd")
		)
		(fp_poly
			(pts
				(arc
					(start -4.2672 0)
					(mid 4.2672 0)
					(end -4.2672 0)
				)
			)
			(stroke
				(width 0)
				(type default)
			)
			(fill no)
			(layer "F.CrtYd")
		)
		(fp_circle
			(center 0 0)
			(end -4.2672 0)
			(stroke
				(width 0.1)
				(type default)
			)
			(fill no)
			(layer "F.Fab")
		)
		(fp_text user "+"
			(at -5.846572 -1.718056 180)
			(unlocked yes)
			(layer "F.SilkS")
			(effects
				(font
					(size 1.905 1.4224)
					(thickness 0.1524)
				)
				(justify left)
			)
		)
		(fp_text user "+"
			(at -5.6642 -0.34925 180)
			(unlocked yes)
			(layer "F.Fab")
			(effects
				(font
					(size 1.905 1.4224)
					(thickness 0.000001)
				)
				(justify left)
			)
		)
		(pad "1" thru_hole rect
			(at -1.75006 0 180)
			(size 1.397 1.397)
			(drill 0.9144)
			(layers "*.Cu" "*.Mask")
			(remove_unused_layers no)
			(net "P12V")
			(clearance 0.0127)
			(thermal_gap 0.0127)
			(padstack
				(mode front_inner_back)
				(layer "Inner"
					(shape circle)
					(size 1.397 1.397)
					(clearance 0.0127)
				)
				(layer "B.Cu"
					(shape rect)
					(size 1.397 1.397)
					(clearance 0.0127)
				)
			)
		)
		(pad "2" thru_hole circle
			(at 1.75006 0 180)
			(size 1.397 1.397)
			(drill 0.9144)
			(layers "*.Cu" "*.Mask")
			(remove_unused_layers no)
			(net "GND")
			(clearance 0.0127)
			(thermal_gap 0.0127)
		)
	)
	(footprint ""
		(layer "F.Cu")
		(at 91.399868 -286.709866)
		(property "Reference" "H21"
			(at -5.1308 -5.23113 0)
			(unlocked yes)
			(layer "F.SilkS")
			(effects
				(font
					(size 0.7874 0.5842)
					(thickness 0.1524)
				)
				(justify left)
			)
		)
		(property "Value" ""
			(at 0 0 0)
			(layer "F.Fab")
			(effects
				(font
					(size 1.27 1.27)
				)
			)
		)
		(duplicate_pad_numbers_are_jumpers no)
		(fp_circle
			(center 0 0)
			(end 4.826 0)
			(stroke
				(width 0.1524)
				(type default)
			)
			(fill no)
			(layer "F.SilkS")
		)
		(fp_circle
			(center 0 0)
			(end 4.826 0)
			(stroke
				(width 0.1524)
				(type default)
			)
			(fill no)
			(layer "B.SilkS")
		)
		(fp_poly
			(pts
				(arc
					(start 0 4.0132)
					(mid 0 -4.0132)
					(end 0 4.0132)
				)
			)
			(stroke
				(width 0)
				(type default)
			)
			(fill no)
			(layer "F.CrtYd")
		)
		(pad "" np_thru_hole circle
			(at 0 0)
			(size 8.001 8.001)
			(drill 8.001)
			(layers "*.Cu" "*.Mask")
			(clearance 0.381)
			(thermal_gap 0.381)
		)
		(zone
			(layers "F.Cu" "B.Cu" "In1.Cu" "In2.Cu" "In3.Cu" "In4.Cu" "In5.Cu" "In6.Cu")
			(hatch none 0.5)
			(connect_pads
				(clearance 0)
			)
			(min_thickness 0.25)
			(keepout
				(tracks not_allowed)
				(vias allowed)
				(pads allowed)
				(copperpour not_allowed)
				(footprints allowed)
			)
			(placement
				(enabled no)
				(sheetname "")
			)
			(fill
				(thermal_gap 0.5)
				(thermal_bridge_width 0.5)
				(island_removal_mode 0)
			)
			(polygon
				(pts
					(arc
						(start 91.399868 -282.188666)
						(mid 91.399868 -291.231066)
						(end 91.399868 -282.188666)
					)
				)
			)
		)
	)
	(footprint ""
		(layer "F.Cu")
		(at 77.993494 -384.526282 180)
		(property "Reference" "R128"
			(at 1.129792 -1.375156 0)
			(unlocked yes)
			(layer "F.SilkS")
			(effects
				(font
					(size 0.7874 0.5842)
					(thickness 0.1524)
				)
				(justify left)
			)
		)
		(property "Value" ""
			(at 0 0 180)
			(layer "F.Fab")
			(effects
				(font
					(size 1.27 1.27)
				)
			)
		)
		(duplicate_pad_numbers_are_jumpers no)
		(fp_line
			(start 0.7874 0.4064)
			(end -0.7874 0.4064)
			(stroke
				(width 0.1524)
				(type default)
			)
			(layer "F.SilkS")
		)
		(fp_line
			(start 0.7874 -0.4064)
			(end 0.7874 0.4064)
			(stroke
				(width 0.1524)
				(type default)
			)
			(layer "F.SilkS")
		)
		(fp_line
			(start -0.7874 0.4064)
			(end -0.7874 -0.4064)
			(stroke
				(width 0.1524)
				(type default)
			)
			(layer "F.SilkS")
		)
		(fp_line
			(start -0.7874 -0.4064)
			(end 0.7874 -0.4064)
			(stroke
				(width 0.1524)
				(type default)
			)
			(layer "F.SilkS")
		)
		(fp_poly
			(pts
				(xy -0.508 0.2794) (xy -0.508 0.2286) (xy -0.635 0.2286) (xy -0.635 -0.254) (xy -0.5334 -0.254)
				(xy -0.5334 -0.2794) (xy 0.5334 -0.2794) (xy 0.5334 -0.254) (xy 0.635 -0.254) (xy 0.635 0.254) (xy 0.5334 0.254)
				(xy 0.5334 0.2794)
			)
			(stroke
				(width 0)
				(type default)
			)
			(fill no)
			(layer "F.CrtYd")
		)
		(pad "1" smd rect
			(at 0.40005 0 180)
			(size 0.4572 0.508)
			(layers "F.Cu" "F.Mask" "F.Paste")
			(net "PSU5_REMOTE_R2_N")
		)
		(pad "2" smd rect
			(at -0.40005 0 180)
			(size 0.4572 0.508)
			(layers "F.Cu" "F.Mask" "F.Paste")
			(net "GND")
		)
	)
	(footprint ""
		(layer "F.Cu")
		(at 80.947006 -297.892216 180)
		(property "Reference" "R123"
			(at 1.088644 1.215136 0)
			(unlocked yes)
			(layer "F.SilkS")
			(effects
				(font
					(size 0.7874 0.5842)
					(thickness 0.1524)
				)
				(justify left)
			)
		)
		(property "Value" ""
			(at 0 0 180)
			(layer "F.Fab")
			(effects
				(font
					(size 1.27 1.27)
				)
			)
		)
		(duplicate_pad_numbers_are_jumpers no)
		(fp_line
			(start 0.7874 0.4064)
			(end -0.7874 0.4064)
			(stroke
				(width 0.1524)
				(type default)
			)
			(layer "F.SilkS")
		)
		(fp_line
			(start 0.7874 -0.4064)
			(end 0.7874 0.4064)
			(stroke
				(width 0.1524)
				(type default)
			)
			(layer "F.SilkS")
		)
		(fp_line
			(start -0.7874 0.4064)
			(end -0.7874 -0.4064)
			(stroke
				(width 0.1524)
				(type default)
			)
			(layer "F.SilkS")
		)
		(fp_line
			(start -0.7874 -0.4064)
			(end 0.7874 -0.4064)
			(stroke
				(width 0.1524)
				(type default)
			)
			(layer "F.SilkS")
		)
		(fp_poly
			(pts
				(xy -0.508 0.2794) (xy -0.508 0.2286) (xy -0.635 0.2286) (xy -0.635 -0.254) (xy -0.5334 -0.254)
				(xy -0.5334 -0.2794) (xy 0.5334 -0.2794) (xy 0.5334 -0.254) (xy 0.635 -0.254) (xy 0.635 0.254) (xy 0.5334 0.254)
				(xy 0.5334 0.2794)
			)
			(stroke
				(width 0)
				(type default)
			)
			(fill no)
			(layer "F.CrtYd")
		)
		(pad "1" smd rect
			(at 0.40005 0 180)
			(size 0.4572 0.508)
			(layers "F.Cu" "F.Mask" "F.Paste")
			(net "PSU4_REMOTE_R2_P")
		)
		(pad "2" smd rect
			(at -0.40005 0 180)
			(size 0.4572 0.508)
			(layers "F.Cu" "F.Mask" "F.Paste")
			(net "P12V")
		)
	)
	(footprint ""
		(layer "F.Cu")
		(at 80.662018 -18.749772 -90)
		(property "Reference" "C6"
			(at -1.75133 0.018796 90)
			(unlocked yes)
			(layer "F.SilkS")
			(effects
				(font
					(size 0.7874 0.5842)
					(thickness 0.1524)
				)
				(justify left)
			)
		)
		(property "Value" ""
			(at 0 0 270)
			(layer "F.Fab")
			(effects
				(font
					(size 1.27 1.27)
				)
			)
		)
		(duplicate_pad_numbers_are_jumpers no)
		(fp_line
			(start -0.7874 0.4064)
			(end -0.7874 -0.4064)
			(stroke
				(width 0.1524)
				(type default)
			)
			(layer "F.SilkS")
		)
		(fp_line
			(start 0.7874 0.4064)
			(end -0.7874 0.4064)
			(stroke
				(width 0.1524)
				(type default)
			)
			(layer "F.SilkS")
		)
		(fp_line
			(start 0 0.381)
			(end 0 -0.381)
			(stroke
				(width 0.1524)
				(type default)
			)
			(layer "F.SilkS")
		)
		(fp_line
			(start -0.7874 -0.4064)
			(end 0.7874 -0.4064)
			(stroke
				(width 0.1524)
				(type default)
			)
			(layer "F.SilkS")
		)
		(fp_line
			(start 0.7874 -0.4064)
			(end 0.7874 0.4064)
			(stroke
				(width 0.1524)
				(type default)
			)
			(layer "F.SilkS")
		)
		(fp_poly
			(pts
				(xy -0.5334 0.254) (xy -0.635 0.254) (xy -0.635 0.2286) (xy -0.635 -0.254) (xy -0.5334 -0.254) (xy -0.5334 -0.2794)
				(xy 0.5334 -0.2794) (xy 0.5334 -0.254) (xy 0.635 -0.254) (xy 0.635 0.254) (xy 0.5334 0.254) (xy 0.5334 0.2794)
				(xy -0.508 0.2794) (xy -0.5334 0.2794)
			)
			(stroke
				(width 0)
				(type default)
			)
			(fill no)
			(layer "F.CrtYd")
		)
		(pad "1" smd rect
			(at 0.40005 0 270)
			(size 0.4572 0.508)
			(layers "F.Cu" "F.Mask" "F.Paste")
			(net "P12V")
		)
		(pad "2" smd rect
			(at -0.40005 0 270)
			(size 0.4572 0.508)
			(layers "F.Cu" "F.Mask" "F.Paste")
			(net "GND")
		)
	)
	(footprint ""
		(layer "F.Cu")
		(at 13.463778 -324.01002 180)
		(property "Reference" "R146"
			(at -1.597406 -0.03556 0)
			(unlocked yes)
			(layer "F.SilkS")
			(effects
				(font
					(size 0.7874 0.5842)
					(thickness 0.1524)
				)
				(justify left)
			)
		)
		(property "Value" ""
			(at 0 0 180)
			(layer "F.Fab")
			(effects
				(font
					(size 1.27 1.27)
				)
			)
		)
		(duplicate_pad_numbers_are_jumpers no)
		(fp_line
			(start 0.7874 0.4064)
			(end -0.7874 0.4064)
			(stroke
				(width 0.1524)
				(type default)
			)
			(layer "F.SilkS")
		)
		(fp_line
			(start 0.7874 -0.4064)
			(end 0.7874 0.4064)
			(stroke
				(width 0.1524)
				(type default)
			)
			(layer "F.SilkS")
		)
		(fp_line
			(start -0.7874 0.4064)
			(end -0.7874 -0.4064)
			(stroke
				(width 0.1524)
				(type default)
			)
			(layer "F.SilkS")
		)
		(fp_line
			(start -0.7874 -0.4064)
			(end 0.7874 -0.4064)
			(stroke
				(width 0.1524)
				(type default)
			)
			(layer "F.SilkS")
		)
		(fp_poly
			(pts
				(xy -0.508 0.2794) (xy -0.508 0.2286) (xy -0.635 0.2286) (xy -0.635 -0.254) (xy -0.5334 -0.254)
				(xy -0.5334 -0.2794) (xy 0.5334 -0.2794) (xy 0.5334 -0.254) (xy 0.635 -0.254) (xy 0.635 0.254) (xy 0.5334 0.254)
				(xy 0.5334 0.2794)
			)
			(stroke
				(width 0)
				(type default)
			)
			(fill no)
			(layer "F.CrtYd")
		)
		(pad "1" smd rect
			(at 0.40005 0 180)
			(size 0.4572 0.508)
			(layers "F.Cu" "F.Mask" "F.Paste")
			(net "FAN5_TACH")
		)
		(pad "2" smd rect
			(at -0.40005 0 180)
			(size 0.4572 0.508)
			(layers "F.Cu" "F.Mask" "F.Paste")
			(net "P12V")
		)
	)
	(footprint ""
		(layer "F.Cu")
		(at 70.555104 -127.633476 90)
		(property "Reference" "C25"
			(at 1.102868 0.090932 90)
			(unlocked yes)
			(layer "F.SilkS")
			(effects
				(font
					(size 0.7874 0.5842)
					(thickness 0.1524)
				)
				(justify left)
			)
		)
		(property "Value" ""
			(at 0 0 90)
			(layer "F.Fab")
			(effects
				(font
					(size 1.27 1.27)
				)
			)
		)
		(duplicate_pad_numbers_are_jumpers no)
		(fp_line
			(start 0.7874 -0.4064)
			(end 0.7874 0.4064)
			(stroke
				(width 0.1524)
				(type default)
			)
			(layer "F.SilkS")
		)
		(fp_line
			(start -0.7874 -0.4064)
			(end 0.7874 -0.4064)
			(stroke
				(width 0.1524)
				(type default)
			)
			(layer "F.SilkS")
		)
		(fp_line
			(start 0 0.381)
			(end 0 -0.381)
			(stroke
				(width 0.1524)
				(type default)
			)
			(layer "F.SilkS")
		)
		(fp_line
			(start 0.7874 0.4064)
			(end -0.7874 0.4064)
			(stroke
				(width 0.1524)
				(type default)
			)
			(layer "F.SilkS")
		)
		(fp_line
			(start -0.7874 0.4064)
			(end -0.7874 -0.4064)
			(stroke
				(width 0.1524)
				(type default)
			)
			(layer "F.SilkS")
		)
		(fp_poly
			(pts
				(xy -0.5334 0.254) (xy -0.635 0.254) (xy -0.635 0.2286) (xy -0.635 -0.254) (xy -0.5334 -0.254) (xy -0.5334 -0.2794)
				(xy 0.5334 -0.2794) (xy 0.5334 -0.254) (xy 0.635 -0.254) (xy 0.635 0.254) (xy 0.5334 0.254) (xy 0.5334 0.2794)
				(xy -0.508 0.2794) (xy -0.5334 0.2794)
			)
			(stroke
				(width 0)
				(type default)
			)
			(fill no)
			(layer "F.CrtYd")
		)
		(pad "1" smd rect
			(at 0.40005 0 90)
			(size 0.4572 0.508)
			(layers "F.Cu" "F.Mask" "F.Paste")
			(net "P12V")
		)
		(pad "2" smd rect
			(at -0.40005 0 90)
			(size 0.4572 0.508)
			(layers "F.Cu" "F.Mask" "F.Paste")
			(net "GND")
		)
	)
	(footprint ""
		(layer "F.Cu")
		(at 68.246244 -216.615772 90)
		(property "Reference" "C41"
			(at 1.187196 -0.117856 90)
			(unlocked yes)
			(layer "F.SilkS")
			(effects
				(font
					(size 0.7874 0.5842)
					(thickness 0.1524)
				)
				(justify left)
			)
		)
		(property "Value" ""
			(at 0 0 90)
			(layer "F.Fab")
			(effects
				(font
					(size 1.27 1.27)
				)
			)
		)
		(duplicate_pad_numbers_are_jumpers no)
		(fp_line
			(start 0.7874 -0.4064)
			(end 0.7874 0.4064)
			(stroke
				(width 0.1524)
				(type default)
			)
			(layer "F.SilkS")
		)
		(fp_line
			(start -0.7874 -0.4064)
			(end 0.7874 -0.4064)
			(stroke
				(width 0.1524)
				(type default)
			)
			(layer "F.SilkS")
		)
		(fp_line
			(start 0 0.381)
			(end 0 -0.381)
			(stroke
				(width 0.1524)
				(type default)
			)
			(layer "F.SilkS")
		)
		(fp_line
			(start 0.7874 0.4064)
			(end -0.7874 0.4064)
			(stroke
				(width 0.1524)
				(type default)
			)
			(layer "F.SilkS")
		)
		(fp_line
			(start -0.7874 0.4064)
			(end -0.7874 -0.4064)
			(stroke
				(width 0.1524)
				(type default)
			)
			(layer "F.SilkS")
		)
		(fp_poly
			(pts
				(xy -0.5334 0.254) (xy -0.635 0.254) (xy -0.635 0.2286) (xy -0.635 -0.254) (xy -0.5334 -0.254) (xy -0.5334 -0.2794)
				(xy 0.5334 -0.2794) (xy 0.5334 -0.254) (xy 0.635 -0.254) (xy 0.635 0.254) (xy 0.5334 0.254) (xy 0.5334 0.2794)
				(xy -0.508 0.2794) (xy -0.5334 0.2794)
			)
			(stroke
				(width 0)
				(type default)
			)
			(fill no)
			(layer "F.CrtYd")
		)
		(pad "1" smd rect
			(at 0.40005 0 90)
			(size 0.4572 0.508)
			(layers "F.Cu" "F.Mask" "F.Paste")
			(net "P12V")
		)
		(pad "2" smd rect
			(at -0.40005 0 90)
			(size 0.4572 0.508)
			(layers "F.Cu" "F.Mask" "F.Paste")
			(net "GND")
		)
	)
	(footprint ""
		(layer "F.Cu")
		(at 72.953626 -472.101672 180)
		(property "Reference" "R132"
			(at 1.12141 -1.136904 0)
			(unlocked yes)
			(layer "F.SilkS")
			(effects
				(font
					(size 0.7874 0.5842)
					(thickness 0.1524)
				)
				(justify left)
			)
		)
		(property "Value" ""
			(at 0 0 180)
			(layer "F.Fab")
			(effects
				(font
					(size 1.27 1.27)
				)
			)
		)
		(duplicate_pad_numbers_are_jumpers no)
		(fp_line
			(start 0.7874 0.4064)
			(end -0.7874 0.4064)
			(stroke
				(width 0.1524)
				(type default)
			)
			(layer "F.SilkS")
		)
		(fp_line
			(start 0.7874 -0.4064)
			(end 0.7874 0.4064)
			(stroke
				(width 0.1524)
				(type default)
			)
			(layer "F.SilkS")
		)
		(fp_line
			(start -0.7874 0.4064)
			(end -0.7874 -0.4064)
			(stroke
				(width 0.1524)
				(type default)
			)
			(layer "F.SilkS")
		)
		(fp_line
			(start -0.7874 -0.4064)
			(end 0.7874 -0.4064)
			(stroke
				(width 0.1524)
				(type default)
			)
			(layer "F.SilkS")
		)
		(fp_poly
			(pts
				(xy -0.508 0.2794) (xy -0.508 0.2286) (xy -0.635 0.2286) (xy -0.635 -0.254) (xy -0.5334 -0.254)
				(xy -0.5334 -0.2794) (xy 0.5334 -0.2794) (xy 0.5334 -0.254) (xy 0.635 -0.254) (xy 0.635 0.254) (xy 0.5334 0.254)
				(xy 0.5334 0.2794)
			)
			(stroke
				(width 0)
				(type default)
			)
			(fill no)
			(layer "F.CrtYd")
		)
		(pad "1" smd rect
			(at 0.40005 0 180)
			(size 0.4572 0.508)
			(layers "F.Cu" "F.Mask" "F.Paste")
			(net "PSU6_REMOTE_R2_N")
		)
		(pad "2" smd rect
			(at -0.40005 0 180)
			(size 0.4572 0.508)
			(layers "F.Cu" "F.Mask" "F.Paste")
			(net "GND")
		)
	)
	(footprint ""
		(layer "F.Cu")
		(at 67.187064 -127.633476 90)
		(property "Reference" "C28"
			(at 1.21158 -0.185674 90)
			(unlocked yes)
			(layer "F.SilkS")
			(effects
				(font
					(size 0.7874 0.5842)
					(thickness 0.1524)
				)
				(justify left)
			)
		)
		(property "Value" ""
			(at 0 0 90)
			(layer "F.Fab")
			(effects
				(font
					(size 1.27 1.27)
				)
			)
		)
		(duplicate_pad_numbers_are_jumpers no)
		(fp_line
			(start 0.7874 -0.4064)
			(end 0.7874 0.4064)
			(stroke
				(width 0.1524)
				(type default)
			)
			(layer "F.SilkS")
		)
		(fp_line
			(start -0.7874 -0.4064)
			(end 0.7874 -0.4064)
			(stroke
				(width 0.1524)
				(type default)
			)
			(layer "F.SilkS")
		)
		(fp_line
			(start 0 0.381)
			(end 0 -0.381)
			(stroke
				(width 0.1524)
				(type default)
			)
			(layer "F.SilkS")
		)
		(fp_line
			(start 0.7874 0.4064)
			(end -0.7874 0.4064)
			(stroke
				(width 0.1524)
				(type default)
			)
			(layer "F.SilkS")
		)
		(fp_line
			(start -0.7874 0.4064)
			(end -0.7874 -0.4064)
			(stroke
				(width 0.1524)
				(type default)
			)
			(layer "F.SilkS")
		)
		(fp_poly
			(pts
				(xy -0.5334 0.254) (xy -0.635 0.254) (xy -0.635 0.2286) (xy -0.635 -0.254) (xy -0.5334 -0.254) (xy -0.5334 -0.2794)
				(xy 0.5334 -0.2794) (xy 0.5334 -0.254) (xy 0.635 -0.254) (xy 0.635 0.254) (xy 0.5334 0.254) (xy 0.5334 0.2794)
				(xy -0.508 0.2794) (xy -0.5334 0.2794)
			)
			(stroke
				(width 0)
				(type default)
			)
			(fill no)
			(layer "F.CrtYd")
		)
		(pad "1" smd rect
			(at 0.40005 0 90)
			(size 0.4572 0.508)
			(layers "F.Cu" "F.Mask" "F.Paste")
			(net "P12V")
		)
		(pad "2" smd rect
			(at -0.40005 0 90)
			(size 0.4572 0.508)
			(layers "F.Cu" "F.Mask" "F.Paste")
			(net "GND")
		)
	)
	(footprint ""
		(layer "F.Cu")
		(at 72.284082 -439.03646 90)
		(property "Reference" "C75"
			(at 1.327912 0.132334 90)
			(unlocked yes)
			(layer "F.SilkS")
			(effects
				(font
					(size 0.7874 0.5842)
					(thickness 0.1524)
				)
				(justify left)
			)
		)
		(property "Value" ""
			(at 0 0 90)
			(layer "F.Fab")
			(effects
				(font
					(size 1.27 1.27)
				)
			)
		)
		(duplicate_pad_numbers_are_jumpers no)
		(fp_line
			(start 0.7874 -0.4064)
			(end 0.7874 0.4064)
			(stroke
				(width 0.1524)
				(type default)
			)
			(layer "F.SilkS")
		)
		(fp_line
			(start -0.7874 -0.4064)
			(end 0.7874 -0.4064)
			(stroke
				(width 0.1524)
				(type default)
			)
			(layer "F.SilkS")
		)
		(fp_line
			(start 0 0.381)
			(end 0 -0.381)
			(stroke
				(width 0.1524)
				(type default)
			)
			(layer "F.SilkS")
		)
		(fp_line
			(start 0.7874 0.4064)
			(end -0.7874 0.4064)
			(stroke
				(width 0.1524)
				(type default)
			)
			(layer "F.SilkS")
		)
		(fp_line
			(start -0.7874 0.4064)
			(end -0.7874 -0.4064)
			(stroke
				(width 0.1524)
				(type default)
			)
			(layer "F.SilkS")
		)
		(fp_poly
			(pts
				(xy -0.5334 0.254) (xy -0.635 0.254) (xy -0.635 0.2286) (xy -0.635 -0.254) (xy -0.5334 -0.254) (xy -0.5334 -0.2794)
				(xy 0.5334 -0.2794) (xy 0.5334 -0.254) (xy 0.635 -0.254) (xy 0.635 0.254) (xy 0.5334 0.254) (xy 0.5334 0.2794)
				(xy -0.508 0.2794) (xy -0.5334 0.2794)
			)
			(stroke
				(width 0)
				(type default)
			)
			(fill no)
			(layer "F.CrtYd")
		)
		(pad "1" smd rect
			(at 0.40005 0 90)
			(size 0.4572 0.508)
			(layers "F.Cu" "F.Mask" "F.Paste")
			(net "P12V")
		)
		(pad "2" smd rect
			(at -0.40005 0 90)
			(size 0.4572 0.508)
			(layers "F.Cu" "F.Mask" "F.Paste")
			(net "GND")
		)
	)
	(footprint ""
		(layer "F.Cu")
		(at 26.001726 -101.689408)
		(property "Reference" "R135"
			(at -4.183888 -0.051562 0)
			(unlocked yes)
			(layer "F.SilkS")
			(effects
				(font
					(size 0.7874 0.5842)
					(thickness 0.1524)
				)
				(justify left)
			)
		)
		(property "Value" ""
			(at 0 0 0)
			(layer "F.Fab")
			(effects
				(font
					(size 1.27 1.27)
				)
			)
		)
		(duplicate_pad_numbers_are_jumpers no)
		(fp_line
			(start -0.7874 -0.4064)
			(end 0.7874 -0.4064)
			(stroke
				(width 0.1524)
				(type default)
			)
			(layer "F.SilkS")
		)
		(fp_line
			(start -0.7874 0.4064)
			(end -0.7874 -0.4064)
			(stroke
				(width 0.1524)
				(type default)
			)
			(layer "F.SilkS")
		)
		(fp_line
			(start 0.7874 -0.4064)
			(end 0.7874 0.4064)
			(stroke
				(width 0.1524)
				(type default)
			)
			(layer "F.SilkS")
		)
		(fp_line
			(start 0.7874 0.4064)
			(end -0.7874 0.4064)
			(stroke
				(width 0.1524)
				(type default)
			)
			(layer "F.SilkS")
		)
		(fp_poly
			(pts
				(xy -0.508 0.2794) (xy -0.508 0.2286) (xy -0.635 0.2286) (xy -0.635 -0.254) (xy -0.5334 -0.254)
				(xy -0.5334 -0.2794) (xy 0.5334 -0.2794) (xy 0.5334 -0.254) (xy 0.635 -0.254) (xy 0.635 0.254) (xy 0.5334 0.254)
				(xy 0.5334 0.2794)
			)
			(stroke
				(width 0)
				(type default)
			)
			(fill no)
			(layer "F.CrtYd")
		)
		(pad "1" smd rect
			(at 0.40005 0)
			(size 0.4572 0.508)
			(layers "F.Cu" "F.Mask" "F.Paste")
			(net "PSU2_CSAHRE")
		)
		(pad "2" smd rect
			(at -0.40005 0)
			(size 0.4572 0.508)
			(layers "F.Cu" "F.Mask" "F.Paste")
			(net "PSU_CSAHRE")
		)
	)
	(footprint ""
		(layer "F.Cu")
		(at 45.911516 -260.355588 180)
		(property "Reference" "R103"
			(at 4.696206 0.233172 0)
			(unlocked yes)
			(layer "F.SilkS")
			(effects
				(font
					(size 0.7874 0.5842)
					(thickness 0.1524)
				)
				(justify left)
			)
		)
		(property "Value" ""
			(at 0 0 180)
			(layer "F.Fab")
			(effects
				(font
					(size 1.27 1.27)
				)
			)
		)
		(duplicate_pad_numbers_are_jumpers no)
		(fp_line
			(start 0.7874 0.4064)
			(end -0.7874 0.4064)
			(stroke
				(width 0.1524)
				(type default)
			)
			(layer "F.SilkS")
		)
		(fp_line
			(start 0.7874 -0.4064)
			(end 0.7874 0.4064)
			(stroke
				(width 0.1524)
				(type default)
			)
			(layer "F.SilkS")
		)
		(fp_line
			(start -0.7874 0.4064)
			(end -0.7874 -0.4064)
			(stroke
				(width 0.1524)
				(type default)
			)
			(layer "F.SilkS")
		)
		(fp_line
			(start -0.7874 -0.4064)
			(end 0.7874 -0.4064)
			(stroke
				(width 0.1524)
				(type default)
			)
			(layer "F.SilkS")
		)
		(fp_poly
			(pts
				(xy -0.508 0.2794) (xy -0.508 0.2286) (xy -0.635 0.2286) (xy -0.635 -0.254) (xy -0.5334 -0.254)
				(xy -0.5334 -0.2794) (xy 0.5334 -0.2794) (xy 0.5334 -0.254) (xy 0.635 -0.254) (xy 0.635 0.254) (xy 0.5334 0.254)
				(xy 0.5334 0.2794)
			)
			(stroke
				(width 0)
				(type default)
			)
			(fill no)
			(layer "F.CrtYd")
		)
		(pad "1" smd rect
			(at 0.40005 0 180)
			(size 0.4572 0.508)
			(layers "F.Cu" "F.Mask" "F.Paste")
			(net "PSU5_REMOTE_R_N")
		)
		(pad "2" smd rect
			(at -0.40005 0 180)
			(size 0.4572 0.508)
			(layers "F.Cu" "F.Mask" "F.Paste")
			(net "GND")
		)
	)
	(footprint ""
		(layer "F.Cu")
		(at 73.963276 -241.518694 -90)
		(property "Reference" "C37"
			(at 0.73406 -3.745992 90)
			(unlocked yes)
			(layer "F.SilkS")
			(effects
				(font
					(size 0.7874 0.5842)
					(thickness 0.1524)
				)
				(justify left)
			)
		)
		(property "Value" ""
			(at 0 0 270)
			(layer "F.Fab")
			(effects
				(font
					(size 1.27 1.27)
				)
			)
		)
		(duplicate_pad_numbers_are_jumpers no)
		(fp_line
			(start -0.7874 0.4064)
			(end -0.7874 -0.4064)
			(stroke
				(width 0.1524)
				(type default)
			)
			(layer "F.SilkS")
		)
		(fp_line
			(start 0.7874 0.4064)
			(end -0.7874 0.4064)
			(stroke
				(width 0.1524)
				(type default)
			)
			(layer "F.SilkS")
		)
		(fp_line
			(start 0 0.381)
			(end 0 -0.381)
			(stroke
				(width 0.1524)
				(type default)
			)
			(layer "F.SilkS")
		)
		(fp_line
			(start -0.7874 -0.4064)
			(end 0.7874 -0.4064)
			(stroke
				(width 0.1524)
				(type default)
			)
			(layer "F.SilkS")
		)
		(fp_line
			(start 0.7874 -0.4064)
			(end 0.7874 0.4064)
			(stroke
				(width 0.1524)
				(type default)
			)
			(layer "F.SilkS")
		)
		(fp_poly
			(pts
				(xy -0.5334 0.254) (xy -0.635 0.254) (xy -0.635 0.2286) (xy -0.635 -0.254) (xy -0.5334 -0.254) (xy -0.5334 -0.2794)
				(xy 0.5334 -0.2794) (xy 0.5334 -0.254) (xy 0.635 -0.254) (xy 0.635 0.254) (xy 0.5334 0.254) (xy 0.5334 0.2794)
				(xy -0.508 0.2794) (xy -0.5334 0.2794)
			)
			(stroke
				(width 0)
				(type default)
			)
			(fill no)
			(layer "F.CrtYd")
		)
		(pad "1" smd rect
			(at 0.40005 0 270)
			(size 0.4572 0.508)
			(layers "F.Cu" "F.Mask" "F.Paste")
			(net "P12V")
		)
		(pad "2" smd rect
			(at -0.40005 0 270)
			(size 0.4572 0.508)
			(layers "F.Cu" "F.Mask" "F.Paste")
			(net "GND")
		)
	)
	(footprint ""
		(layer "F.Cu")
		(at 70.678548 -483.48138 90)
		(property "Reference" "C83"
			(at -4.10845 0.070104 90)
			(unlocked yes)
			(layer "F.SilkS")
			(effects
				(font
					(size 0.7874 0.5842)
					(thickness 0.1524)
				)
				(justify left)
			)
		)
		(property "Value" ""
			(at 0 0 90)
			(layer "F.Fab")
			(effects
				(font
					(size 1.27 1.27)
				)
			)
		)
		(duplicate_pad_numbers_are_jumpers no)
		(fp_line
			(start 0.7874 -0.4064)
			(end 0.7874 0.4064)
			(stroke
				(width 0.1524)
				(type default)
			)
			(layer "F.SilkS")
		)
		(fp_line
			(start -0.7874 -0.4064)
			(end 0.7874 -0.4064)
			(stroke
				(width 0.1524)
				(type default)
			)
			(layer "F.SilkS")
		)
		(fp_line
			(start 0 0.381)
			(end 0 -0.381)
			(stroke
				(width 0.1524)
				(type default)
			)
			(layer "F.SilkS")
		)
		(fp_line
			(start 0.7874 0.4064)
			(end -0.7874 0.4064)
			(stroke
				(width 0.1524)
				(type default)
			)
			(layer "F.SilkS")
		)
		(fp_line
			(start -0.7874 0.4064)
			(end -0.7874 -0.4064)
			(stroke
				(width 0.1524)
				(type default)
			)
			(layer "F.SilkS")
		)
		(fp_poly
			(pts
				(xy -0.5334 0.254) (xy -0.635 0.254) (xy -0.635 0.2286) (xy -0.635 -0.254) (xy -0.5334 -0.254) (xy -0.5334 -0.2794)
				(xy 0.5334 -0.2794) (xy 0.5334 -0.254) (xy 0.635 -0.254) (xy 0.635 0.254) (xy 0.5334 0.254) (xy 0.5334 0.2794)
				(xy -0.508 0.2794) (xy -0.5334 0.2794)
			)
			(stroke
				(width 0)
				(type default)
			)
			(fill no)
			(layer "F.CrtYd")
		)
		(pad "1" smd rect
			(at 0.40005 0 90)
			(size 0.4572 0.508)
			(layers "F.Cu" "F.Mask" "F.Paste")
			(net "P12V")
		)
		(pad "2" smd rect
			(at -0.40005 0 90)
			(size 0.4572 0.508)
			(layers "F.Cu" "F.Mask" "F.Paste")
			(net "GND")
		)
	)
	(footprint ""
		(layer "F.Cu")
		(at 26.068274 -185.521092)
		(property "Reference" "R70"
			(at -3.997198 0.128524 0)
			(unlocked yes)
			(layer "F.SilkS")
			(effects
				(font
					(size 0.7874 0.5842)
					(thickness 0.1524)
				)
				(justify left)
			)
		)
		(property "Value" ""
			(at 0 0 0)
			(layer "F.Fab")
			(effects
				(font
					(size 1.27 1.27)
				)
			)
		)
		(duplicate_pad_numbers_are_jumpers no)
		(fp_line
			(start -0.7874 -0.4064)
			(end 0.7874 -0.4064)
			(stroke
				(width 0.1524)
				(type default)
			)
			(layer "F.SilkS")
		)
		(fp_line
			(start -0.7874 0.4064)
			(end -0.7874 -0.4064)
			(stroke
				(width 0.1524)
				(type default)
			)
			(layer "F.SilkS")
		)
		(fp_line
			(start 0.7874 -0.4064)
			(end 0.7874 0.4064)
			(stroke
				(width 0.1524)
				(type default)
			)
			(layer "F.SilkS")
		)
		(fp_line
			(start 0.7874 0.4064)
			(end -0.7874 0.4064)
			(stroke
				(width 0.1524)
				(type default)
			)
			(layer "F.SilkS")
		)
		(fp_poly
			(pts
				(xy -0.508 0.2794) (xy -0.508 0.2286) (xy -0.635 0.2286) (xy -0.635 -0.254) (xy -0.5334 -0.254)
				(xy -0.5334 -0.2794) (xy 0.5334 -0.2794) (xy 0.5334 -0.254) (xy 0.635 -0.254) (xy 0.635 0.254) (xy 0.5334 0.254)
				(xy 0.5334 0.2794)
			)
			(stroke
				(width 0)
				(type default)
			)
			(fill no)
			(layer "F.CrtYd")
		)
		(pad "1" smd rect
			(at 0.40005 0)
			(size 0.4572 0.508)
			(layers "F.Cu" "F.Mask" "F.Paste")
			(net "PSU3_PS_KILL")
		)
		(pad "2" smd rect
			(at -0.40005 0)
			(size 0.4572 0.508)
			(layers "F.Cu" "F.Mask" "F.Paste")
			(net "P12V_STBY")
		)
	)
	(footprint ""
		(layer "F.Cu")
		(at 39.97325 -192.216278 180)
		(property "Reference" "R10"
			(at -1.626616 -0.081026 0)
			(unlocked yes)
			(layer "F.SilkS")
			(effects
				(font
					(size 0.7874 0.5842)
					(thickness 0.1524)
				)
				(justify left)
			)
		)
		(property "Value" ""
			(at 0 0 180)
			(layer "F.Fab")
			(effects
				(font
					(size 1.27 1.27)
				)
			)
		)
		(duplicate_pad_numbers_are_jumpers no)
		(fp_line
			(start 0.7874 0.4064)
			(end -0.7874 0.4064)
			(stroke
				(width 0.1524)
				(type default)
			)
			(layer "F.SilkS")
		)
		(fp_line
			(start 0.7874 -0.4064)
			(end 0.7874 0.4064)
			(stroke
				(width 0.1524)
				(type default)
			)
			(layer "F.SilkS")
		)
		(fp_line
			(start -0.7874 0.4064)
			(end -0.7874 -0.4064)
			(stroke
				(width 0.1524)
				(type default)
			)
			(layer "F.SilkS")
		)
		(fp_line
			(start -0.7874 -0.4064)
			(end 0.7874 -0.4064)
			(stroke
				(width 0.1524)
				(type default)
			)
			(layer "F.SilkS")
		)
		(fp_poly
			(pts
				(xy -0.508 0.2794) (xy -0.508 0.2286) (xy -0.635 0.2286) (xy -0.635 -0.254) (xy -0.5334 -0.254)
				(xy -0.5334 -0.2794) (xy 0.5334 -0.2794) (xy 0.5334 -0.254) (xy 0.635 -0.254) (xy 0.635 0.254) (xy 0.5334 0.254)
				(xy 0.5334 0.2794)
			)
			(stroke
				(width 0)
				(type default)
			)
			(fill no)
			(layer "F.CrtYd")
		)
		(pad "1" smd rect
			(at 0.40005 0 180)
			(size 0.4572 0.508)
			(layers "F.Cu" "F.Mask" "F.Paste")
			(net "PSU3_RETURN")
		)
		(pad "2" smd rect
			(at -0.40005 0 180)
			(size 0.4572 0.508)
			(layers "F.Cu" "F.Mask" "F.Paste")
			(net "GND")
		)
	)
	(footprint ""
		(layer "F.Cu")
		(at 46.385734 -244.518434 180)
		(property "Reference" "R91"
			(at 4.322064 -0.051816 0)
			(unlocked yes)
			(layer "F.SilkS")
			(effects
				(font
					(size 0.7874 0.5842)
					(thickness 0.1524)
				)
				(justify left)
			)
		)
		(property "Value" ""
			(at 0 0 180)
			(layer "F.Fab")
			(effects
				(font
					(size 1.27 1.27)
				)
			)
		)
		(duplicate_pad_numbers_are_jumpers no)
		(fp_line
			(start 0.7874 0.4064)
			(end -0.7874 0.4064)
			(stroke
				(width 0.1524)
				(type default)
			)
			(layer "F.SilkS")
		)
		(fp_line
			(start 0.7874 -0.4064)
			(end 0.7874 0.4064)
			(stroke
				(width 0.1524)
				(type default)
			)
			(layer "F.SilkS")
		)
		(fp_line
			(start -0.7874 0.4064)
			(end -0.7874 -0.4064)
			(stroke
				(width 0.1524)
				(type default)
			)
			(layer "F.SilkS")
		)
		(fp_line
			(start -0.7874 -0.4064)
			(end 0.7874 -0.4064)
			(stroke
				(width 0.1524)
				(type default)
			)
			(layer "F.SilkS")
		)
		(fp_poly
			(pts
				(xy -0.508 0.2794) (xy -0.508 0.2286) (xy -0.635 0.2286) (xy -0.635 -0.254) (xy -0.5334 -0.254)
				(xy -0.5334 -0.2794) (xy 0.5334 -0.2794) (xy 0.5334 -0.254) (xy 0.635 -0.254) (xy 0.635 0.254) (xy 0.5334 0.254)
				(xy 0.5334 0.2794)
			)
			(stroke
				(width 0)
				(type default)
			)
			(fill no)
			(layer "F.CrtYd")
		)
		(pad "1" smd rect
			(at 0.40005 0 180)
			(size 0.4572 0.508)
			(layers "F.Cu" "F.Mask" "F.Paste")
			(net "PSU2_REMOTE_R_N")
		)
		(pad "2" smd rect
			(at -0.40005 0 180)
			(size 0.4572 0.508)
			(layers "F.Cu" "F.Mask" "F.Paste")
			(net "GND")
		)
	)
	(footprint ""
		(layer "F.Cu")
		(at 69.982334 -374.411748 -90)
		(property "Reference" "C58"
			(at -2.675128 0.148844 90)
			(unlocked yes)
			(layer "F.SilkS")
			(effects
				(font
					(size 0.7874 0.5842)
					(thickness 0.1524)
				)
				(justify left)
			)
		)
		(property "Value" ""
			(at 0 0 270)
			(layer "F.Fab")
			(effects
				(font
					(size 1.27 1.27)
				)
			)
		)
		(duplicate_pad_numbers_are_jumpers no)
		(fp_line
			(start -0.7874 0.4064)
			(end -0.7874 -0.4064)
			(stroke
				(width 0.1524)
				(type default)
			)
			(layer "F.SilkS")
		)
		(fp_line
			(start 0.7874 0.4064)
			(end -0.7874 0.4064)
			(stroke
				(width 0.1524)
				(type default)
			)
			(layer "F.SilkS")
		)
		(fp_line
			(start 0 0.381)
			(end 0 -0.381)
			(stroke
				(width 0.1524)
				(type default)
			)
			(layer "F.SilkS")
		)
		(fp_line
			(start -0.7874 -0.4064)
			(end 0.7874 -0.4064)
			(stroke
				(width 0.1524)
				(type default)
			)
			(layer "F.SilkS")
		)
		(fp_line
			(start 0.7874 -0.4064)
			(end 0.7874 0.4064)
			(stroke
				(width 0.1524)
				(type default)
			)
			(layer "F.SilkS")
		)
		(fp_poly
			(pts
				(xy -0.5334 0.254) (xy -0.635 0.254) (xy -0.635 0.2286) (xy -0.635 -0.254) (xy -0.5334 -0.254) (xy -0.5334 -0.2794)
				(xy 0.5334 -0.2794) (xy 0.5334 -0.254) (xy 0.635 -0.254) (xy 0.635 0.254) (xy 0.5334 0.254) (xy 0.5334 0.2794)
				(xy -0.508 0.2794) (xy -0.5334 0.2794)
			)
			(stroke
				(width 0)
				(type default)
			)
			(fill no)
			(layer "F.CrtYd")
		)
		(pad "1" smd rect
			(at 0.40005 0 270)
			(size 0.4572 0.508)
			(layers "F.Cu" "F.Mask" "F.Paste")
			(net "P12V")
		)
		(pad "2" smd rect
			(at -0.40005 0 270)
			(size 0.4572 0.508)
			(layers "F.Cu" "F.Mask" "F.Paste")
			(net "GND")
		)
	)
	(footprint ""
		(layer "F.Cu")
		(at 27.33421 -197.033896 -90)
		(property "Reference" "R97"
			(at -1.141222 0.065278 90)
			(unlocked yes)
			(layer "F.SilkS")
			(effects
				(font
					(size 0.7874 0.5842)
					(thickness 0.1524)
				)
				(justify left)
			)
		)
		(property "Value" ""
			(at 0 0 270)
			(layer "F.Fab")
			(effects
				(font
					(size 1.27 1.27)
				)
			)
		)
		(duplicate_pad_numbers_are_jumpers no)
		(fp_line
			(start -0.7874 0.4064)
			(end -0.7874 -0.4064)
			(stroke
				(width 0.1524)
				(type default)
			)
			(layer "F.SilkS")
		)
		(fp_line
			(start 0.7874 0.4064)
			(end -0.7874 0.4064)
			(stroke
				(width 0.1524)
				(type default)
			)
			(layer "F.SilkS")
		)
		(fp_line
			(start -0.7874 -0.4064)
			(end 0.7874 -0.4064)
			(stroke
				(width 0.1524)
				(type default)
			)
			(layer "F.SilkS")
		)
		(fp_line
			(start 0.7874 -0.4064)
			(end 0.7874 0.4064)
			(stroke
				(width 0.1524)
				(type default)
			)
			(layer "F.SilkS")
		)
		(fp_poly
			(pts
				(xy -0.508 0.2794) (xy -0.508 0.2286) (xy -0.635 0.2286) (xy -0.635 -0.254) (xy -0.5334 -0.254)
				(xy -0.5334 -0.2794) (xy 0.5334 -0.2794) (xy 0.5334 -0.254) (xy 0.635 -0.254) (xy 0.635 0.254) (xy 0.5334 0.254)
				(xy 0.5334 0.2794)
			)
			(stroke
				(width 0)
				(type default)
			)
			(fill no)
			(layer "F.CrtYd")
		)
		(pad "1" smd rect
			(at 0.40005 0 270)
			(size 0.4572 0.508)
			(layers "F.Cu" "F.Mask" "F.Paste")
			(net "PSU3_REMOTE_N")
		)
		(pad "2" smd rect
			(at -0.40005 0 270)
			(size 0.4572 0.508)
			(layers "F.Cu" "F.Mask" "F.Paste")
			(net "PSU3_REMOTE_R_N")
		)
	)
	(footprint ""
		(layer "F.Cu")
		(at 30.45968 -260.130036)
		(property "Reference" "J3"
			(at -4.153662 5.745988 0)
			(unlocked yes)
			(layer "F.SilkS")
			(effects
				(font
					(size 0.7874 0.5842)
					(thickness 0.1524)
				)
				(justify left)
			)
		)
		(property "Value" ""
			(at 0 0 0)
			(layer "F.Fab")
			(effects
				(font
					(size 1.27 1.27)
				)
			)
		)
		(duplicate_pad_numbers_are_jumpers no)
		(fp_line
			(start -2.135124 -4.560062)
			(end -2.135124 83.300062)
			(stroke
				(width 0.1524)
				(type default)
			)
			(layer "F.SilkS")
		)
		(fp_line
			(start -2.135124 83.300062)
			(end 7.215124 83.300062)
			(stroke
				(width 0.1524)
				(type default)
			)
			(layer "F.SilkS")
		)
		(fp_line
			(start 7.215124 -4.560062)
			(end -2.135124 -4.560062)
			(stroke
				(width 0.1524)
				(type default)
			)
			(layer "F.SilkS")
		)
		(fp_line
			(start 7.215124 83.300062)
			(end 7.215124 -4.560062)
			(stroke
				(width 0.1524)
				(type default)
			)
			(layer "F.SilkS")
		)
		(fp_poly
			(pts
				(xy -2.758694 -0.014732) (xy -5.458714 -0.714756) (xy -5.458714 0.685292)
			)
			(stroke
				(width 0)
				(type default)
			)
			(fill yes)
			(layer "F.SilkS")
		)
		(fp_poly
			(pts
				(xy -2.28219 -0.127) (xy -4.98221 -0.827024) (xy -4.98221 0.573024)
			)
			(stroke
				(width 0)
				(type default)
			)
			(fill yes)
			(layer "B.SilkS")
		)
		(fp_poly
			(pts
				(xy -0.8636 -0.8636) (xy -0.8636 79.6036) (xy -0.8636 79.629) (xy 5.9436 79.629) (xy 5.9436 79.6036)
				(xy 5.9436 -0.8636) (xy 5.9436 -0.889) (xy -0.8636 -0.889)
			)
			(stroke
				(width 0)
				(type default)
			)
			(fill no)
			(layer "B.CrtYd")
		)
		(fp_rect
			(start -2.135124 -4.560062)
			(end 7.21487 83.300062)
			(stroke
				(width 0)
				(type default)
			)
			(fill no)
			(layer "F.CrtYd")
		)
		(fp_line
			(start -2.135124 -4.560062)
			(end 7.215124 -4.560062)
			(stroke
				(width 0.1)
				(type default)
			)
			(layer "F.Fab")
		)
		(fp_line
			(start -2.135124 83.300062)
			(end -2.135124 -4.560062)
			(stroke
				(width 0.1)
				(type default)
			)
			(layer "F.Fab")
		)
		(fp_line
			(start 7.215124 -4.560062)
			(end 7.215124 83.300062)
			(stroke
				(width 0.1)
				(type default)
			)
			(layer "F.Fab")
		)
		(fp_line
			(start 7.215124 83.300062)
			(end -2.135124 83.300062)
			(stroke
				(width 0.1)
				(type default)
			)
			(layer "F.Fab")
		)
		(fp_text user "32"
			(at -3.66268 79.554324 0)
			(unlocked yes)
			(layer "F.SilkS")
			(effects
				(font
					(size 0.7874 0.5842)
					(thickness 0.1524)
				)
				(justify left)
			)
		)
		(fp_text user "1"
			(at -3.093974 -0.810768 0)
			(unlocked yes)
			(layer "F.SilkS")
			(effects
				(font
					(size 0.7874 0.5842)
					(thickness 0.1524)
				)
				(justify left)
			)
		)
		(fp_text user "64"
			(at 7.495794 -0.366014 0)
			(unlocked yes)
			(layer "F.SilkS")
			(effects
				(font
					(size 0.7874 0.5842)
					(thickness 0.1524)
				)
				(justify left)
			)
		)
		(fp_text user "33"
			(at 7.680706 82.813906 0)
			(unlocked yes)
			(layer "F.SilkS")
			(effects
				(font
					(size 0.7874 0.5842)
					(thickness 0.1524)
				)
				(justify left)
			)
		)
		(fp_text user "1"
			(at -1.689608 -0.958596 0)
			(unlocked yes)
			(layer "B.SilkS")
			(effects
				(font
					(size 0.7874 0.5842)
					(thickness 0.1524)
				)
				(justify left mirror)
			)
		)
		(fp_text user "32"
			(at -0.73152 79.809086 0)
			(unlocked yes)
			(layer "B.SilkS")
			(effects
				(font
					(size 0.7874 0.5842)
					(thickness 0.1524)
				)
				(justify left mirror)
			)
		)
		(fp_text user "64"
			(at 5.89153 -1.71323 0)
			(unlocked yes)
			(layer "B.SilkS")
			(effects
				(font
					(size 0.7874 0.5842)
					(thickness 0.1524)
				)
				(justify left mirror)
			)
		)
		(fp_text user "33"
			(at 6.095238 82.893154 0)
			(unlocked yes)
			(layer "B.SilkS")
			(effects
				(font
					(size 0.7874 0.5842)
					(thickness 0.1524)
				)
				(justify left mirror)
			)
		)
		(pad "1" thru_hole rect
			(at 0 0 270)
			(size 1.6256 1.6256)
			(drill 1.1176)
			(layers "*.Cu" "*.Mask")
			(remove_unused_layers no)
			(net "P12V")
			(clearance 0)
			(padstack
				(mode front_inner_back)
				(layer "Inner"
					(shape circle)
					(size 1.6256 1.6256)
					(clearance 0)
				)
				(layer "B.Cu"
					(shape rect)
					(size 1.6256 1.6256)
					(clearance 0)
				)
			)
		)
		(pad "2" thru_hole circle
			(at 0 2.54 270)
			(size 1.6256 1.6256)
			(drill 1.1176)
			(layers "*.Cu" "*.Mask")
			(remove_unused_layers no)
			(net "P12V")
			(clearance 0)
		)
		(pad "3" thru_hole circle
			(at 0 5.08 270)
			(size 1.6256 1.6256)
			(drill 1.1176)
			(layers "*.Cu" "*.Mask")
			(remove_unused_layers no)
			(net "P12V")
			(clearance 0)
		)
		(pad "4" thru_hole circle
			(at 0 7.62 270)
			(size 1.6256 1.6256)
			(drill 1.1176)
			(layers "*.Cu" "*.Mask")
			(remove_unused_layers no)
			(net "P12V")
			(clearance 0)
		)
		(pad "5" thru_hole circle
			(at 0 10.16 270)
			(size 1.6256 1.6256)
			(drill 1.1176)
			(layers "*.Cu" "*.Mask")
			(remove_unused_layers no)
			(net "P12V")
			(clearance 0)
		)
		(pad "6" thru_hole circle
			(at 0 12.7 270)
			(size 1.6256 1.6256)
			(drill 1.1176)
			(layers "*.Cu" "*.Mask")
			(remove_unused_layers no)
			(net "P12V")
			(clearance 0)
		)
		(pad "7" thru_hole circle
			(at 0 15.24 270)
			(size 1.6256 1.6256)
			(drill 1.1176)
			(layers "*.Cu" "*.Mask")
			(remove_unused_layers no)
			(net "P12V")
			(clearance 0)
		)
		(pad "8" thru_hole circle
			(at 0 17.78 270)
			(size 1.6256 1.6256)
			(drill 1.1176)
			(layers "*.Cu" "*.Mask")
			(remove_unused_layers no)
			(net "P12V")
			(clearance 0)
		)
		(pad "9" thru_hole circle
			(at 0 20.32 270)
			(size 1.6256 1.6256)
			(drill 1.1176)
			(layers "*.Cu" "*.Mask")
			(remove_unused_layers no)
			(net "P12V")
			(clearance 0)
		)
		(pad "10" thru_hole circle
			(at 0 22.86 270)
			(size 1.6256 1.6256)
			(drill 1.1176)
			(layers "*.Cu" "*.Mask")
			(remove_unused_layers no)
			(net "P12V")
			(clearance 0)
		)
		(pad "11" thru_hole circle
			(at 0 25.4 270)
			(size 1.6256 1.6256)
			(drill 1.1176)
			(layers "*.Cu" "*.Mask")
			(remove_unused_layers no)
			(net "P12V")
			(clearance 0)
		)
		(pad "12" thru_hole circle
			(at 0 27.94 270)
			(size 1.6256 1.6256)
			(drill 1.1176)
			(layers "*.Cu" "*.Mask")
			(remove_unused_layers no)
			(net "P12V")
			(clearance 0)
		)
		(pad "13" thru_hole circle
			(at 0 30.48 270)
			(size 1.6256 1.6256)
			(drill 1.1176)
			(layers "*.Cu" "*.Mask")
			(remove_unused_layers no)
			(net "GND")
			(clearance 0)
		)
		(pad "14" thru_hole circle
			(at 0 33.02 270)
			(size 1.6256 1.6256)
			(drill 1.1176)
			(layers "*.Cu" "*.Mask")
			(remove_unused_layers no)
			(net "GND")
			(clearance 0)
		)
		(pad "15" thru_hole circle
			(at 0 35.56 270)
			(size 1.6256 1.6256)
			(drill 1.1176)
			(layers "*.Cu" "*.Mask")
			(remove_unused_layers no)
			(net "GND")
			(clearance 0)
		)
		(pad "16" thru_hole circle
			(at 0 38.1 270)
			(size 1.6256 1.6256)
			(drill 1.1176)
			(layers "*.Cu" "*.Mask")
			(remove_unused_layers no)
			(net "GND")
			(clearance 0)
		)
		(pad "17" thru_hole circle
			(at 0 40.64 270)
			(size 1.6256 1.6256)
			(drill 1.1176)
			(layers "*.Cu" "*.Mask")
			(remove_unused_layers no)
			(net "GND")
			(clearance 0)
		)
		(pad "18" thru_hole circle
			(at 0 43.18 270)
			(size 1.6256 1.6256)
			(drill 1.1176)
			(layers "*.Cu" "*.Mask")
			(remove_unused_layers no)
			(net "GND")
			(clearance 0)
		)
		(pad "19" thru_hole circle
			(at 0 45.72 270)
			(size 1.6256 1.6256)
			(drill 1.1176)
			(layers "*.Cu" "*.Mask")
			(remove_unused_layers no)
			(net "GND")
			(clearance 0)
		)
		(pad "20" thru_hole circle
			(at 0 48.26 270)
			(size 1.6256 1.6256)
			(drill 1.1176)
			(layers "*.Cu" "*.Mask")
			(remove_unused_layers no)
			(net "GND")
			(clearance 0)
		)
		(pad "21" thru_hole circle
			(at 0 50.8 270)
			(size 1.6256 1.6256)
			(drill 1.1176)
			(layers "*.Cu" "*.Mask")
			(remove_unused_layers no)
			(net "GND")
			(clearance 0)
		)
		(pad "22" thru_hole circle
			(at 0 53.34 270)
			(size 1.6256 1.6256)
			(drill 1.1176)
			(layers "*.Cu" "*.Mask")
			(remove_unused_layers no)
			(net "GND")
			(clearance 0)
		)
		(pad "23" thru_hole circle
			(at 0 55.88 270)
			(size 1.6256 1.6256)
			(drill 1.1176)
			(layers "*.Cu" "*.Mask")
			(remove_unused_layers no)
			(net "GND")
			(clearance 0)
		)
		(pad "24" thru_hole circle
			(at 0 58.42 270)
			(size 1.6256 1.6256)
			(drill 1.1176)
			(layers "*.Cu" "*.Mask")
			(remove_unused_layers no)
			(net "GND")
			(clearance 0)
		)
		(pad "25" thru_hole circle
			(at 0 60.96 270)
			(size 1.6256 1.6256)
			(drill 1.1176)
			(layers "*.Cu" "*.Mask")
			(remove_unused_layers no)
			(net "PHLOSS")
			(clearance 0)
		)
		(pad "26" thru_hole circle
			(at 0 63.5 270)
			(size 1.6256 1.6256)
			(drill 1.1176)
			(layers "*.Cu" "*.Mask")
			(remove_unused_layers no)
			(net "PSU3_REMOTE_N")
			(clearance 0)
		)
		(pad "27" thru_hole circle
			(at 0 66.04 270)
			(size 1.6256 1.6256)
			(drill 1.1176)
			(layers "*.Cu" "*.Mask")
			(remove_unused_layers no)
			(net "PSU3_AC_OK")
			(clearance 0)
		)
		(pad "28" thru_hole circle
			(at 0 68.58 270)
			(size 1.6256 1.6256)
			(drill 1.1176)
			(layers "*.Cu" "*.Mask")
			(remove_unused_layers no)
			(net "PSU3_CSAHRE")
			(clearance 0)
		)
		(pad "29" thru_hole circle
			(at 0 71.12 270)
			(size 1.6256 1.6256)
			(drill 1.1176)
			(layers "*.Cu" "*.Mask")
			(remove_unused_layers no)
			(net "PSU3_PS_ON_N")
			(clearance 0)
		)
		(pad "30" thru_hole circle
			(at 0 73.66 270)
			(size 1.6256 1.6256)
			(drill 1.1176)
			(layers "*.Cu" "*.Mask")
			(remove_unused_layers no)
			(net "PSU3_PS_KILL")
			(clearance 0)
		)
		(pad "31" thru_hole circle
			(at 0 76.2 270)
			(size 1.6256 1.6256)
			(drill 1.1176)
			(layers "*.Cu" "*.Mask")
			(remove_unused_layers no)
			(net "PSU3_RESET")
			(clearance 0)
		)
		(pad "32" thru_hole circle
			(at 0 78.74 270)
			(size 1.6256 1.6256)
			(drill 1.1176)
			(layers "*.Cu" "*.Mask")
			(remove_unused_layers no)
			(net "PSU_ALERT_N")
			(clearance 0)
		)
		(pad "33" thru_hole circle
			(at 5.08 78.74 270)
			(size 1.6256 1.6256)
			(drill 1.1176)
			(layers "*.Cu" "*.Mask")
			(remove_unused_layers no)
			(net "I2C_PSU2_SDA")
			(clearance 0)
		)
		(pad "34" thru_hole circle
			(at 5.08 76.2 270)
			(size 1.6256 1.6256)
			(drill 1.1176)
			(layers "*.Cu" "*.Mask")
			(remove_unused_layers no)
			(net "Net_428")
			(clearance 0)
		)
		(pad "35" thru_hole circle
			(at 5.08 73.66 270)
			(size 1.6256 1.6256)
			(drill 1.1176)
			(layers "*.Cu" "*.Mask")
			(remove_unused_layers no)
			(net "I2C_PSU2_SCL")
			(clearance 0)
		)
		(pad "36" thru_hole circle
			(at 5.08 71.12 270)
			(size 1.6256 1.6256)
			(drill 1.1176)
			(layers "*.Cu" "*.Mask")
			(remove_unused_layers no)
			(net "PSU3_RETURN")
			(clearance 0)
		)
		(pad "37" thru_hole circle
			(at 5.08 68.58 270)
			(size 1.6256 1.6256)
			(drill 1.1176)
			(layers "*.Cu" "*.Mask")
			(remove_unused_layers no)
			(net "PSU3_DC_OK")
			(clearance 0)
		)
		(pad "38" thru_hole circle
			(at 5.08 66.04 270)
			(size 1.6256 1.6256)
			(drill 1.1176)
			(layers "*.Cu" "*.Mask")
			(remove_unused_layers no)
			(net "PSU3_AD0")
			(clearance 0)
		)
		(pad "39" thru_hole circle
			(at 5.08 63.5 270)
			(size 1.6256 1.6256)
			(drill 1.1176)
			(layers "*.Cu" "*.Mask")
			(remove_unused_layers no)
			(net "P12V_STBY")
			(clearance 0)
		)
		(pad "40" thru_hole circle
			(at 5.08 60.96 270)
			(size 1.6256 1.6256)
			(drill 1.1176)
			(layers "*.Cu" "*.Mask")
			(remove_unused_layers no)
			(net "PSU3_REMOTE_P")
			(clearance 0)
		)
		(pad "41" thru_hole circle
			(at 5.08 58.42 270)
			(size 1.6256 1.6256)
			(drill 1.1176)
			(layers "*.Cu" "*.Mask")
			(remove_unused_layers no)
			(net "GND")
			(clearance 0)
		)
		(pad "42" thru_hole circle
			(at 5.08 55.88 270)
			(size 1.6256 1.6256)
			(drill 1.1176)
			(layers "*.Cu" "*.Mask")
			(remove_unused_layers no)
			(net "GND")
			(clearance 0)
		)
		(pad "43" thru_hole circle
			(at 5.08 53.34 270)
			(size 1.6256 1.6256)
			(drill 1.1176)
			(layers "*.Cu" "*.Mask")
			(remove_unused_layers no)
			(net "GND")
			(clearance 0)
		)
		(pad "44" thru_hole circle
			(at 5.08 50.8 270)
			(size 1.6256 1.6256)
			(drill 1.1176)
			(layers "*.Cu" "*.Mask")
			(remove_unused_layers no)
			(net "GND")
			(clearance 0)
		)
		(pad "45" thru_hole circle
			(at 5.08 48.26 270)
			(size 1.6256 1.6256)
			(drill 1.1176)
			(layers "*.Cu" "*.Mask")
			(remove_unused_layers no)
			(net "GND")
			(clearance 0)
		)
		(pad "46" thru_hole circle
			(at 5.08 45.72 270)
			(size 1.6256 1.6256)
			(drill 1.1176)
			(layers "*.Cu" "*.Mask")
			(remove_unused_layers no)
			(net "GND")
			(clearance 0)
		)
		(pad "47" thru_hole circle
			(at 5.08 43.18 270)
			(size 1.6256 1.6256)
			(drill 1.1176)
			(layers "*.Cu" "*.Mask")
			(remove_unused_layers no)
			(net "GND")
			(clearance 0)
		)
		(pad "48" thru_hole circle
			(at 5.08 40.64 270)
			(size 1.6256 1.6256)
			(drill 1.1176)
			(layers "*.Cu" "*.Mask")
			(remove_unused_layers no)
			(net "GND")
			(clearance 0)
		)
		(pad "49" thru_hole circle
			(at 5.08 38.1 270)
			(size 1.6256 1.6256)
			(drill 1.1176)
			(layers "*.Cu" "*.Mask")
			(remove_unused_layers no)
			(net "GND")
			(clearance 0)
		)
		(pad "50" thru_hole circle
			(at 5.08 35.56 270)
			(size 1.6256 1.6256)
			(drill 1.1176)
			(layers "*.Cu" "*.Mask")
			(remove_unused_layers no)
			(net "GND")
			(clearance 0)
		)
		(pad "51" thru_hole circle
			(at 5.08 33.02 270)
			(size 1.6256 1.6256)
			(drill 1.1176)
			(layers "*.Cu" "*.Mask")
			(remove_unused_layers no)
			(net "GND")
			(clearance 0)
		)
		(pad "52" thru_hole circle
			(at 5.08 30.48 270)
			(size 1.6256 1.6256)
			(drill 1.1176)
			(layers "*.Cu" "*.Mask")
			(remove_unused_layers no)
			(net "GND")
			(clearance 0)
		)
		(pad "53" thru_hole circle
			(at 5.08 27.94 270)
			(size 1.6256 1.6256)
			(drill 1.1176)
			(layers "*.Cu" "*.Mask")
			(remove_unused_layers no)
			(net "P12V")
			(clearance 0)
		)
		(pad "54" thru_hole circle
			(at 5.08 25.4 270)
			(size 1.6256 1.6256)
			(drill 1.1176)
			(layers "*.Cu" "*.Mask")
			(remove_unused_layers no)
			(net "P12V")
			(clearance 0)
		)
		(pad "55" thru_hole circle
			(at 5.08 22.86 270)
			(size 1.6256 1.6256)
			(drill 1.1176)
			(layers "*.Cu" "*.Mask")
			(remove_unused_layers no)
			(net "P12V")
			(clearance 0)
		)
		(pad "56" thru_hole circle
			(at 5.08 20.32 270)
			(size 1.6256 1.6256)
			(drill 1.1176)
			(layers "*.Cu" "*.Mask")
			(remove_unused_layers no)
			(net "P12V")
			(clearance 0)
		)
		(pad "57" thru_hole circle
			(at 5.08 17.78 270)
			(size 1.6256 1.6256)
			(drill 1.1176)
			(layers "*.Cu" "*.Mask")
			(remove_unused_layers no)
			(net "P12V")
			(clearance 0)
		)
		(pad "58" thru_hole circle
			(at 5.08 15.24 270)
			(size 1.6256 1.6256)
			(drill 1.1176)
			(layers "*.Cu" "*.Mask")
			(remove_unused_layers no)
			(net "P12V")
			(clearance 0)
		)
		(pad "59" thru_hole circle
			(at 5.08 12.7 270)
			(size 1.6256 1.6256)
			(drill 1.1176)
			(layers "*.Cu" "*.Mask")
			(remove_unused_layers no)
			(net "P12V")
			(clearance 0)
		)
		(pad "60" thru_hole circle
			(at 5.08 10.16 270)
			(size 1.6256 1.6256)
			(drill 1.1176)
			(layers "*.Cu" "*.Mask")
			(remove_unused_layers no)
			(net "P12V")
			(clearance 0)
		)
		(pad "61" thru_hole circle
			(at 5.08 7.62 270)
			(size 1.6256 1.6256)
			(drill 1.1176)
			(layers "*.Cu" "*.Mask")
			(remove_unused_layers no)
			(net "P12V")
			(clearance 0)
		)
		(pad "62" thru_hole circle
			(at 5.08 5.08 270)
			(size 1.6256 1.6256)
			(drill 1.1176)
			(layers "*.Cu" "*.Mask")
			(remove_unused_layers no)
			(net "P12V")
			(clearance 0)
		)
		(pad "63" thru_hole circle
			(at 5.08 2.54 270)
			(size 1.6256 1.6256)
			(drill 1.1176)
			(layers "*.Cu" "*.Mask")
			(remove_unused_layers no)
			(net "P12V")
			(clearance 0)
		)
		(pad "64" thru_hole circle
			(at 5.08 0 270)
			(size 1.6256 1.6256)
			(drill 1.1176)
			(layers "*.Cu" "*.Mask")
			(remove_unused_layers no)
			(net "P12V")
			(clearance 0)
		)
	)
	(footprint ""
		(layer "F.Cu")
		(at 30.45968 -436.930038)
		(property "Reference" "J5"
			(at -4.20243 -2.774188 0)
			(unlocked yes)
			(layer "F.SilkS")
			(effects
				(font
					(size 0.7874 0.5842)
					(thickness 0.1524)
				)
				(justify left)
			)
		)
		(property "Value" ""
			(at 0 0 0)
			(layer "F.Fab")
			(effects
				(font
					(size 1.27 1.27)
				)
			)
		)
		(duplicate_pad_numbers_are_jumpers no)
		(fp_line
			(start -2.135124 -4.560062)
			(end -2.135124 83.300062)
			(stroke
				(width 0.1524)
				(type default)
			)
			(layer "F.SilkS")
		)
		(fp_line
			(start -2.135124 83.300062)
			(end 7.215124 83.300062)
			(stroke
				(width 0.1524)
				(type default)
			)
			(layer "F.SilkS")
		)
		(fp_line
			(start 7.215124 -4.560062)
			(end -2.135124 -4.560062)
			(stroke
				(width 0.1524)
				(type default)
			)
			(layer "F.SilkS")
		)
		(fp_line
			(start 7.215124 83.300062)
			(end 7.215124 -4.560062)
			(stroke
				(width 0.1524)
				(type default)
			)
			(layer "F.SilkS")
		)
		(fp_poly
			(pts
				(xy -2.74447 -0.00889) (xy -5.44449 -0.708914) (xy -5.44449 0.691134)
			)
			(stroke
				(width 0)
				(type default)
			)
			(fill yes)
			(layer "F.SilkS")
		)
		(fp_poly
			(pts
				(xy -2.28219 -0.127) (xy -4.98221 -0.827024) (xy -4.98221 0.573024)
			)
			(stroke
				(width 0)
				(type default)
			)
			(fill yes)
			(layer "B.SilkS")
		)
		(fp_poly
			(pts
				(xy -0.8636 -0.8636) (xy -0.8636 79.6036) (xy -0.8636 79.629) (xy 5.9436 79.629) (xy 5.9436 79.6036)
				(xy 5.9436 -0.8636) (xy 5.9436 -0.889) (xy -0.8636 -0.889)
			)
			(stroke
				(width 0)
				(type default)
			)
			(fill no)
			(layer "B.CrtYd")
		)
		(fp_rect
			(start -2.135124 -4.560062)
			(end 7.21487 83.300062)
			(stroke
				(width 0)
				(type default)
			)
			(fill no)
			(layer "F.CrtYd")
		)
		(fp_line
			(start -2.135124 -4.560062)
			(end 7.215124 -4.560062)
			(stroke
				(width 0.1)
				(type default)
			)
			(layer "F.Fab")
		)
		(fp_line
			(start -2.135124 83.300062)
			(end -2.135124 -4.560062)
			(stroke
				(width 0.1)
				(type default)
			)
			(layer "F.Fab")
		)
		(fp_line
			(start 7.215124 -4.560062)
			(end 7.215124 83.300062)
			(stroke
				(width 0.1)
				(type default)
			)
			(layer "F.Fab")
		)
		(fp_line
			(start 7.215124 83.300062)
			(end -2.135124 83.300062)
			(stroke
				(width 0.1)
				(type default)
			)
			(layer "F.Fab")
		)
		(fp_text user "32"
			(at -3.655568 78.848458 0)
			(unlocked yes)
			(layer "F.SilkS")
			(effects
				(font
					(size 0.7874 0.5842)
					(thickness 0.1524)
				)
				(justify left)
			)
		)
		(fp_text user "1"
			(at -3.370834 -1.059434 0)
			(unlocked yes)
			(layer "F.SilkS")
			(effects
				(font
					(size 0.7874 0.5842)
					(thickness 0.1524)
				)
				(justify left)
			)
		)
		(fp_text user "33"
			(at 7.649464 81.833466 0)
			(unlocked yes)
			(layer "F.SilkS")
			(effects
				(font
					(size 0.7874 0.5842)
					(thickness 0.1524)
				)
				(justify left)
			)
		)
		(fp_text user "64"
			(at 7.771638 -0.257048 0)
			(unlocked yes)
			(layer "F.SilkS")
			(effects
				(font
					(size 0.7874 0.5842)
					(thickness 0.1524)
				)
				(justify left)
			)
		)
		(fp_text user "32"
			(at -1.12649 78.817216 0)
			(unlocked yes)
			(layer "B.SilkS")
			(effects
				(font
					(size 0.7874 0.5842)
					(thickness 0.1524)
				)
				(justify left mirror)
			)
		)
		(fp_text user "1"
			(at -1.029208 -1.200912 0)
			(unlocked yes)
			(layer "B.SilkS")
			(effects
				(font
					(size 0.7874 0.5842)
					(thickness 0.1524)
				)
				(justify left mirror)
			)
		)
		(fp_text user "33"
			(at 5.666486 81.833466 0)
			(unlocked yes)
			(layer "B.SilkS")
			(effects
				(font
					(size 0.7874 0.5842)
					(thickness 0.1524)
				)
				(justify left mirror)
			)
		)
		(fp_text user "64"
			(at 5.904992 -1.819148 0)
			(unlocked yes)
			(layer "B.SilkS")
			(effects
				(font
					(size 0.7874 0.5842)
					(thickness 0.1524)
				)
				(justify left mirror)
			)
		)
		(pad "1" thru_hole rect
			(at 0 0 270)
			(size 1.6256 1.6256)
			(drill 1.1176)
			(layers "*.Cu" "*.Mask")
			(remove_unused_layers no)
			(net "P12V")
			(clearance 0)
			(padstack
				(mode front_inner_back)
				(layer "Inner"
					(shape circle)
					(size 1.6256 1.6256)
					(clearance 0)
				)
				(layer "B.Cu"
					(shape rect)
					(size 1.6256 1.6256)
					(clearance 0)
				)
			)
		)
		(pad "2" thru_hole circle
			(at 0 2.54 270)
			(size 1.6256 1.6256)
			(drill 1.1176)
			(layers "*.Cu" "*.Mask")
			(remove_unused_layers no)
			(net "P12V")
			(clearance 0)
		)
		(pad "3" thru_hole circle
			(at 0 5.08 270)
			(size 1.6256 1.6256)
			(drill 1.1176)
			(layers "*.Cu" "*.Mask")
			(remove_unused_layers no)
			(net "P12V")
			(clearance 0)
		)
		(pad "4" thru_hole circle
			(at 0 7.62 270)
			(size 1.6256 1.6256)
			(drill 1.1176)
			(layers "*.Cu" "*.Mask")
			(remove_unused_layers no)
			(net "P12V")
			(clearance 0)
		)
		(pad "5" thru_hole circle
			(at 0 10.16 270)
			(size 1.6256 1.6256)
			(drill 1.1176)
			(layers "*.Cu" "*.Mask")
			(remove_unused_layers no)
			(net "P12V")
			(clearance 0)
		)
		(pad "6" thru_hole circle
			(at 0 12.7 270)
			(size 1.6256 1.6256)
			(drill 1.1176)
			(layers "*.Cu" "*.Mask")
			(remove_unused_layers no)
			(net "P12V")
			(clearance 0)
		)
		(pad "7" thru_hole circle
			(at 0 15.24 270)
			(size 1.6256 1.6256)
			(drill 1.1176)
			(layers "*.Cu" "*.Mask")
			(remove_unused_layers no)
			(net "P12V")
			(clearance 0)
		)
		(pad "8" thru_hole circle
			(at 0 17.78 270)
			(size 1.6256 1.6256)
			(drill 1.1176)
			(layers "*.Cu" "*.Mask")
			(remove_unused_layers no)
			(net "P12V")
			(clearance 0)
		)
		(pad "9" thru_hole circle
			(at 0 20.32 270)
			(size 1.6256 1.6256)
			(drill 1.1176)
			(layers "*.Cu" "*.Mask")
			(remove_unused_layers no)
			(net "P12V")
			(clearance 0)
		)
		(pad "10" thru_hole circle
			(at 0 22.86 270)
			(size 1.6256 1.6256)
			(drill 1.1176)
			(layers "*.Cu" "*.Mask")
			(remove_unused_layers no)
			(net "P12V")
			(clearance 0)
		)
		(pad "11" thru_hole circle
			(at 0 25.4 270)
			(size 1.6256 1.6256)
			(drill 1.1176)
			(layers "*.Cu" "*.Mask")
			(remove_unused_layers no)
			(net "P12V")
			(clearance 0)
		)
		(pad "12" thru_hole circle
			(at 0 27.94 270)
			(size 1.6256 1.6256)
			(drill 1.1176)
			(layers "*.Cu" "*.Mask")
			(remove_unused_layers no)
			(net "P12V")
			(clearance 0)
		)
		(pad "13" thru_hole circle
			(at 0 30.48 270)
			(size 1.6256 1.6256)
			(drill 1.1176)
			(layers "*.Cu" "*.Mask")
			(remove_unused_layers no)
			(net "GND")
			(clearance 0)
		)
		(pad "14" thru_hole circle
			(at 0 33.02 270)
			(size 1.6256 1.6256)
			(drill 1.1176)
			(layers "*.Cu" "*.Mask")
			(remove_unused_layers no)
			(net "GND")
			(clearance 0)
		)
		(pad "15" thru_hole circle
			(at 0 35.56 270)
			(size 1.6256 1.6256)
			(drill 1.1176)
			(layers "*.Cu" "*.Mask")
			(remove_unused_layers no)
			(net "GND")
			(clearance 0)
		)
		(pad "16" thru_hole circle
			(at 0 38.1 270)
			(size 1.6256 1.6256)
			(drill 1.1176)
			(layers "*.Cu" "*.Mask")
			(remove_unused_layers no)
			(net "GND")
			(clearance 0)
		)
		(pad "17" thru_hole circle
			(at 0 40.64 270)
			(size 1.6256 1.6256)
			(drill 1.1176)
			(layers "*.Cu" "*.Mask")
			(remove_unused_layers no)
			(net "GND")
			(clearance 0)
		)
		(pad "18" thru_hole circle
			(at 0 43.18 270)
			(size 1.6256 1.6256)
			(drill 1.1176)
			(layers "*.Cu" "*.Mask")
			(remove_unused_layers no)
			(net "GND")
			(clearance 0)
		)
		(pad "19" thru_hole circle
			(at 0 45.72 270)
			(size 1.6256 1.6256)
			(drill 1.1176)
			(layers "*.Cu" "*.Mask")
			(remove_unused_layers no)
			(net "GND")
			(clearance 0)
		)
		(pad "20" thru_hole circle
			(at 0 48.26 270)
			(size 1.6256 1.6256)
			(drill 1.1176)
			(layers "*.Cu" "*.Mask")
			(remove_unused_layers no)
			(net "GND")
			(clearance 0)
		)
		(pad "21" thru_hole circle
			(at 0 50.8 270)
			(size 1.6256 1.6256)
			(drill 1.1176)
			(layers "*.Cu" "*.Mask")
			(remove_unused_layers no)
			(net "GND")
			(clearance 0)
		)
		(pad "22" thru_hole circle
			(at 0 53.34 270)
			(size 1.6256 1.6256)
			(drill 1.1176)
			(layers "*.Cu" "*.Mask")
			(remove_unused_layers no)
			(net "GND")
			(clearance 0)
		)
		(pad "23" thru_hole circle
			(at 0 55.88 270)
			(size 1.6256 1.6256)
			(drill 1.1176)
			(layers "*.Cu" "*.Mask")
			(remove_unused_layers no)
			(net "GND")
			(clearance 0)
		)
		(pad "24" thru_hole circle
			(at 0 58.42 270)
			(size 1.6256 1.6256)
			(drill 1.1176)
			(layers "*.Cu" "*.Mask")
			(remove_unused_layers no)
			(net "GND")
			(clearance 0)
		)
		(pad "25" thru_hole circle
			(at 0 60.96 270)
			(size 1.6256 1.6256)
			(drill 1.1176)
			(layers "*.Cu" "*.Mask")
			(remove_unused_layers no)
			(net "PHLOSS")
			(clearance 0)
		)
		(pad "26" thru_hole circle
			(at 0 63.5 270)
			(size 1.6256 1.6256)
			(drill 1.1176)
			(layers "*.Cu" "*.Mask")
			(remove_unused_layers no)
			(net "PSU5_REMOTE_N")
			(clearance 0)
		)
		(pad "27" thru_hole circle
			(at 0 66.04 270)
			(size 1.6256 1.6256)
			(drill 1.1176)
			(layers "*.Cu" "*.Mask")
			(remove_unused_layers no)
			(net "PSU5_AC_OK")
			(clearance 0)
		)
		(pad "28" thru_hole circle
			(at 0 68.58 270)
			(size 1.6256 1.6256)
			(drill 1.1176)
			(layers "*.Cu" "*.Mask")
			(remove_unused_layers no)
			(net "PSU5_CSAHRE")
			(clearance 0)
		)
		(pad "29" thru_hole circle
			(at 0 71.12 270)
			(size 1.6256 1.6256)
			(drill 1.1176)
			(layers "*.Cu" "*.Mask")
			(remove_unused_layers no)
			(net "PSU5_PS_ON_N")
			(clearance 0)
		)
		(pad "30" thru_hole circle
			(at 0 73.66 270)
			(size 1.6256 1.6256)
			(drill 1.1176)
			(layers "*.Cu" "*.Mask")
			(remove_unused_layers no)
			(net "PSU5_PS_KILL")
			(clearance 0)
		)
		(pad "31" thru_hole circle
			(at 0 76.2 270)
			(size 1.6256 1.6256)
			(drill 1.1176)
			(layers "*.Cu" "*.Mask")
			(remove_unused_layers no)
			(net "PSU5_RESET")
			(clearance 0)
		)
		(pad "32" thru_hole circle
			(at 0 78.74 270)
			(size 1.6256 1.6256)
			(drill 1.1176)
			(layers "*.Cu" "*.Mask")
			(remove_unused_layers no)
			(net "PSU_ALERT_N")
			(clearance 0)
		)
		(pad "33" thru_hole circle
			(at 5.08 78.74 270)
			(size 1.6256 1.6256)
			(drill 1.1176)
			(layers "*.Cu" "*.Mask")
			(remove_unused_layers no)
			(net "I2C_PSU3_SDA")
			(clearance 0)
		)
		(pad "34" thru_hole circle
			(at 5.08 76.2 270)
			(size 1.6256 1.6256)
			(drill 1.1176)
			(layers "*.Cu" "*.Mask")
			(remove_unused_layers no)
			(net "Net_426")
			(clearance 0)
		)
		(pad "35" thru_hole circle
			(at 5.08 73.66 270)
			(size 1.6256 1.6256)
			(drill 1.1176)
			(layers "*.Cu" "*.Mask")
			(remove_unused_layers no)
			(net "I2C_PSU3_SCL")
			(clearance 0)
		)
		(pad "36" thru_hole circle
			(at 5.08 71.12 270)
			(size 1.6256 1.6256)
			(drill 1.1176)
			(layers "*.Cu" "*.Mask")
			(remove_unused_layers no)
			(net "PSU5_RETURN")
			(clearance 0)
		)
		(pad "37" thru_hole circle
			(at 5.08 68.58 270)
			(size 1.6256 1.6256)
			(drill 1.1176)
			(layers "*.Cu" "*.Mask")
			(remove_unused_layers no)
			(net "PSU5_DC_OK")
			(clearance 0)
		)
		(pad "38" thru_hole circle
			(at 5.08 66.04 270)
			(size 1.6256 1.6256)
			(drill 1.1176)
			(layers "*.Cu" "*.Mask")
			(remove_unused_layers no)
			(net "PSU5_AD0")
			(clearance 0)
		)
		(pad "39" thru_hole circle
			(at 5.08 63.5 270)
			(size 1.6256 1.6256)
			(drill 1.1176)
			(layers "*.Cu" "*.Mask")
			(remove_unused_layers no)
			(net "P12V_STBY")
			(clearance 0)
		)
		(pad "40" thru_hole circle
			(at 5.08 60.96 270)
			(size 1.6256 1.6256)
			(drill 1.1176)
			(layers "*.Cu" "*.Mask")
			(remove_unused_layers no)
			(net "PSU5_REMOTE_P")
			(clearance 0)
		)
		(pad "41" thru_hole circle
			(at 5.08 58.42 270)
			(size 1.6256 1.6256)
			(drill 1.1176)
			(layers "*.Cu" "*.Mask")
			(remove_unused_layers no)
			(net "GND")
			(clearance 0)
		)
		(pad "42" thru_hole circle
			(at 5.08 55.88 270)
			(size 1.6256 1.6256)
			(drill 1.1176)
			(layers "*.Cu" "*.Mask")
			(remove_unused_layers no)
			(net "GND")
			(clearance 0)
		)
		(pad "43" thru_hole circle
			(at 5.08 53.34 270)
			(size 1.6256 1.6256)
			(drill 1.1176)
			(layers "*.Cu" "*.Mask")
			(remove_unused_layers no)
			(net "GND")
			(clearance 0)
		)
		(pad "44" thru_hole circle
			(at 5.08 50.8 270)
			(size 1.6256 1.6256)
			(drill 1.1176)
			(layers "*.Cu" "*.Mask")
			(remove_unused_layers no)
			(net "GND")
			(clearance 0)
		)
		(pad "45" thru_hole circle
			(at 5.08 48.26 270)
			(size 1.6256 1.6256)
			(drill 1.1176)
			(layers "*.Cu" "*.Mask")
			(remove_unused_layers no)
			(net "GND")
			(clearance 0)
		)
		(pad "46" thru_hole circle
			(at 5.08 45.72 270)
			(size 1.6256 1.6256)
			(drill 1.1176)
			(layers "*.Cu" "*.Mask")
			(remove_unused_layers no)
			(net "GND")
			(clearance 0)
		)
		(pad "47" thru_hole circle
			(at 5.08 43.18 270)
			(size 1.6256 1.6256)
			(drill 1.1176)
			(layers "*.Cu" "*.Mask")
			(remove_unused_layers no)
			(net "GND")
			(clearance 0)
		)
		(pad "48" thru_hole circle
			(at 5.08 40.64 270)
			(size 1.6256 1.6256)
			(drill 1.1176)
			(layers "*.Cu" "*.Mask")
			(remove_unused_layers no)
			(net "GND")
			(clearance 0)
		)
		(pad "49" thru_hole circle
			(at 5.08 38.1 270)
			(size 1.6256 1.6256)
			(drill 1.1176)
			(layers "*.Cu" "*.Mask")
			(remove_unused_layers no)
			(net "GND")
			(clearance 0)
		)
		(pad "50" thru_hole circle
			(at 5.08 35.56 270)
			(size 1.6256 1.6256)
			(drill 1.1176)
			(layers "*.Cu" "*.Mask")
			(remove_unused_layers no)
			(net "GND")
			(clearance 0)
		)
		(pad "51" thru_hole circle
			(at 5.08 33.02 270)
			(size 1.6256 1.6256)
			(drill 1.1176)
			(layers "*.Cu" "*.Mask")
			(remove_unused_layers no)
			(net "GND")
			(clearance 0)
		)
		(pad "52" thru_hole circle
			(at 5.08 30.48 270)
			(size 1.6256 1.6256)
			(drill 1.1176)
			(layers "*.Cu" "*.Mask")
			(remove_unused_layers no)
			(net "GND")
			(clearance 0)
		)
		(pad "53" thru_hole circle
			(at 5.08 27.94 270)
			(size 1.6256 1.6256)
			(drill 1.1176)
			(layers "*.Cu" "*.Mask")
			(remove_unused_layers no)
			(net "P12V")
			(clearance 0)
		)
		(pad "54" thru_hole circle
			(at 5.08 25.4 270)
			(size 1.6256 1.6256)
			(drill 1.1176)
			(layers "*.Cu" "*.Mask")
			(remove_unused_layers no)
			(net "P12V")
			(clearance 0)
		)
		(pad "55" thru_hole circle
			(at 5.08 22.86 270)
			(size 1.6256 1.6256)
			(drill 1.1176)
			(layers "*.Cu" "*.Mask")
			(remove_unused_layers no)
			(net "P12V")
			(clearance 0)
		)
		(pad "56" thru_hole circle
			(at 5.08 20.32 270)
			(size 1.6256 1.6256)
			(drill 1.1176)
			(layers "*.Cu" "*.Mask")
			(remove_unused_layers no)
			(net "P12V")
			(clearance 0)
		)
		(pad "57" thru_hole circle
			(at 5.08 17.78 270)
			(size 1.6256 1.6256)
			(drill 1.1176)
			(layers "*.Cu" "*.Mask")
			(remove_unused_layers no)
			(net "P12V")
			(clearance 0)
		)
		(pad "58" thru_hole circle
			(at 5.08 15.24 270)
			(size 1.6256 1.6256)
			(drill 1.1176)
			(layers "*.Cu" "*.Mask")
			(remove_unused_layers no)
			(net "P12V")
			(clearance 0)
		)
		(pad "59" thru_hole circle
			(at 5.08 12.7 270)
			(size 1.6256 1.6256)
			(drill 1.1176)
			(layers "*.Cu" "*.Mask")
			(remove_unused_layers no)
			(net "P12V")
			(clearance 0)
		)
		(pad "60" thru_hole circle
			(at 5.08 10.16 270)
			(size 1.6256 1.6256)
			(drill 1.1176)
			(layers "*.Cu" "*.Mask")
			(remove_unused_layers no)
			(net "P12V")
			(clearance 0)
		)
		(pad "61" thru_hole circle
			(at 5.08 7.62 270)
			(size 1.6256 1.6256)
			(drill 1.1176)
			(layers "*.Cu" "*.Mask")
			(remove_unused_layers no)
			(net "P12V")
			(clearance 0)
		)
		(pad "62" thru_hole circle
			(at 5.08 5.08 270)
			(size 1.6256 1.6256)
			(drill 1.1176)
			(layers "*.Cu" "*.Mask")
			(remove_unused_layers no)
			(net "P12V")
			(clearance 0)
		)
		(pad "63" thru_hole circle
			(at 5.08 2.54 270)
			(size 1.6256 1.6256)
			(drill 1.1176)
			(layers "*.Cu" "*.Mask")
			(remove_unused_layers no)
			(net "P12V")
			(clearance 0)
		)
		(pad "64" thru_hole circle
			(at 5.08 0 270)
			(size 1.6256 1.6256)
			(drill 1.1176)
			(layers "*.Cu" "*.Mask")
			(remove_unused_layers no)
			(net "P12V")
			(clearance 0)
		)
	)
	(footprint ""
		(layer "F.Cu")
		(at 50.743612 -151.92502 180)
		(property "Reference" "CE8"
			(at -4.261612 -1.5494 0)
			(unlocked yes)
			(layer "F.SilkS")
			(effects
				(font
					(size 0.7874 0.5842)
					(thickness 0.1524)
				)
				(justify left)
			)
		)
		(property "Value" ""
			(at 0 0 180)
			(layer "F.Fab")
			(effects
				(font
					(size 1.27 1.27)
				)
			)
		)
		(duplicate_pad_numbers_are_jumpers no)
		(fp_line
			(start 0 -4.2672)
			(end 0 4.2672)
			(stroke
				(width 0.1524)
				(type default)
			)
			(layer "F.SilkS")
		)
		(fp_circle
			(center 0 0)
			(end -4.2672 0)
			(stroke
				(width 0.1524)
				(type default)
			)
			(fill no)
			(layer "F.SilkS")
		)
		(fp_poly
			(pts
				(arc
					(start 0 -4.2672)
					(mid 4.2672 0)
					(end 0 4.2672)
				)
			)
			(stroke
				(width 0)
				(type default)
			)
			(fill yes)
			(layer "F.SilkS")
		)
		(fp_poly
			(pts
				(xy -2.5146 -0.762) (xy -0.9906 -0.762) (xy -0.9906 0.762) (xy -2.5146 0.762)
			)
			(stroke
				(width 0)
				(type default)
			)
			(fill no)
			(layer "B.CrtYd")
		)
		(fp_poly
			(pts
				(arc
					(start 1.7526 0.762)
					(mid 2.291415 -0.538815)
					(end 0.9906 0)
				)
				(arc
					(start 0.9906 0.0254)
					(mid 1.206345 0.546255)
					(end 1.7272 0.762)
				)
			)
			(stroke
				(width 0)
				(type default)
			)
			(fill no)
			(layer "B.CrtYd")
		)
		(fp_poly
			(pts
				(arc
					(start -4.2672 0)
					(mid 4.2672 0)
					(end -4.2672 0)
				)
			)
			(stroke
				(width 0)
				(type default)
			)
			(fill no)
			(layer "F.CrtYd")
		)
		(fp_circle
			(center 0 0)
			(end -4.2672 0)
			(stroke
				(width 0.1)
				(type default)
			)
			(fill no)
			(layer "F.Fab")
		)
		(fp_text user "+"
			(at -4.996688 -3.352292 180)
			(unlocked yes)
			(layer "F.SilkS")
			(effects
				(font
					(size 1.905 1.4224)
					(thickness 0.1524)
				)
				(justify left)
			)
		)
		(fp_text user "+"
			(at -5.6642 -0.34925 180)
			(unlocked yes)
			(layer "F.Fab")
			(effects
				(font
					(size 1.905 1.4224)
					(thickness 0.000001)
				)
				(justify left)
			)
		)
		(pad "1" thru_hole rect
			(at -1.75006 0 180)
			(size 1.397 1.397)
			(drill 0.9144)
			(layers "*.Cu" "*.Mask")
			(remove_unused_layers no)
			(net "P12V")
			(clearance 0.0127)
			(thermal_gap 0.0127)
			(padstack
				(mode front_inner_back)
				(layer "Inner"
					(shape circle)
					(size 1.397 1.397)
					(clearance 0.0127)
				)
				(layer "B.Cu"
					(shape rect)
					(size 1.397 1.397)
					(clearance 0.0127)
				)
			)
		)
		(pad "2" thru_hole circle
			(at 1.75006 0 180)
			(size 1.397 1.397)
			(drill 0.9144)
			(layers "*.Cu" "*.Mask")
			(remove_unused_layers no)
			(net "GND")
			(clearance 0.0127)
			(thermal_gap 0.0127)
		)
	)
	(footprint ""
		(layer "F.Cu")
		(at 75.059286 -152.923748 -90)
		(property "Reference" "C24"
			(at -2.638552 0.03937 90)
			(unlocked yes)
			(layer "F.SilkS")
			(effects
				(font
					(size 0.7874 0.5842)
					(thickness 0.1524)
				)
				(justify left)
			)
		)
		(property "Value" ""
			(at 0 0 270)
			(layer "F.Fab")
			(effects
				(font
					(size 1.27 1.27)
				)
			)
		)
		(duplicate_pad_numbers_are_jumpers no)
		(fp_line
			(start -0.7874 0.4064)
			(end -0.7874 -0.4064)
			(stroke
				(width 0.1524)
				(type default)
			)
			(layer "F.SilkS")
		)
		(fp_line
			(start 0.7874 0.4064)
			(end -0.7874 0.4064)
			(stroke
				(width 0.1524)
				(type default)
			)
			(layer "F.SilkS")
		)
		(fp_line
			(start 0 0.381)
			(end 0 -0.381)
			(stroke
				(width 0.1524)
				(type default)
			)
			(layer "F.SilkS")
		)
		(fp_line
			(start -0.7874 -0.4064)
			(end 0.7874 -0.4064)
			(stroke
				(width 0.1524)
				(type default)
			)
			(layer "F.SilkS")
		)
		(fp_line
			(start 0.7874 -0.4064)
			(end 0.7874 0.4064)
			(stroke
				(width 0.1524)
				(type default)
			)
			(layer "F.SilkS")
		)
		(fp_poly
			(pts
				(xy -0.5334 0.254) (xy -0.635 0.254) (xy -0.635 0.2286) (xy -0.635 -0.254) (xy -0.5334 -0.254) (xy -0.5334 -0.2794)
				(xy 0.5334 -0.2794) (xy 0.5334 -0.254) (xy 0.635 -0.254) (xy 0.635 0.254) (xy 0.5334 0.254) (xy 0.5334 0.2794)
				(xy -0.508 0.2794) (xy -0.5334 0.2794)
			)
			(stroke
				(width 0)
				(type default)
			)
			(fill no)
			(layer "F.CrtYd")
		)
		(pad "1" smd rect
			(at 0.40005 0 270)
			(size 0.4572 0.508)
			(layers "F.Cu" "F.Mask" "F.Paste")
			(net "P12V")
		)
		(pad "2" smd rect
			(at -0.40005 0 270)
			(size 0.4572 0.508)
			(layers "F.Cu" "F.Mask" "F.Paste")
			(net "GND")
		)
	)
	(footprint ""
		(layer "F.Cu")
		(at 50.554382 -418.636958 180)
		(property "Reference" "CE19"
			(at 6.458458 3.641344 0)
			(unlocked yes)
			(layer "F.SilkS")
			(effects
				(font
					(size 0.7874 0.5842)
					(thickness 0.1524)
				)
				(justify left)
			)
		)
		(property "Value" ""
			(at 0 0 180)
			(layer "F.Fab")
			(effects
				(font
					(size 1.27 1.27)
				)
			)
		)
		(duplicate_pad_numbers_are_jumpers no)
		(fp_line
			(start 0 -4.2672)
			(end 0 4.2672)
			(stroke
				(width 0.1524)
				(type default)
			)
			(layer "F.SilkS")
		)
		(fp_circle
			(center 0 0)
			(end -4.2672 0)
			(stroke
				(width 0.1524)
				(type default)
			)
			(fill no)
			(layer "F.SilkS")
		)
		(fp_poly
			(pts
				(arc
					(start 0 -4.2672)
					(mid 4.2672 0)
					(end 0 4.2672)
				)
			)
			(stroke
				(width 0)
				(type default)
			)
			(fill yes)
			(layer "F.SilkS")
		)
		(fp_poly
			(pts
				(xy -2.5146 -0.762) (xy -0.9906 -0.762) (xy -0.9906 0.762) (xy -2.5146 0.762)
			)
			(stroke
				(width 0)
				(type default)
			)
			(fill no)
			(layer "B.CrtYd")
		)
		(fp_poly
			(pts
				(arc
					(start 1.7526 0.762)
					(mid 2.291415 -0.538815)
					(end 0.9906 0)
				)
				(arc
					(start 0.9906 0.0254)
					(mid 1.206345 0.546255)
					(end 1.7272 0.762)
				)
			)
			(stroke
				(width 0)
				(type default)
			)
			(fill no)
			(layer "B.CrtYd")
		)
		(fp_poly
			(pts
				(arc
					(start -4.2672 0)
					(mid 4.2672 0)
					(end -4.2672 0)
				)
			)
			(stroke
				(width 0)
				(type default)
			)
			(fill no)
			(layer "F.CrtYd")
		)
		(fp_circle
			(center 0 0)
			(end -4.2672 0)
			(stroke
				(width 0.1)
				(type default)
			)
			(fill no)
			(layer "F.Fab")
		)
		(fp_text user "+"
			(at -5.740908 1.215136 180)
			(unlocked yes)
			(layer "F.SilkS")
			(effects
				(font
					(size 1.905 1.4224)
					(thickness 0.1524)
				)
				(justify left)
			)
		)
		(fp_text user "+"
			(at -5.6642 -0.34925 180)
			(unlocked yes)
			(layer "F.Fab")
			(effects
				(font
					(size 1.905 1.4224)
					(thickness 0.000001)
				)
				(justify left)
			)
		)
		(pad "1" thru_hole rect
			(at -1.75006 0 180)
			(size 1.397 1.397)
			(drill 0.9144)
			(layers "*.Cu" "*.Mask")
			(remove_unused_layers no)
			(net "P12V")
			(clearance 0.0127)
			(thermal_gap 0.0127)
			(padstack
				(mode front_inner_back)
				(layer "Inner"
					(shape circle)
					(size 1.397 1.397)
					(clearance 0.0127)
				)
				(layer "B.Cu"
					(shape rect)
					(size 1.397 1.397)
					(clearance 0.0127)
				)
			)
		)
		(pad "2" thru_hole circle
			(at 1.75006 0 180)
			(size 1.397 1.397)
			(drill 0.9144)
			(layers "*.Cu" "*.Mask")
			(remove_unused_layers no)
			(net "GND")
			(clearance 0.0127)
			(thermal_gap 0.0127)
		)
	)
	(footprint ""
		(layer "F.Cu")
		(at 16.599916 -206.99984)
		(property "Reference" "H2"
			(at -3.038856 -9.000998 0)
			(unlocked yes)
			(layer "F.SilkS")
			(effects
				(font
					(size 0.7874 0.5842)
					(thickness 0.1524)
				)
				(justify left)
			)
		)
		(property "Value" ""
			(at 0 0 0)
			(layer "F.Fab")
			(effects
				(font
					(size 1.27 1.27)
				)
			)
		)
		(duplicate_pad_numbers_are_jumpers no)
		(fp_circle
			(center 0 0)
			(end 7.999984 0)
			(stroke
				(width 0.1524)
				(type default)
			)
			(fill no)
			(layer "F.SilkS")
		)
		(fp_circle
			(center 0 0)
			(end 14.7066 0)
			(stroke
				(width 0.1524)
				(type default)
			)
			(fill no)
			(layer "B.SilkS")
		)
		(fp_poly
			(pts
				(arc
					(start 0 5.0038)
					(mid 0 -5.0038)
					(end 0 5.0038)
				)
			)
			(stroke
				(width 0)
				(type default)
			)
			(fill no)
			(layer "F.CrtYd")
		)
		(pad "" np_thru_hole circle
			(at 0 0)
			(size 4.0132 4.0132)
			(drill 4.0132)
			(layers "*.Cu" "*.Mask")
			(clearance 0.381)
			(thermal_gap 0.381)
		)
		(pad "2" thru_hole circle
			(at 0 -3.50012)
			(size 0.762 0.762)
			(drill 0.5588)
			(layers "*.Cu" "*.Mask")
			(remove_unused_layers no)
			(net "GND")
			(clearance 0.1524)
			(thermal_gap 0.1524)
		)
		(pad "3" thru_hole circle
			(at -2.500122 -2.500122)
			(size 0.762 0.762)
			(drill 0.5588)
			(layers "*.Cu" "*.Mask")
			(remove_unused_layers no)
			(net "GND")
			(clearance 0.1524)
			(thermal_gap 0.1524)
		)
		(pad "4" thru_hole circle
			(at -3.50012 0)
			(size 0.762 0.762)
			(drill 0.5588)
			(layers "*.Cu" "*.Mask")
			(remove_unused_layers no)
			(net "GND")
			(clearance 0.1524)
			(thermal_gap 0.1524)
		)
		(pad "5" thru_hole circle
			(at -2.500122 2.500122)
			(size 0.762 0.762)
			(drill 0.5588)
			(layers "*.Cu" "*.Mask")
			(remove_unused_layers no)
			(net "GND")
			(clearance 0.1524)
			(thermal_gap 0.1524)
		)
		(pad "6" thru_hole circle
			(at 0 3.50012)
			(size 0.762 0.762)
			(drill 0.5588)
			(layers "*.Cu" "*.Mask")
			(remove_unused_layers no)
			(net "GND")
			(clearance 0.1524)
			(thermal_gap 0.1524)
		)
		(pad "7" thru_hole circle
			(at 2.500122 2.500122)
			(size 0.762 0.762)
			(drill 0.5588)
			(layers "*.Cu" "*.Mask")
			(remove_unused_layers no)
			(net "GND")
			(clearance 0.1524)
			(thermal_gap 0.1524)
		)
		(pad "8" thru_hole circle
			(at 3.50012 0)
			(size 0.762 0.762)
			(drill 0.5588)
			(layers "*.Cu" "*.Mask")
			(remove_unused_layers no)
			(net "GND")
			(clearance 0.1524)
			(thermal_gap 0.1524)
		)
		(pad "9" thru_hole circle
			(at 2.500122 -2.500122)
			(size 0.762 0.762)
			(drill 0.5588)
			(layers "*.Cu" "*.Mask")
			(remove_unused_layers no)
			(net "GND")
			(clearance 0.1524)
			(thermal_gap 0.1524)
		)
		(zone
			(layer "F.Cu")
			(hatch none 0.5)
			(connect_pads
				(clearance 0)
			)
			(min_thickness 0.25)
			(keepout
				(tracks not_allowed)
				(vias allowed)
				(pads allowed)
				(copperpour not_allowed)
				(footprints allowed)
			)
			(placement
				(enabled no)
				(sheetname "")
			)
			(fill
				(thermal_gap 0.5)
				(thermal_bridge_width 0.5)
				(island_removal_mode 0)
			)
			(polygon
				(pts
					(arc
						(start 16.599916 -215.00084)
						(mid 8.598916 -206.99984)
						(end 16.599916 -198.99884)
					)
					(arc
						(start 16.599916 -198.99884)
						(mid 18.035016 -200.43394)
						(end 16.599916 -201.86904)
					)
					(arc
						(start 16.599916 -201.86904)
						(mid 11.469116 -206.99984)
						(end 16.599916 -212.13064)
					)
					(arc
						(start 16.599916 -212.13064)
						(mid 18.035016 -213.56574)
						(end 16.599916 -215.00084)
					)
				)
			)
		)
		(zone
			(layer "F.Cu")
			(hatch none 0.5)
			(connect_pads
				(clearance 0)
			)
			(min_thickness 0.25)
			(keepout
				(tracks not_allowed)
				(vias allowed)
				(pads allowed)
				(copperpour not_allowed)
				(footprints allowed)
			)
			(placement
				(enabled no)
				(sheetname "")
			)
			(fill
				(thermal_gap 0.5)
				(thermal_bridge_width 0.5)
				(island_removal_mode 0)
			)
			(polygon
				(pts
					(arc
						(start 16.599916 -215.00084)
						(mid 24.600916 -206.99984)
						(end 16.599916 -198.99884)
					)
					(arc
						(start 16.599916 -198.99884)
						(mid 15.164816 -200.43394)
						(end 16.599916 -201.86904)
					)
					(arc
						(start 16.599916 -201.86904)
						(mid 21.730716 -206.99984)
						(end 16.599916 -212.13064)
					)
					(arc
						(start 16.599916 -212.13064)
						(mid 15.164816 -213.56574)
						(end 16.599916 -215.00084)
					)
				)
			)
		)
		(zone
			(layers "F.Cu" "B.Cu" "In1.Cu" "In2.Cu" "In3.Cu" "In4.Cu" "In5.Cu" "In6.Cu")
			(hatch none 0.5)
			(connect_pads
				(clearance 0)
			)
			(min_thickness 0.25)
			(keepout
				(tracks not_allowed)
				(vias allowed)
				(pads allowed)
				(copperpour not_allowed)
				(footprints allowed)
			)
			(placement
				(enabled no)
				(sheetname "")
			)
			(fill
				(thermal_gap 0.5)
				(thermal_bridge_width 0.5)
				(island_removal_mode 0)
			)
			(polygon
				(pts
					(arc
						(start 16.599916 -204.48778)
						(mid 16.599916 -209.5119)
						(end 16.599916 -204.48778)
					)
				)
			)
		)
	)
	(footprint ""
		(layer "F.Cu")
		(at 71.392796 -83.335368 90)
		(property "Reference" "C21"
			(at 1.101852 -0.164846 90)
			(unlocked yes)
			(layer "F.SilkS")
			(effects
				(font
					(size 0.7874 0.5842)
					(thickness 0.1524)
				)
				(justify left)
			)
		)
		(property "Value" ""
			(at 0 0 90)
			(layer "F.Fab")
			(effects
				(font
					(size 1.27 1.27)
				)
			)
		)
		(duplicate_pad_numbers_are_jumpers no)
		(fp_line
			(start 0.7874 -0.4064)
			(end 0.7874 0.4064)
			(stroke
				(width 0.1524)
				(type default)
			)
			(layer "F.SilkS")
		)
		(fp_line
			(start -0.7874 -0.4064)
			(end 0.7874 -0.4064)
			(stroke
				(width 0.1524)
				(type default)
			)
			(layer "F.SilkS")
		)
		(fp_line
			(start 0 0.381)
			(end 0 -0.381)
			(stroke
				(width 0.1524)
				(type default)
			)
			(layer "F.SilkS")
		)
		(fp_line
			(start 0.7874 0.4064)
			(end -0.7874 0.4064)
			(stroke
				(width 0.1524)
				(type default)
			)
			(layer "F.SilkS")
		)
		(fp_line
			(start -0.7874 0.4064)
			(end -0.7874 -0.4064)
			(stroke
				(width 0.1524)
				(type default)
			)
			(layer "F.SilkS")
		)
		(fp_poly
			(pts
				(xy -0.5334 0.254) (xy -0.635 0.254) (xy -0.635 0.2286) (xy -0.635 -0.254) (xy -0.5334 -0.254) (xy -0.5334 -0.2794)
				(xy 0.5334 -0.2794) (xy 0.5334 -0.254) (xy 0.635 -0.254) (xy 0.635 0.254) (xy 0.5334 0.254) (xy 0.5334 0.2794)
				(xy -0.508 0.2794) (xy -0.5334 0.2794)
			)
			(stroke
				(width 0)
				(type default)
			)
			(fill no)
			(layer "F.CrtYd")
		)
		(pad "1" smd rect
			(at 0.40005 0 90)
			(size 0.4572 0.508)
			(layers "F.Cu" "F.Mask" "F.Paste")
			(net "P12V")
		)
		(pad "2" smd rect
			(at -0.40005 0 90)
			(size 0.4572 0.508)
			(layers "F.Cu" "F.Mask" "F.Paste")
			(net "GND")
		)
	)
	(footprint ""
		(layer "F.Cu")
		(at 46.436788 -251.703332 180)
		(property "Reference" "R100"
			(at 2.469388 -1.292098 0)
			(unlocked yes)
			(layer "F.SilkS")
			(effects
				(font
					(size 0.7874 0.5842)
					(thickness 0.1524)
				)
				(justify left)
			)
		)
		(property "Value" ""
			(at 0 0 180)
			(layer "F.Fab")
			(effects
				(font
					(size 1.27 1.27)
				)
			)
		)
		(duplicate_pad_numbers_are_jumpers no)
		(fp_line
			(start 0.7874 0.4064)
			(end -0.7874 0.4064)
			(stroke
				(width 0.1524)
				(type default)
			)
			(layer "F.SilkS")
		)
		(fp_line
			(start 0.7874 -0.4064)
			(end 0.7874 0.4064)
			(stroke
				(width 0.1524)
				(type default)
			)
			(layer "F.SilkS")
		)
		(fp_line
			(start -0.7874 0.4064)
			(end -0.7874 -0.4064)
			(stroke
				(width 0.1524)
				(type default)
			)
			(layer "F.SilkS")
		)
		(fp_line
			(start -0.7874 -0.4064)
			(end 0.7874 -0.4064)
			(stroke
				(width 0.1524)
				(type default)
			)
			(layer "F.SilkS")
		)
		(fp_poly
			(pts
				(xy -0.508 0.2794) (xy -0.508 0.2286) (xy -0.635 0.2286) (xy -0.635 -0.254) (xy -0.5334 -0.254)
				(xy -0.5334 -0.2794) (xy 0.5334 -0.2794) (xy 0.5334 -0.254) (xy 0.635 -0.254) (xy 0.635 0.254) (xy 0.5334 0.254)
				(xy 0.5334 0.2794)
			)
			(stroke
				(width 0)
				(type default)
			)
			(fill no)
			(layer "F.CrtYd")
		)
		(pad "1" smd rect
			(at 0.40005 0 180)
			(size 0.4572 0.508)
			(layers "F.Cu" "F.Mask" "F.Paste")
			(net "PSU6_REMOTE_R_P")
		)
		(pad "2" smd rect
			(at -0.40005 0 180)
			(size 0.4572 0.508)
			(layers "F.Cu" "F.Mask" "F.Paste")
			(net "P12V")
		)
	)
	(footprint ""
		(layer "F.Cu")
		(at 26.492708 -14.7955)
		(property "Reference" "R134"
			(at -3.978148 -0.004826 0)
			(unlocked yes)
			(layer "F.SilkS")
			(effects
				(font
					(size 0.7874 0.5842)
					(thickness 0.1524)
				)
				(justify left)
			)
		)
		(property "Value" ""
			(at 0 0 0)
			(layer "F.Fab")
			(effects
				(font
					(size 1.27 1.27)
				)
			)
		)
		(duplicate_pad_numbers_are_jumpers no)
		(fp_line
			(start -0.7874 -0.4064)
			(end 0.7874 -0.4064)
			(stroke
				(width 0.1524)
				(type default)
			)
			(layer "F.SilkS")
		)
		(fp_line
			(start -0.7874 0.4064)
			(end -0.7874 -0.4064)
			(stroke
				(width 0.1524)
				(type default)
			)
			(layer "F.SilkS")
		)
		(fp_line
			(start 0.7874 -0.4064)
			(end 0.7874 0.4064)
			(stroke
				(width 0.1524)
				(type default)
			)
			(layer "F.SilkS")
		)
		(fp_line
			(start 0.7874 0.4064)
			(end -0.7874 0.4064)
			(stroke
				(width 0.1524)
				(type default)
			)
			(layer "F.SilkS")
		)
		(fp_poly
			(pts
				(xy -0.508 0.2794) (xy -0.508 0.2286) (xy -0.635 0.2286) (xy -0.635 -0.254) (xy -0.5334 -0.254)
				(xy -0.5334 -0.2794) (xy 0.5334 -0.2794) (xy 0.5334 -0.254) (xy 0.635 -0.254) (xy 0.635 0.254) (xy 0.5334 0.254)
				(xy 0.5334 0.2794)
			)
			(stroke
				(width 0)
				(type default)
			)
			(fill no)
			(layer "F.CrtYd")
		)
		(pad "1" smd rect
			(at 0.40005 0)
			(size 0.4572 0.508)
			(layers "F.Cu" "F.Mask" "F.Paste")
			(net "PSU1_CSAHRE")
		)
		(pad "2" smd rect
			(at -0.40005 0)
			(size 0.4572 0.508)
			(layers "F.Cu" "F.Mask" "F.Paste")
			(net "PSU_CSAHRE")
		)
	)
	(footprint ""
		(layer "F.Cu")
		(at 27.16911 -373.43207)
		(property "Reference" "R19"
			(at -3.196844 0.148336 0)
			(unlocked yes)
			(layer "F.SilkS")
			(effects
				(font
					(size 0.7874 0.5842)
					(thickness 0.1524)
				)
				(justify left)
			)
		)
		(property "Value" ""
			(at 0 0 0)
			(layer "F.Fab")
			(effects
				(font
					(size 1.27 1.27)
				)
			)
		)
		(duplicate_pad_numbers_are_jumpers no)
		(fp_line
			(start -0.7874 -0.4064)
			(end 0.7874 -0.4064)
			(stroke
				(width 0.1524)
				(type default)
			)
			(layer "F.SilkS")
		)
		(fp_line
			(start -0.7874 0.4064)
			(end -0.7874 -0.4064)
			(stroke
				(width 0.1524)
				(type default)
			)
			(layer "F.SilkS")
		)
		(fp_line
			(start 0.7874 -0.4064)
			(end 0.7874 0.4064)
			(stroke
				(width 0.1524)
				(type default)
			)
			(layer "F.SilkS")
		)
		(fp_line
			(start 0.7874 0.4064)
			(end -0.7874 0.4064)
			(stroke
				(width 0.1524)
				(type default)
			)
			(layer "F.SilkS")
		)
		(fp_poly
			(pts
				(xy -0.508 0.2794) (xy -0.508 0.2286) (xy -0.635 0.2286) (xy -0.635 -0.254) (xy -0.5334 -0.254)
				(xy -0.5334 -0.2794) (xy 0.5334 -0.2794) (xy 0.5334 -0.254) (xy 0.635 -0.254) (xy 0.635 0.254) (xy 0.5334 0.254)
				(xy 0.5334 0.2794)
			)
			(stroke
				(width 0)
				(type default)
			)
			(fill no)
			(layer "F.CrtYd")
		)
		(pad "1" smd rect
			(at 0.40005 0)
			(size 0.4572 0.508)
			(layers "F.Cu" "F.Mask" "F.Paste")
			(net "PSU5_REMOTE_N")
		)
		(pad "2" smd rect
			(at -0.40005 0)
			(size 0.4572 0.508)
			(layers "F.Cu" "F.Mask" "F.Paste")
			(net "GND")
		)
	)
	(footprint ""
		(layer "F.Cu")
		(at 16.599916 -29.19984)
		(property "Reference" "H11"
			(at 3.43535 -8.642604 0)
			(unlocked yes)
			(layer "F.SilkS")
			(effects
				(font
					(size 0.7874 0.5842)
					(thickness 0.1524)
				)
				(justify left)
			)
		)
		(property "Value" ""
			(at 0 0 0)
			(layer "F.Fab")
			(effects
				(font
					(size 1.27 1.27)
				)
			)
		)
		(duplicate_pad_numbers_are_jumpers no)
		(fp_circle
			(center 0 0)
			(end 7.999984 0)
			(stroke
				(width 0.1524)
				(type default)
			)
			(fill no)
			(layer "F.SilkS")
		)
		(fp_circle
			(center 0 0)
			(end 14.7066 0)
			(stroke
				(width 0.1524)
				(type default)
			)
			(fill no)
			(layer "B.SilkS")
		)
		(fp_poly
			(pts
				(arc
					(start 0 5.0038)
					(mid 0 -5.0038)
					(end 0 5.0038)
				)
			)
			(stroke
				(width 0)
				(type default)
			)
			(fill no)
			(layer "F.CrtYd")
		)
		(pad "" np_thru_hole circle
			(at 0 0)
			(size 4.0132 4.0132)
			(drill 4.0132)
			(layers "*.Cu" "*.Mask")
			(clearance 0.381)
			(thermal_gap 0.381)
		)
		(pad "2" thru_hole circle
			(at 0 -3.50012)
			(size 0.762 0.762)
			(drill 0.5588)
			(layers "*.Cu" "*.Mask")
			(remove_unused_layers no)
			(net "GND")
			(clearance 0.1524)
			(thermal_gap 0.1524)
		)
		(pad "3" thru_hole circle
			(at -2.500122 -2.500122)
			(size 0.762 0.762)
			(drill 0.5588)
			(layers "*.Cu" "*.Mask")
			(remove_unused_layers no)
			(net "GND")
			(clearance 0.1524)
			(thermal_gap 0.1524)
		)
		(pad "4" thru_hole circle
			(at -3.50012 0)
			(size 0.762 0.762)
			(drill 0.5588)
			(layers "*.Cu" "*.Mask")
			(remove_unused_layers no)
			(net "GND")
			(clearance 0.1524)
			(thermal_gap 0.1524)
		)
		(pad "5" thru_hole circle
			(at -2.500122 2.500122)
			(size 0.762 0.762)
			(drill 0.5588)
			(layers "*.Cu" "*.Mask")
			(remove_unused_layers no)
			(net "GND")
			(clearance 0.1524)
			(thermal_gap 0.1524)
		)
		(pad "6" thru_hole circle
			(at 0 3.50012)
			(size 0.762 0.762)
			(drill 0.5588)
			(layers "*.Cu" "*.Mask")
			(remove_unused_layers no)
			(net "GND")
			(clearance 0.1524)
			(thermal_gap 0.1524)
		)
		(pad "7" thru_hole circle
			(at 2.500122 2.500122)
			(size 0.762 0.762)
			(drill 0.5588)
			(layers "*.Cu" "*.Mask")
			(remove_unused_layers no)
			(net "GND")
			(clearance 0.1524)
			(thermal_gap 0.1524)
		)
		(pad "8" thru_hole circle
			(at 3.50012 0)
			(size 0.762 0.762)
			(drill 0.5588)
			(layers "*.Cu" "*.Mask")
			(remove_unused_layers no)
			(net "GND")
			(clearance 0.1524)
			(thermal_gap 0.1524)
		)
		(pad "9" thru_hole circle
			(at 2.500122 -2.500122)
			(size 0.762 0.762)
			(drill 0.5588)
			(layers "*.Cu" "*.Mask")
			(remove_unused_layers no)
			(net "GND")
			(clearance 0.1524)
			(thermal_gap 0.1524)
		)
		(zone
			(layer "F.Cu")
			(hatch none 0.5)
			(connect_pads
				(clearance 0)
			)
			(min_thickness 0.25)
			(keepout
				(tracks not_allowed)
				(vias allowed)
				(pads allowed)
				(copperpour not_allowed)
				(footprints allowed)
			)
			(placement
				(enabled no)
				(sheetname "")
			)
			(fill
				(thermal_gap 0.5)
				(thermal_bridge_width 0.5)
				(island_removal_mode 0)
			)
			(polygon
				(pts
					(arc
						(start 16.599916 -37.20084)
						(mid 8.598916 -29.19984)
						(end 16.599916 -21.19884)
					)
					(arc
						(start 16.599916 -21.19884)
						(mid 18.035016 -22.63394)
						(end 16.599916 -24.06904)
					)
					(arc
						(start 16.599916 -24.06904)
						(mid 11.469116 -29.19984)
						(end 16.599916 -34.33064)
					)
					(arc
						(start 16.599916 -34.33064)
						(mid 18.035016 -35.76574)
						(end 16.599916 -37.20084)
					)
				)
			)
		)
		(zone
			(layer "F.Cu")
			(hatch none 0.5)
			(connect_pads
				(clearance 0)
			)
			(min_thickness 0.25)
			(keepout
				(tracks not_allowed)
				(vias allowed)
				(pads allowed)
				(copperpour not_allowed)
				(footprints allowed)
			)
			(placement
				(enabled no)
				(sheetname "")
			)
			(fill
				(thermal_gap 0.5)
				(thermal_bridge_width 0.5)
				(island_removal_mode 0)
			)
			(polygon
				(pts
					(arc
						(start 16.599916 -37.20084)
						(mid 24.600916 -29.19984)
						(end 16.599916 -21.19884)
					)
					(arc
						(start 16.599916 -21.19884)
						(mid 15.164816 -22.63394)
						(end 16.599916 -24.06904)
					)
					(arc
						(start 16.599916 -24.06904)
						(mid 21.730716 -29.19984)
						(end 16.599916 -34.33064)
					)
					(arc
						(start 16.599916 -34.33064)
						(mid 15.164816 -35.76574)
						(end 16.599916 -37.20084)
					)
				)
			)
		)
		(zone
			(layers "F.Cu" "B.Cu" "In1.Cu" "In2.Cu" "In3.Cu" "In4.Cu" "In5.Cu" "In6.Cu")
			(hatch none 0.5)
			(connect_pads
				(clearance 0)
			)
			(min_thickness 0.25)
			(keepout
				(tracks not_allowed)
				(vias allowed)
				(pads allowed)
				(copperpour not_allowed)
				(footprints allowed)
			)
			(placement
				(enabled no)
				(sheetname "")
			)
			(fill
				(thermal_gap 0.5)
				(thermal_bridge_width 0.5)
				(island_removal_mode 0)
			)
			(polygon
				(pts
					(arc
						(start 16.599916 -26.68778)
						(mid 16.599916 -31.7119)
						(end 16.599916 -26.68778)
					)
				)
			)
		)
	)
	(footprint ""
		(layer "F.Cu")
		(at 69.863208 -350.498664 90)
		(property "Reference" "C62"
			(at 1.14046 -0.108966 90)
			(unlocked yes)
			(layer "F.SilkS")
			(effects
				(font
					(size 0.7874 0.5842)
					(thickness 0.1524)
				)
				(justify left)
			)
		)
		(property "Value" ""
			(at 0 0 90)
			(layer "F.Fab")
			(effects
				(font
					(size 1.27 1.27)
				)
			)
		)
		(duplicate_pad_numbers_are_jumpers no)
		(fp_line
			(start 0.7874 -0.4064)
			(end 0.7874 0.4064)
			(stroke
				(width 0.1524)
				(type default)
			)
			(layer "F.SilkS")
		)
		(fp_line
			(start -0.7874 -0.4064)
			(end 0.7874 -0.4064)
			(stroke
				(width 0.1524)
				(type default)
			)
			(layer "F.SilkS")
		)
		(fp_line
			(start 0 0.381)
			(end 0 -0.381)
			(stroke
				(width 0.1524)
				(type default)
			)
			(layer "F.SilkS")
		)
		(fp_line
			(start 0.7874 0.4064)
			(end -0.7874 0.4064)
			(stroke
				(width 0.1524)
				(type default)
			)
			(layer "F.SilkS")
		)
		(fp_line
			(start -0.7874 0.4064)
			(end -0.7874 -0.4064)
			(stroke
				(width 0.1524)
				(type default)
			)
			(layer "F.SilkS")
		)
		(fp_poly
			(pts
				(xy -0.5334 0.254) (xy -0.635 0.254) (xy -0.635 0.2286) (xy -0.635 -0.254) (xy -0.5334 -0.254) (xy -0.5334 -0.2794)
				(xy 0.5334 -0.2794) (xy 0.5334 -0.254) (xy 0.635 -0.254) (xy 0.635 0.254) (xy 0.5334 0.254) (xy 0.5334 0.2794)
				(xy -0.508 0.2794) (xy -0.5334 0.2794)
			)
			(stroke
				(width 0)
				(type default)
			)
			(fill no)
			(layer "F.CrtYd")
		)
		(pad "1" smd rect
			(at 0.40005 0 90)
			(size 0.4572 0.508)
			(layers "F.Cu" "F.Mask" "F.Paste")
			(net "P12V")
		)
		(pad "2" smd rect
			(at -0.40005 0 90)
			(size 0.4572 0.508)
			(layers "F.Cu" "F.Mask" "F.Paste")
			(net "GND")
		)
	)
	(footprint ""
		(layer "F.Cu")
		(at 39.461948 -199.56907 -90)
		(property "Reference" "R94"
			(at -0.904494 -3.072892 90)
			(unlocked yes)
			(layer "F.SilkS")
			(effects
				(font
					(size 0.7874 0.5842)
					(thickness 0.1524)
				)
				(justify left)
			)
		)
		(property "Value" ""
			(at 0 0 270)
			(layer "F.Fab")
			(effects
				(font
					(size 1.27 1.27)
				)
			)
		)
		(duplicate_pad_numbers_are_jumpers no)
		(fp_line
			(start -0.7874 0.4064)
			(end -0.7874 -0.4064)
			(stroke
				(width 0.1524)
				(type default)
			)
			(layer "F.SilkS")
		)
		(fp_line
			(start 0.7874 0.4064)
			(end -0.7874 0.4064)
			(stroke
				(width 0.1524)
				(type default)
			)
			(layer "F.SilkS")
		)
		(fp_line
			(start -0.7874 -0.4064)
			(end 0.7874 -0.4064)
			(stroke
				(width 0.1524)
				(type default)
			)
			(layer "F.SilkS")
		)
		(fp_line
			(start 0.7874 -0.4064)
			(end 0.7874 0.4064)
			(stroke
				(width 0.1524)
				(type default)
			)
			(layer "F.SilkS")
		)
		(fp_poly
			(pts
				(xy -0.508 0.2794) (xy -0.508 0.2286) (xy -0.635 0.2286) (xy -0.635 -0.254) (xy -0.5334 -0.254)
				(xy -0.5334 -0.2794) (xy 0.5334 -0.2794) (xy 0.5334 -0.254) (xy 0.635 -0.254) (xy 0.635 0.254) (xy 0.5334 0.254)
				(xy 0.5334 0.2794)
			)
			(stroke
				(width 0)
				(type default)
			)
			(fill no)
			(layer "F.CrtYd")
		)
		(pad "1" smd rect
			(at 0.40005 0 270)
			(size 0.4572 0.508)
			(layers "F.Cu" "F.Mask" "F.Paste")
			(net "PSU3_REMOTE_P")
		)
		(pad "2" smd rect
			(at -0.40005 0 270)
			(size 0.4572 0.508)
			(layers "F.Cu" "F.Mask" "F.Paste")
			(net "PSU3_REMOTE_R_P")
		)
	)
	(footprint ""
		(layer "F.Cu")
		(at 39.460424 -198.769478 90)
		(property "Reference" "R118"
			(at -0.484632 1.99009 0)
			(unlocked yes)
			(layer "F.SilkS")
			(effects
				(font
					(size 0.7874 0.5842)
					(thickness 0.1524)
				)
				(justify left)
			)
		)
		(property "Value" ""
			(at 0 0 90)
			(layer "F.Fab")
			(effects
				(font
					(size 1.27 1.27)
				)
			)
		)
		(duplicate_pad_numbers_are_jumpers no)
		(fp_line
			(start 0.7874 -0.4064)
			(end 0.7874 0.4064)
			(stroke
				(width 0.1524)
				(type default)
			)
			(layer "F.SilkS")
		)
		(fp_line
			(start -0.7874 -0.4064)
			(end 0.7874 -0.4064)
			(stroke
				(width 0.1524)
				(type default)
			)
			(layer "F.SilkS")
		)
		(fp_line
			(start 0.7874 0.4064)
			(end -0.7874 0.4064)
			(stroke
				(width 0.1524)
				(type default)
			)
			(layer "F.SilkS")
		)
		(fp_line
			(start -0.7874 0.4064)
			(end -0.7874 -0.4064)
			(stroke
				(width 0.1524)
				(type default)
			)
			(layer "F.SilkS")
		)
		(fp_poly
			(pts
				(xy -0.508 0.2794) (xy -0.508 0.2286) (xy -0.635 0.2286) (xy -0.635 -0.254) (xy -0.5334 -0.254)
				(xy -0.5334 -0.2794) (xy 0.5334 -0.2794) (xy 0.5334 -0.254) (xy 0.635 -0.254) (xy 0.635 0.254) (xy 0.5334 0.254)
				(xy 0.5334 0.2794)
			)
			(stroke
				(width 0)
				(type default)
			)
			(fill no)
			(layer "F.CrtYd")
		)
		(pad "1" smd rect
			(at 0.40005 0 90)
			(size 0.4572 0.508)
			(layers "F.Cu" "F.Mask" "F.Paste")
			(net "PSU3_REMOTE_P")
		)
		(pad "2" smd rect
			(at -0.40005 0 90)
			(size 0.4572 0.508)
			(layers "F.Cu" "F.Mask" "F.Paste")
			(net "PSU3_REMOTE_R2_P")
		)
	)
	(footprint ""
		(layer "F.Cu")
		(at 50.39868 -519.020552 180)
		(property "Reference" "CE24"
			(at 0.751586 5.701792 0)
			(unlocked yes)
			(layer "F.SilkS")
			(effects
				(font
					(size 0.7874 0.5842)
					(thickness 0.1524)
				)
				(justify left)
			)
		)
		(property "Value" ""
			(at 0 0 180)
			(layer "F.Fab")
			(effects
				(font
					(size 1.27 1.27)
				)
			)
		)
		(duplicate_pad_numbers_are_jumpers no)
		(fp_line
			(start 0 -4.2672)
			(end 0 4.2672)
			(stroke
				(width 0.1524)
				(type default)
			)
			(layer "F.SilkS")
		)
		(fp_circle
			(center 0 0)
			(end -4.2672 0)
			(stroke
				(width 0.1524)
				(type default)
			)
			(fill no)
			(layer "F.SilkS")
		)
		(fp_poly
			(pts
				(arc
					(start 0 -4.2672)
					(mid 4.2672 0)
					(end 0 4.2672)
				)
			)
			(stroke
				(width 0)
				(type default)
			)
			(fill yes)
			(layer "F.SilkS")
		)
		(fp_poly
			(pts
				(xy -2.5146 -0.762) (xy -0.9906 -0.762) (xy -0.9906 0.762) (xy -2.5146 0.762)
			)
			(stroke
				(width 0)
				(type default)
			)
			(fill no)
			(layer "B.CrtYd")
		)
		(fp_poly
			(pts
				(arc
					(start 1.7526 0.762)
					(mid 2.291415 -0.538815)
					(end 0.9906 0)
				)
				(arc
					(start 0.9906 0.0254)
					(mid 1.206345 0.546255)
					(end 1.7272 0.762)
				)
			)
			(stroke
				(width 0)
				(type default)
			)
			(fill no)
			(layer "B.CrtYd")
		)
		(fp_poly
			(pts
				(arc
					(start -4.2672 0)
					(mid 4.2672 0)
					(end -4.2672 0)
				)
			)
			(stroke
				(width 0)
				(type default)
			)
			(fill no)
			(layer "F.CrtYd")
		)
		(fp_circle
			(center 0 0)
			(end -4.2672 0)
			(stroke
				(width 0.1)
				(type default)
			)
			(fill no)
			(layer "F.Fab")
		)
		(fp_text user "+"
			(at -5.892292 -1.58115 180)
			(unlocked yes)
			(layer "F.SilkS")
			(effects
				(font
					(size 1.905 1.4224)
					(thickness 0.1524)
				)
				(justify left)
			)
		)
		(fp_text user "+"
			(at -5.6642 -0.34925 180)
			(unlocked yes)
			(layer "F.Fab")
			(effects
				(font
					(size 1.905 1.4224)
					(thickness 0.000001)
				)
				(justify left)
			)
		)
		(pad "1" thru_hole rect
			(at -1.75006 0 180)
			(size 1.397 1.397)
			(drill 0.9144)
			(layers "*.Cu" "*.Mask")
			(remove_unused_layers no)
			(net "P12V")
			(clearance 0.0127)
			(thermal_gap 0.0127)
			(padstack
				(mode front_inner_back)
				(layer "Inner"
					(shape circle)
					(size 1.397 1.397)
					(clearance 0.0127)
				)
				(layer "B.Cu"
					(shape rect)
					(size 1.397 1.397)
					(clearance 0.0127)
				)
			)
		)
		(pad "2" thru_hole circle
			(at 1.75006 0 180)
			(size 1.397 1.397)
			(drill 0.9144)
			(layers "*.Cu" "*.Mask")
			(remove_unused_layers no)
			(net "GND")
			(clearance 0.0127)
			(thermal_gap 0.0127)
		)
	)
	(footprint ""
		(layer "F.Cu")
		(at 50.39868 -463.099658 180)
		(property "Reference" "CE22"
			(at -4.925568 2.154174 0)
			(unlocked yes)
			(layer "F.SilkS")
			(effects
				(font
					(size 0.7874 0.5842)
					(thickness 0.1524)
				)
				(justify left)
			)
		)
		(property "Value" ""
			(at 0 0 180)
			(layer "F.Fab")
			(effects
				(font
					(size 1.27 1.27)
				)
			)
		)
		(duplicate_pad_numbers_are_jumpers no)
		(fp_line
			(start 0 -4.2672)
			(end 0 4.2672)
			(stroke
				(width 0.1524)
				(type default)
			)
			(layer "F.SilkS")
		)
		(fp_circle
			(center 0 0)
			(end -4.2672 0)
			(stroke
				(width 0.1524)
				(type default)
			)
			(fill no)
			(layer "F.SilkS")
		)
		(fp_poly
			(pts
				(arc
					(start 0 -4.2672)
					(mid 4.2672 0)
					(end 0 4.2672)
				)
			)
			(stroke
				(width 0)
				(type default)
			)
			(fill yes)
			(layer "F.SilkS")
		)
		(fp_poly
			(pts
				(xy -2.5146 -0.762) (xy -0.9906 -0.762) (xy -0.9906 0.762) (xy -2.5146 0.762)
			)
			(stroke
				(width 0)
				(type default)
			)
			(fill no)
			(layer "B.CrtYd")
		)
		(fp_poly
			(pts
				(arc
					(start 1.7526 0.762)
					(mid 2.291415 -0.538815)
					(end 0.9906 0)
				)
				(arc
					(start 0.9906 0.0254)
					(mid 1.206345 0.546255)
					(end 1.7272 0.762)
				)
			)
			(stroke
				(width 0)
				(type default)
			)
			(fill no)
			(layer "B.CrtYd")
		)
		(fp_poly
			(pts
				(arc
					(start -4.2672 0)
					(mid 4.2672 0)
					(end -4.2672 0)
				)
			)
			(stroke
				(width 0)
				(type default)
			)
			(fill no)
			(layer "F.CrtYd")
		)
		(fp_circle
			(center 0 0)
			(end -4.2672 0)
			(stroke
				(width 0.1)
				(type default)
			)
			(fill no)
			(layer "F.Fab")
		)
		(fp_text user "+"
			(at -5.6642 -0.34925 180)
			(unlocked yes)
			(layer "F.SilkS")
			(effects
				(font
					(size 1.905 1.4224)
					(thickness 0.1524)
				)
				(justify left)
			)
		)
		(fp_text user "+"
			(at -5.6642 -0.34925 180)
			(unlocked yes)
			(layer "F.Fab")
			(effects
				(font
					(size 1.905 1.4224)
					(thickness 0.000001)
				)
				(justify left)
			)
		)
		(pad "1" thru_hole rect
			(at -1.75006 0 180)
			(size 1.397 1.397)
			(drill 0.9144)
			(layers "*.Cu" "*.Mask")
			(remove_unused_layers no)
			(net "P12V")
			(clearance 0.0127)
			(thermal_gap 0.0127)
			(padstack
				(mode front_inner_back)
				(layer "Inner"
					(shape circle)
					(size 1.397 1.397)
					(clearance 0.0127)
				)
				(layer "B.Cu"
					(shape rect)
					(size 1.397 1.397)
					(clearance 0.0127)
				)
			)
		)
		(pad "2" thru_hole circle
			(at 1.75006 0 180)
			(size 1.397 1.397)
			(drill 0.9144)
			(layers "*.Cu" "*.Mask")
			(remove_unused_layers no)
			(net "GND")
			(clearance 0.0127)
			(thermal_gap 0.0127)
		)
	)
	(footprint ""
		(layer "F.Cu")
		(at 27.577542 -373.832628 -90)
		(property "Reference" "R105"
			(at -1.451356 0.04318 90)
			(unlocked yes)
			(layer "F.SilkS")
			(effects
				(font
					(size 0.7874 0.5842)
					(thickness 0.1524)
				)
				(justify left)
			)
		)
		(property "Value" ""
			(at 0 0 270)
			(layer "F.Fab")
			(effects
				(font
					(size 1.27 1.27)
				)
			)
		)
		(duplicate_pad_numbers_are_jumpers no)
		(fp_line
			(start -0.7874 0.4064)
			(end -0.7874 -0.4064)
			(stroke
				(width 0.1524)
				(type default)
			)
			(layer "F.SilkS")
		)
		(fp_line
			(start 0.7874 0.4064)
			(end -0.7874 0.4064)
			(stroke
				(width 0.1524)
				(type default)
			)
			(layer "F.SilkS")
		)
		(fp_line
			(start -0.7874 -0.4064)
			(end 0.7874 -0.4064)
			(stroke
				(width 0.1524)
				(type default)
			)
			(layer "F.SilkS")
		)
		(fp_line
			(start 0.7874 -0.4064)
			(end 0.7874 0.4064)
			(stroke
				(width 0.1524)
				(type default)
			)
			(layer "F.SilkS")
		)
		(fp_poly
			(pts
				(xy -0.508 0.2794) (xy -0.508 0.2286) (xy -0.635 0.2286) (xy -0.635 -0.254) (xy -0.5334 -0.254)
				(xy -0.5334 -0.2794) (xy 0.5334 -0.2794) (xy 0.5334 -0.254) (xy 0.635 -0.254) (xy 0.635 0.254) (xy 0.5334 0.254)
				(xy 0.5334 0.2794)
			)
			(stroke
				(width 0)
				(type default)
			)
			(fill no)
			(layer "F.CrtYd")
		)
		(pad "1" smd rect
			(at 0.40005 0 270)
			(size 0.4572 0.508)
			(layers "F.Cu" "F.Mask" "F.Paste")
			(net "PSU5_REMOTE_N")
		)
		(pad "2" smd rect
			(at -0.40005 0 270)
			(size 0.4572 0.508)
			(layers "F.Cu" "F.Mask" "F.Paste")
			(net "PSU5_REMOTE_R_N")
		)
	)
	(footprint ""
		(layer "F.Cu")
		(at 51.411124 -262.266176 180)
		(property "Reference" "CE7"
			(at -3.278124 3.86588 0)
			(unlocked yes)
			(layer "F.SilkS")
			(effects
				(font
					(size 0.7874 0.5842)
					(thickness 0.1524)
				)
				(justify left)
			)
		)
		(property "Value" ""
			(at 0 0 180)
			(layer "F.Fab")
			(effects
				(font
					(size 1.27 1.27)
				)
			)
		)
		(duplicate_pad_numbers_are_jumpers no)
		(fp_line
			(start 0 -4.2672)
			(end 0 4.2672)
			(stroke
				(width 0.1524)
				(type default)
			)
			(layer "F.SilkS")
		)
		(fp_circle
			(center 0 0)
			(end -4.2672 0)
			(stroke
				(width 0.1524)
				(type default)
			)
			(fill no)
			(layer "F.SilkS")
		)
		(fp_poly
			(pts
				(arc
					(start 0 -4.2672)
					(mid 4.2672 0)
					(end 0 4.2672)
				)
			)
			(stroke
				(width 0)
				(type default)
			)
			(fill yes)
			(layer "F.SilkS")
		)
		(fp_poly
			(pts
				(xy -2.5146 -0.762) (xy -0.9906 -0.762) (xy -0.9906 0.762) (xy -2.5146 0.762)
			)
			(stroke
				(width 0)
				(type default)
			)
			(fill no)
			(layer "B.CrtYd")
		)
		(fp_poly
			(pts
				(arc
					(start 1.7526 0.762)
					(mid 2.291415 -0.538815)
					(end 0.9906 0)
				)
				(arc
					(start 0.9906 0.0254)
					(mid 1.206345 0.546255)
					(end 1.7272 0.762)
				)
			)
			(stroke
				(width 0)
				(type default)
			)
			(fill no)
			(layer "B.CrtYd")
		)
		(fp_poly
			(pts
				(arc
					(start -4.2672 0)
					(mid 4.2672 0)
					(end -4.2672 0)
				)
			)
			(stroke
				(width 0)
				(type default)
			)
			(fill no)
			(layer "F.CrtYd")
		)
		(fp_circle
			(center 0 0)
			(end -4.2672 0)
			(stroke
				(width 0.1)
				(type default)
			)
			(fill no)
			(layer "F.Fab")
		)
		(fp_text user "+"
			(at -6.549898 -0.069596 180)
			(unlocked yes)
			(layer "F.SilkS")
			(effects
				(font
					(size 1.905 1.4224)
					(thickness 0.1524)
				)
				(justify left)
			)
		)
		(fp_text user "+"
			(at -5.6642 -0.34925 180)
			(unlocked yes)
			(layer "F.Fab")
			(effects
				(font
					(size 1.905 1.4224)
					(thickness 0.000001)
				)
				(justify left)
			)
		)
		(pad "1" thru_hole rect
			(at -1.75006 0 180)
			(size 1.397 1.397)
			(drill 0.9144)
			(layers "*.Cu" "*.Mask")
			(remove_unused_layers no)
			(net "P12V")
			(clearance 0.0127)
			(thermal_gap 0.0127)
			(padstack
				(mode front_inner_back)
				(layer "Inner"
					(shape circle)
					(size 1.397 1.397)
					(clearance 0.0127)
				)
				(layer "B.Cu"
					(shape rect)
					(size 1.397 1.397)
					(clearance 0.0127)
				)
			)
		)
		(pad "2" thru_hole circle
			(at 1.75006 0 180)
			(size 1.397 1.397)
			(drill 0.9144)
			(layers "*.Cu" "*.Mask")
			(remove_unused_layers no)
			(net "GND")
			(clearance 0.0127)
			(thermal_gap 0.0127)
		)
	)
	(footprint ""
		(layer "F.Cu")
		(at 69.108828 -304.009806 90)
		(property "Reference" "C54"
			(at 1.035812 0.169926 90)
			(unlocked yes)
			(layer "F.SilkS")
			(effects
				(font
					(size 0.7874 0.5842)
					(thickness 0.1524)
				)
				(justify left)
			)
		)
		(property "Value" ""
			(at 0 0 90)
			(layer "F.Fab")
			(effects
				(font
					(size 1.27 1.27)
				)
			)
		)
		(duplicate_pad_numbers_are_jumpers no)
		(fp_line
			(start 0.7874 -0.4064)
			(end 0.7874 0.4064)
			(stroke
				(width 0.1524)
				(type default)
			)
			(layer "F.SilkS")
		)
		(fp_line
			(start -0.7874 -0.4064)
			(end 0.7874 -0.4064)
			(stroke
				(width 0.1524)
				(type default)
			)
			(layer "F.SilkS")
		)
		(fp_line
			(start 0 0.381)
			(end 0 -0.381)
			(stroke
				(width 0.1524)
				(type default)
			)
			(layer "F.SilkS")
		)
		(fp_line
			(start 0.7874 0.4064)
			(end -0.7874 0.4064)
			(stroke
				(width 0.1524)
				(type default)
			)
			(layer "F.SilkS")
		)
		(fp_line
			(start -0.7874 0.4064)
			(end -0.7874 -0.4064)
			(stroke
				(width 0.1524)
				(type default)
			)
			(layer "F.SilkS")
		)
		(fp_poly
			(pts
				(xy -0.5334 0.254) (xy -0.635 0.254) (xy -0.635 0.2286) (xy -0.635 -0.254) (xy -0.5334 -0.254) (xy -0.5334 -0.2794)
				(xy 0.5334 -0.2794) (xy 0.5334 -0.254) (xy 0.635 -0.254) (xy 0.635 0.254) (xy 0.5334 0.254) (xy 0.5334 0.2794)
				(xy -0.508 0.2794) (xy -0.5334 0.2794)
			)
			(stroke
				(width 0)
				(type default)
			)
			(fill no)
			(layer "F.CrtYd")
		)
		(pad "1" smd rect
			(at 0.40005 0 90)
			(size 0.4572 0.508)
			(layers "F.Cu" "F.Mask" "F.Paste")
			(net "P12V")
		)
		(pad "2" smd rect
			(at -0.40005 0 90)
			(size 0.4572 0.508)
			(layers "F.Cu" "F.Mask" "F.Paste")
			(net "GND")
		)
	)
	(footprint ""
		(layer "F.Cu")
		(at 72.19696 -350.498918 90)
		(property "Reference" "C60"
			(at 1.140206 0.322072 90)
			(unlocked yes)
			(layer "F.SilkS")
			(effects
				(font
					(size 0.7874 0.5842)
					(thickness 0.1524)
				)
				(justify left)
			)
		)
		(property "Value" ""
			(at 0 0 90)
			(layer "F.Fab")
			(effects
				(font
					(size 1.27 1.27)
				)
			)
		)
		(duplicate_pad_numbers_are_jumpers no)
		(fp_line
			(start 0.7874 -0.4064)
			(end 0.7874 0.4064)
			(stroke
				(width 0.1524)
				(type default)
			)
			(layer "F.SilkS")
		)
		(fp_line
			(start -0.7874 -0.4064)
			(end 0.7874 -0.4064)
			(stroke
				(width 0.1524)
				(type default)
			)
			(layer "F.SilkS")
		)
		(fp_line
			(start 0 0.381)
			(end 0 -0.381)
			(stroke
				(width 0.1524)
				(type default)
			)
			(layer "F.SilkS")
		)
		(fp_line
			(start 0.7874 0.4064)
			(end -0.7874 0.4064)
			(stroke
				(width 0.1524)
				(type default)
			)
			(layer "F.SilkS")
		)
		(fp_line
			(start -0.7874 0.4064)
			(end -0.7874 -0.4064)
			(stroke
				(width 0.1524)
				(type default)
			)
			(layer "F.SilkS")
		)
		(fp_poly
			(pts
				(xy -0.5334 0.254) (xy -0.635 0.254) (xy -0.635 0.2286) (xy -0.635 -0.254) (xy -0.5334 -0.254) (xy -0.5334 -0.2794)
				(xy 0.5334 -0.2794) (xy 0.5334 -0.254) (xy 0.635 -0.254) (xy 0.635 0.254) (xy 0.5334 0.254) (xy 0.5334 0.2794)
				(xy -0.508 0.2794) (xy -0.5334 0.2794)
			)
			(stroke
				(width 0)
				(type default)
			)
			(fill no)
			(layer "F.CrtYd")
		)
		(pad "1" smd rect
			(at 0.40005 0 90)
			(size 0.4572 0.508)
			(layers "F.Cu" "F.Mask" "F.Paste")
			(net "P12V")
		)
		(pad "2" smd rect
			(at -0.40005 0 90)
			(size 0.4572 0.508)
			(layers "F.Cu" "F.Mask" "F.Paste")
			(net "GND")
		)
	)
	(footprint ""
		(layer "F.Cu")
		(at 69.41947 -216.615772 90)
		(property "Reference" "C40"
			(at 1.187196 -0.020574 90)
			(unlocked yes)
			(layer "F.SilkS")
			(effects
				(font
					(size 0.7874 0.5842)
					(thickness 0.1524)
				)
				(justify left)
			)
		)
		(property "Value" ""
			(at 0 0 90)
			(layer "F.Fab")
			(effects
				(font
					(size 1.27 1.27)
				)
			)
		)
		(duplicate_pad_numbers_are_jumpers no)
		(fp_line
			(start 0.7874 -0.4064)
			(end 0.7874 0.4064)
			(stroke
				(width 0.1524)
				(type default)
			)
			(layer "F.SilkS")
		)
		(fp_line
			(start -0.7874 -0.4064)
			(end 0.7874 -0.4064)
			(stroke
				(width 0.1524)
				(type default)
			)
			(layer "F.SilkS")
		)
		(fp_line
			(start 0 0.381)
			(end 0 -0.381)
			(stroke
				(width 0.1524)
				(type default)
			)
			(layer "F.SilkS")
		)
		(fp_line
			(start 0.7874 0.4064)
			(end -0.7874 0.4064)
			(stroke
				(width 0.1524)
				(type default)
			)
			(layer "F.SilkS")
		)
		(fp_line
			(start -0.7874 0.4064)
			(end -0.7874 -0.4064)
			(stroke
				(width 0.1524)
				(type default)
			)
			(layer "F.SilkS")
		)
		(fp_poly
			(pts
				(xy -0.5334 0.254) (xy -0.635 0.254) (xy -0.635 0.2286) (xy -0.635 -0.254) (xy -0.5334 -0.254) (xy -0.5334 -0.2794)
				(xy 0.5334 -0.2794) (xy 0.5334 -0.254) (xy 0.635 -0.254) (xy 0.635 0.254) (xy 0.5334 0.254) (xy 0.5334 0.2794)
				(xy -0.508 0.2794) (xy -0.5334 0.2794)
			)
			(stroke
				(width 0)
				(type default)
			)
			(fill no)
			(layer "F.CrtYd")
		)
		(pad "1" smd rect
			(at 0.40005 0 90)
			(size 0.4572 0.508)
			(layers "F.Cu" "F.Mask" "F.Paste")
			(net "P12V")
		)
		(pad "2" smd rect
			(at -0.40005 0 90)
			(size 0.4572 0.508)
			(layers "F.Cu" "F.Mask" "F.Paste")
			(net "GND")
		)
	)
	(footprint ""
		(layer "F.Cu")
		(at 73.532746 -439.03646 90)
		(property "Reference" "C74"
			(at 1.327912 0.190754 90)
			(unlocked yes)
			(layer "F.SilkS")
			(effects
				(font
					(size 0.7874 0.5842)
					(thickness 0.1524)
				)
				(justify left)
			)
		)
		(property "Value" ""
			(at 0 0 90)
			(layer "F.Fab")
			(effects
				(font
					(size 1.27 1.27)
				)
			)
		)
		(duplicate_pad_numbers_are_jumpers no)
		(fp_line
			(start 0.7874 -0.4064)
			(end 0.7874 0.4064)
			(stroke
				(width 0.1524)
				(type default)
			)
			(layer "F.SilkS")
		)
		(fp_line
			(start -0.7874 -0.4064)
			(end 0.7874 -0.4064)
			(stroke
				(width 0.1524)
				(type default)
			)
			(layer "F.SilkS")
		)
		(fp_line
			(start 0 0.381)
			(end 0 -0.381)
			(stroke
				(width 0.1524)
				(type default)
			)
			(layer "F.SilkS")
		)
		(fp_line
			(start 0.7874 0.4064)
			(end -0.7874 0.4064)
			(stroke
				(width 0.1524)
				(type default)
			)
			(layer "F.SilkS")
		)
		(fp_line
			(start -0.7874 0.4064)
			(end -0.7874 -0.4064)
			(stroke
				(width 0.1524)
				(type default)
			)
			(layer "F.SilkS")
		)
		(fp_poly
			(pts
				(xy -0.5334 0.254) (xy -0.635 0.254) (xy -0.635 0.2286) (xy -0.635 -0.254) (xy -0.5334 -0.254) (xy -0.5334 -0.2794)
				(xy 0.5334 -0.2794) (xy 0.5334 -0.254) (xy 0.635 -0.254) (xy 0.635 0.254) (xy 0.5334 0.254) (xy 0.5334 0.2794)
				(xy -0.508 0.2794) (xy -0.5334 0.2794)
			)
			(stroke
				(width 0)
				(type default)
			)
			(fill no)
			(layer "F.CrtYd")
		)
		(pad "1" smd rect
			(at 0.40005 0 90)
			(size 0.4572 0.508)
			(layers "F.Cu" "F.Mask" "F.Paste")
			(net "P12V")
		)
		(pad "2" smd rect
			(at -0.40005 0 90)
			(size 0.4572 0.508)
			(layers "F.Cu" "F.Mask" "F.Paste")
			(net "GND")
		)
	)
	(footprint ""
		(layer "F.Cu")
		(at 71.423022 -63.973456 -90)
		(property "Reference" "C10"
			(at -2.559304 0.082804 90)
			(unlocked yes)
			(layer "F.SilkS")
			(effects
				(font
					(size 0.7874 0.5842)
					(thickness 0.1524)
				)
				(justify left)
			)
		)
		(property "Value" ""
			(at 0 0 270)
			(layer "F.Fab")
			(effects
				(font
					(size 1.27 1.27)
				)
			)
		)
		(duplicate_pad_numbers_are_jumpers no)
		(fp_line
			(start -0.7874 0.4064)
			(end -0.7874 -0.4064)
			(stroke
				(width 0.1524)
				(type default)
			)
			(layer "F.SilkS")
		)
		(fp_line
			(start 0.7874 0.4064)
			(end -0.7874 0.4064)
			(stroke
				(width 0.1524)
				(type default)
			)
			(layer "F.SilkS")
		)
		(fp_line
			(start 0 0.381)
			(end 0 -0.381)
			(stroke
				(width 0.1524)
				(type default)
			)
			(layer "F.SilkS")
		)
		(fp_line
			(start -0.7874 -0.4064)
			(end 0.7874 -0.4064)
			(stroke
				(width 0.1524)
				(type default)
			)
			(layer "F.SilkS")
		)
		(fp_line
			(start 0.7874 -0.4064)
			(end 0.7874 0.4064)
			(stroke
				(width 0.1524)
				(type default)
			)
			(layer "F.SilkS")
		)
		(fp_poly
			(pts
				(xy -0.5334 0.254) (xy -0.635 0.254) (xy -0.635 0.2286) (xy -0.635 -0.254) (xy -0.5334 -0.254) (xy -0.5334 -0.2794)
				(xy 0.5334 -0.2794) (xy 0.5334 -0.254) (xy 0.635 -0.254) (xy 0.635 0.254) (xy 0.5334 0.254) (xy 0.5334 0.2794)
				(xy -0.508 0.2794) (xy -0.5334 0.2794)
			)
			(stroke
				(width 0)
				(type default)
			)
			(fill no)
			(layer "F.CrtYd")
		)
		(pad "1" smd rect
			(at 0.40005 0 270)
			(size 0.4572 0.508)
			(layers "F.Cu" "F.Mask" "F.Paste")
			(net "P12V")
		)
		(pad "2" smd rect
			(at -0.40005 0 270)
			(size 0.4572 0.508)
			(layers "F.Cu" "F.Mask" "F.Paste")
			(net "GND")
		)
	)
	(footprint ""
		(layer "F.Cu")
		(at 6.449822 -352.669856)
		(property "Reference" "J25"
			(at 6.653784 1.81356 90)
			(unlocked yes)
			(layer "F.SilkS")
			(effects
				(font
					(size 0.7874 0.5842)
					(thickness 0.1524)
				)
				(justify left)
			)
		)
		(property "Value" ""
			(at 0 0 0)
			(layer "F.Fab")
			(effects
				(font
					(size 1.27 1.27)
				)
			)
		)
		(duplicate_pad_numbers_are_jumpers no)
		(fp_line
			(start -9.400032 -5.999988)
			(end -9.400032 89.229946)
			(stroke
				(width 0.1524)
				(type default)
			)
			(layer "F.SilkS")
		)
		(fp_line
			(start -9.400032 89.229946)
			(end 5.649976 89.229946)
			(stroke
				(width 0.1524)
				(type default)
			)
			(layer "F.SilkS")
		)
		(fp_line
			(start -6.400038 -2.999994)
			(end 2.649982 -2.999994)
			(stroke
				(width 0.1524)
				(type default)
			)
			(layer "F.SilkS")
		)
		(fp_line
			(start -6.400038 86.229952)
			(end -6.400038 -2.999994)
			(stroke
				(width 0.1524)
				(type default)
			)
			(layer "F.SilkS")
		)
		(fp_line
			(start -2.265172 86.229952)
			(end -6.400038 86.229952)
			(stroke
				(width 0.1524)
				(type default)
			)
			(layer "F.SilkS")
		)
		(fp_line
			(start 2.649982 -2.999994)
			(end 2.649982 86.229952)
			(stroke
				(width 0.1524)
				(type default)
			)
			(layer "F.SilkS")
		)
		(fp_line
			(start 2.649982 86.229952)
			(end -0.334772 86.229952)
			(stroke
				(width 0.1524)
				(type default)
			)
			(layer "F.SilkS")
		)
		(fp_line
			(start 5.649976 -5.999988)
			(end -9.400032 -5.999988)
			(stroke
				(width 0.1524)
				(type default)
			)
			(layer "F.SilkS")
		)
		(fp_line
			(start 5.649976 89.229946)
			(end 5.649976 -5.999988)
			(stroke
				(width 0.1524)
				(type default)
			)
			(layer "F.SilkS")
		)
		(fp_poly
			(pts
				(xy 0.127 -6.569456) (xy 0.889 -8.474456) (xy -0.635 -8.474456)
			)
			(stroke
				(width 0)
				(type default)
			)
			(fill yes)
			(layer "F.SilkS")
		)
		(fp_line
			(start -9.400032 -5.999988)
			(end -9.400032 89.229946)
			(stroke
				(width 0.1524)
				(type default)
			)
			(layer "B.SilkS")
		)
		(fp_line
			(start -9.400032 89.229946)
			(end 5.649976 89.229946)
			(stroke
				(width 0.1524)
				(type default)
			)
			(layer "B.SilkS")
		)
		(fp_line
			(start -6.400038 -2.999994)
			(end 2.649982 -2.999994)
			(stroke
				(width 0.1524)
				(type default)
			)
			(layer "B.SilkS")
		)
		(fp_line
			(start -6.400038 86.229952)
			(end -6.400038 -2.999994)
			(stroke
				(width 0.1524)
				(type default)
			)
			(layer "B.SilkS")
		)
		(fp_line
			(start -2.265172 86.229952)
			(end -6.400038 86.229952)
			(stroke
				(width 0.1524)
				(type default)
			)
			(layer "B.SilkS")
		)
		(fp_line
			(start 2.649982 -2.999994)
			(end 2.649982 86.229952)
			(stroke
				(width 0.1524)
				(type default)
			)
			(layer "B.SilkS")
		)
		(fp_line
			(start 2.649982 86.229952)
			(end -0.334772 86.229952)
			(stroke
				(width 0.1524)
				(type default)
			)
			(layer "B.SilkS")
		)
		(fp_line
			(start 5.649976 -5.999988)
			(end -9.400032 -5.999988)
			(stroke
				(width 0.1524)
				(type default)
			)
			(layer "B.SilkS")
		)
		(fp_line
			(start 5.649976 89.229946)
			(end 5.649976 -5.999988)
			(stroke
				(width 0.1524)
				(type default)
			)
			(layer "B.SilkS")
		)
		(fp_poly
			(pts
				(xy 0.127 -6.569456) (xy 0.889 -8.474456) (xy -0.635 -8.474456)
			)
			(stroke
				(width 0)
				(type default)
			)
			(fill yes)
			(layer "B.SilkS")
		)
		(fp_poly
			(pts
				(xy 2.5654 -0.5842) (xy -5.08 -0.5842) (xy -5.08 86.2838) (xy 2.5654 86.2838)
			)
			(stroke
				(width 0)
				(type default)
			)
			(fill no)
			(layer "B.CrtYd")
		)
		(fp_poly
			(pts
				(xy -6.400038 -2.999994) (xy -6.400038 86.229952) (xy -1.624838 86.229952) (xy -1.624838 86.2838)
				(xy -0.964438 86.2838) (xy -0.964438 86.229952) (xy 2.649982 86.229952) (xy 2.649982 -2.999994)
			)
			(stroke
				(width 0)
				(type default)
			)
			(fill no)
			(layer "F.CrtYd")
		)
		(fp_line
			(start -6.400038 -2.999994)
			(end -6.400038 86.229952)
			(stroke
				(width 0.1)
				(type default)
			)
			(layer "F.Fab")
		)
		(fp_line
			(start -6.400038 86.229952)
			(end 2.649982 86.229952)
			(stroke
				(width 0.1)
				(type default)
			)
			(layer "F.Fab")
		)
		(fp_line
			(start 2.649982 -2.999994)
			(end -6.400038 -2.999994)
			(stroke
				(width 0.1)
				(type default)
			)
			(layer "F.Fab")
		)
		(fp_line
			(start 2.649982 86.229952)
			(end 2.649982 -2.999994)
			(stroke
				(width 0.1)
				(type default)
			)
			(layer "F.Fab")
		)
		(fp_text user "B82"
			(at -4.692142 85.662262 90)
			(unlocked yes)
			(layer "F.SilkS")
			(effects
				(font
					(size 0.7874 0.5842)
					(thickness 0.1524)
				)
				(justify left)
			)
		)
		(fp_text user "B2"
			(at -4.289298 -3.45821 90)
			(unlocked yes)
			(layer "F.SilkS")
			(effects
				(font
					(size 0.7874 0.5842)
					(thickness 0.1524)
				)
				(justify left)
			)
		)
		(fp_text user "B81"
			(at -3.288538 85.729064 90)
			(unlocked yes)
			(layer "F.SilkS")
			(effects
				(font
					(size 0.7874 0.5842)
					(thickness 0.1524)
				)
				(justify left)
			)
		)
		(fp_text user "B1"
			(at -2.289302 -3.45821 90)
			(unlocked yes)
			(layer "F.SilkS")
			(effects
				(font
					(size 0.7874 0.5842)
					(thickness 0.1524)
				)
				(justify left)
			)
		)
		(fp_text user "A1"
			(at -0.09017 -3.658616 90)
			(unlocked yes)
			(layer "F.SilkS")
			(effects
				(font
					(size 0.7874 0.5842)
					(thickness 0.1524)
				)
				(justify left)
			)
		)
		(fp_text user "A2"
			(at 1.91008 -3.658616 90)
			(unlocked yes)
			(layer "F.SilkS")
			(effects
				(font
					(size 0.7874 0.5842)
					(thickness 0.1524)
				)
				(justify left)
			)
		)
		(fp_text user "A81"
			(at 1.930908 85.713824 90)
			(unlocked yes)
			(layer "F.SilkS")
			(effects
				(font
					(size 0.7874 0.5842)
					(thickness 0.1524)
				)
				(justify left)
			)
		)
		(fp_text user "PRESS  FIT"
			(at 8.750046 8.877046 90)
			(unlocked yes)
			(layer "F.SilkS")
			(effects
				(font
					(size 1.27 0.9652)
					(thickness 0.1524)
				)
				(justify left)
			)
		)
		(fp_text user "A82"
			(at 11.784584 85.145626 90)
			(unlocked yes)
			(layer "F.SilkS")
			(effects
				(font
					(size 0.7874 0.5842)
					(thickness 0.1524)
				)
				(justify left)
			)
		)
		(fp_text user "B2"
			(at -4.40817 0.275844 270)
			(unlocked yes)
			(layer "B.SilkS")
			(effects
				(font
					(size 0.7874 0.5842)
					(thickness 0.1524)
				)
				(justify left mirror)
			)
		)
		(fp_text user "B82"
			(at -4.40817 86.013544 270)
			(unlocked yes)
			(layer "B.SilkS")
			(effects
				(font
					(size 0.7874 0.5842)
					(thickness 0.1524)
				)
				(justify left mirror)
			)
		)
		(fp_text user "B81"
			(at -3.170174 84.489544 270)
			(unlocked yes)
			(layer "B.SilkS")
			(effects
				(font
					(size 0.7874 0.5842)
					(thickness 0.1524)
				)
				(justify left mirror)
			)
		)
		(fp_text user "B1"
			(at -2.408174 -0.867156 270)
			(unlocked yes)
			(layer "B.SilkS")
			(effects
				(font
					(size 0.7874 0.5842)
					(thickness 0.1524)
				)
				(justify left mirror)
			)
		)
		(fp_text user "A1"
			(at 0.091694 -0.867156 270)
			(unlocked yes)
			(layer "B.SilkS")
			(effects
				(font
					(size 0.7874 0.5842)
					(thickness 0.1524)
				)
				(justify left mirror)
			)
		)
		(fp_text user "A81"
			(at 0.861568 84.897722 270)
			(unlocked yes)
			(layer "B.SilkS")
			(effects
				(font
					(size 0.7874 0.5842)
					(thickness 0.1524)
				)
				(justify left mirror)
			)
		)
		(fp_text user "A2"
			(at 2.091944 0.275844 270)
			(unlocked yes)
			(layer "B.SilkS")
			(effects
				(font
					(size 0.7874 0.5842)
					(thickness 0.1524)
				)
				(justify left mirror)
			)
		)
		(fp_text user "A82"
			(at 2.091944 86.013544 270)
			(unlocked yes)
			(layer "B.SilkS")
			(effects
				(font
					(size 0.7874 0.5842)
					(thickness 0.1524)
				)
				(justify left mirror)
			)
		)
		(fp_text user "PRESS  FIT"
			(at 11.557254 39.706804 270)
			(unlocked yes)
			(layer "B.SilkS")
			(effects
				(font
					(size 1.6002 1.1938)
					(thickness 0.000001)
				)
				(justify left mirror)
			)
		)
		(pad "" np_thru_hole circle
			(at -1.249934 11.649964 270)
			(size 2.413 2.413)
			(drill 2.413)
			(layers "*.Cu" "*.Mask")
			(clearance 0.381)
			(thermal_gap 0.381)
		)
		(pad "" np_thru_hole circle
			(at -1.249934 84.799932 270)
			(size 2.413 2.413)
			(drill 2.413)
			(layers "*.Cu" "*.Mask")
			(clearance 0.381)
			(thermal_gap 0.381)
		)
		(pad "A1" thru_hole rect
			(at 0 0 270)
			(size 1.016 1.016)
			(drill 0.7112)
			(layers "*.Cu" "*.Mask")
			(remove_unused_layers no)
			(net "MATE_A1")
			(clearance 0.1016)
			(thermal_gap 0.1016)
			(padstack
				(mode front_inner_back)
				(layer "Inner"
					(shape circle)
					(size 1.016 1.016)
					(clearance 0.1016)
				)
				(layer "B.Cu"
					(shape rect)
					(size 1.016 1.016)
					(clearance 0.1016)
				)
			)
		)
		(pad "A2" thru_hole circle
			(at 1.999996 0.999998 270)
			(size 1.016 1.016)
			(drill 0.7112)
			(layers "*.Cu" "*.Mask")
			(remove_unused_layers no)
			(net "GND")
			(clearance 0.1016)
			(thermal_gap 0.1016)
		)
		(pad "A3" thru_hole circle
			(at 0 1.999996 270)
			(size 1.016 1.016)
			(drill 0.7112)
			(layers "*.Cu" "*.Mask")
			(remove_unused_layers no)
			(net "LAN2_P3_P")
			(clearance 0.1016)
			(thermal_gap 0.1016)
		)
		(pad "A4" thru_hole circle
			(at 1.999996 2.999994 270)
			(size 1.016 1.016)
			(drill 0.7112)
			(layers "*.Cu" "*.Mask")
			(remove_unused_layers no)
			(net "LAN2_P3_N")
			(clearance 0.1016)
			(thermal_gap 0.1016)
		)
		(pad "A5" thru_hole circle
			(at 0 3.999992 270)
			(size 1.016 1.016)
			(drill 0.7112)
			(layers "*.Cu" "*.Mask")
			(remove_unused_layers no)
			(net "GND")
			(clearance 0.1016)
			(thermal_gap 0.1016)
		)
		(pad "A6" thru_hole circle
			(at 1.999996 4.99999 270)
			(size 1.016 1.016)
			(drill 0.7112)
			(layers "*.Cu" "*.Mask")
			(remove_unused_layers no)
			(net "LAN2_P4_P")
			(clearance 0.1016)
			(thermal_gap 0.1016)
		)
		(pad "A7" thru_hole circle
			(at 0 5.999988 270)
			(size 1.016 1.016)
			(drill 0.7112)
			(layers "*.Cu" "*.Mask")
			(remove_unused_layers no)
			(net "LAN2_P4_N")
			(clearance 0.1016)
			(thermal_gap 0.1016)
		)
		(pad "A8" thru_hole circle
			(at 1.999996 6.999986 270)
			(size 1.016 1.016)
			(drill 0.7112)
			(layers "*.Cu" "*.Mask")
			(remove_unused_layers no)
			(net "GND")
			(clearance 0.1016)
			(thermal_gap 0.1016)
		)
		(pad "A9" thru_hole circle
			(at 0 7.999984 270)
			(size 1.016 1.016)
			(drill 0.7112)
			(layers "*.Cu" "*.Mask")
			(remove_unused_layers no)
			(net "POWER_SW3_PWR_CTR_12V")
			(clearance 0.1016)
			(thermal_gap 0.1016)
		)
		(pad "A10" thru_hole circle
			(at 1.999996 8.999982 270)
			(size 1.016 1.016)
			(drill 0.7112)
			(layers "*.Cu" "*.Mask")
			(remove_unused_layers no)
			(net "POWER_SW2_PWR_CTR_12V")
			(clearance 0.1016)
			(thermal_gap 0.1016)
		)
		(pad "A11" thru_hole circle
			(at 0 9.99998 270)
			(size 1.016 1.016)
			(drill 0.7112)
			(layers "*.Cu" "*.Mask")
			(remove_unused_layers no)
			(net "POWER_SW1_PWR_CTR_12V")
			(clearance 0.1016)
			(thermal_gap 0.1016)
		)
		(pad "A12" thru_hole circle
			(at 1.999996 12.999974 270)
			(size 1.016 1.016)
			(drill 0.7112)
			(layers "*.Cu" "*.Mask")
			(remove_unused_layers no)
			(net "GND36")
			(clearance 0.1016)
			(thermal_gap 0.1016)
		)
		(pad "A13" thru_hole circle
			(at 0 13.999972 270)
			(size 1.016 1.016)
			(drill 0.7112)
			(layers "*.Cu" "*.Mask")
			(remove_unused_layers no)
			(net "Net_439")
			(clearance 0.1016)
			(thermal_gap 0.1016)
		)
		(pad "A14" thru_hole circle
			(at 1.999996 14.99997 270)
			(size 1.016 1.016)
			(drill 0.7112)
			(layers "*.Cu" "*.Mask")
			(remove_unused_layers no)
			(net "Net_438")
			(clearance 0.1016)
			(thermal_gap 0.1016)
		)
		(pad "A15" thru_hole circle
			(at 0 15.999968 270)
			(size 1.016 1.016)
			(drill 0.7112)
			(layers "*.Cu" "*.Mask")
			(remove_unused_layers no)
			(net "GND37")
			(clearance 0.1016)
			(thermal_gap 0.1016)
		)
		(pad "A16" thru_hole circle
			(at 1.999996 16.999966 270)
			(size 1.016 1.016)
			(drill 0.7112)
			(layers "*.Cu" "*.Mask")
			(remove_unused_layers no)
			(net "Net_443")
			(clearance 0.1016)
			(thermal_gap 0.1016)
		)
		(pad "A17" thru_hole circle
			(at 0 17.999964 270)
			(size 1.016 1.016)
			(drill 0.7112)
			(layers "*.Cu" "*.Mask")
			(remove_unused_layers no)
			(net "GND")
			(clearance 0.1016)
			(thermal_gap 0.1016)
		)
		(pad "A18" thru_hole circle
			(at 1.999996 18.999962 270)
			(size 1.016 1.016)
			(drill 0.7112)
			(layers "*.Cu" "*.Mask")
			(remove_unused_layers no)
			(net "GND38")
			(clearance 0.1016)
			(thermal_gap 0.1016)
		)
		(pad "A19" thru_hole circle
			(at 0 19.99996 270)
			(size 1.016 1.016)
			(drill 0.7112)
			(layers "*.Cu" "*.Mask")
			(remove_unused_layers no)
			(net "Net_6")
			(clearance 0.1016)
			(thermal_gap 0.1016)
		)
		(pad "A20" thru_hole circle
			(at 1.999996 20.999958 270)
			(size 1.016 1.016)
			(drill 0.7112)
			(layers "*.Cu" "*.Mask")
			(remove_unused_layers no)
			(net "GND39")
			(clearance 0.1016)
			(thermal_gap 0.1016)
		)
		(pad "A21" thru_hole circle
			(at 0 21.999956 270)
			(size 1.016 1.016)
			(drill 0.7112)
			(layers "*.Cu" "*.Mask")
			(remove_unused_layers no)
			(net "Net_4")
			(clearance 0.1016)
			(thermal_gap 0.1016)
		)
		(pad "A22" thru_hole circle
			(at 1.999996 22.999954 270)
			(size 1.016 1.016)
			(drill 0.7112)
			(layers "*.Cu" "*.Mask")
			(remove_unused_layers no)
			(net "Net_5")
			(clearance 0.1016)
			(thermal_gap 0.1016)
		)
		(pad "A23" thru_hole circle
			(at 0 23.999952 270)
			(size 1.016 1.016)
			(drill 0.7112)
			(layers "*.Cu" "*.Mask")
			(remove_unused_layers no)
			(net "GND40")
			(clearance 0.1016)
			(thermal_gap 0.1016)
		)
		(pad "A24" thru_hole circle
			(at 1.999996 24.99995 270)
			(size 1.016 1.016)
			(drill 0.7112)
			(layers "*.Cu" "*.Mask")
			(remove_unused_layers no)
			(net "GND41")
			(clearance 0.1016)
			(thermal_gap 0.1016)
		)
		(pad "A25" thru_hole circle
			(at 0 25.999948 270)
			(size 1.016 1.016)
			(drill 0.7112)
			(layers "*.Cu" "*.Mask")
			(remove_unused_layers no)
			(net "GND")
			(clearance 0.1016)
			(thermal_gap 0.1016)
		)
		(pad "A26" thru_hole circle
			(at 1.999996 26.999946 270)
			(size 1.016 1.016)
			(drill 0.7112)
			(layers "*.Cu" "*.Mask")
			(remove_unused_layers no)
			(net "FAN4_TACH")
			(clearance 0.1016)
			(thermal_gap 0.1016)
		)
		(pad "A27" thru_hole circle
			(at 0 27.999944 270)
			(size 1.016 1.016)
			(drill 0.7112)
			(layers "*.Cu" "*.Mask")
			(remove_unused_layers no)
			(net "FAN5_TACH")
			(clearance 0.1016)
			(thermal_gap 0.1016)
		)
		(pad "A28" thru_hole circle
			(at 1.999996 28.999942 270)
			(size 1.016 1.016)
			(drill 0.7112)
			(layers "*.Cu" "*.Mask")
			(remove_unused_layers no)
			(net "FAN6_TACH")
			(clearance 0.1016)
			(thermal_gap 0.1016)
		)
		(pad "A29" thru_hole circle
			(at 0 29.99994 270)
			(size 1.016 1.016)
			(drill 0.7112)
			(layers "*.Cu" "*.Mask")
			(remove_unused_layers no)
			(net "GND")
			(clearance 0.1016)
			(thermal_gap 0.1016)
		)
		(pad "A30" thru_hole circle
			(at 1.999996 30.999938 270)
			(size 1.016 1.016)
			(drill 0.7112)
			(layers "*.Cu" "*.Mask")
			(remove_unused_layers no)
			(net "FAN_PWM")
			(clearance 0.1016)
			(thermal_gap 0.1016)
		)
		(pad "A31" thru_hole circle
			(at 0 31.999936 270)
			(size 1.016 1.016)
			(drill 0.7112)
			(layers "*.Cu" "*.Mask")
			(remove_unused_layers no)
			(net "GND")
			(clearance 0.1016)
			(thermal_gap 0.1016)
		)
		(pad "A32" thru_hole circle
			(at 1.999996 32.999934 270)
			(size 1.016 1.016)
			(drill 0.7112)
			(layers "*.Cu" "*.Mask")
			(remove_unused_layers no)
			(net "I2C_PSU3_SCL")
			(clearance 0.1016)
			(thermal_gap 0.1016)
		)
		(pad "A33" thru_hole circle
			(at 0 33.999932 270)
			(size 1.016 1.016)
			(drill 0.7112)
			(layers "*.Cu" "*.Mask")
			(remove_unused_layers no)
			(net "I2C_PSU3_SDA")
			(clearance 0.1016)
			(thermal_gap 0.1016)
		)
		(pad "A34" thru_hole circle
			(at 1.999996 34.99993 270)
			(size 1.016 1.016)
			(drill 0.7112)
			(layers "*.Cu" "*.Mask")
			(remove_unused_layers no)
			(net "GND")
			(clearance 0.1016)
			(thermal_gap 0.1016)
		)
		(pad "A35" thru_hole circle
			(at 0 35.999928 270)
			(size 1.016 1.016)
			(drill 0.7112)
			(layers "*.Cu" "*.Mask")
			(remove_unused_layers no)
			(net "T11_BLAD1_EN")
			(clearance 0.1016)
			(thermal_gap 0.1016)
		)
		(pad "A36" thru_hole circle
			(at 1.999996 36.999926 270)
			(size 1.016 1.016)
			(drill 0.7112)
			(layers "*.Cu" "*.Mask")
			(remove_unused_layers no)
			(net "TP_T11_BLAD2_EN")
			(clearance 0.1016)
			(thermal_gap 0.1016)
		)
		(pad "A37" thru_hole circle
			(at 0 37.999924 270)
			(size 1.016 1.016)
			(drill 0.7112)
			(layers "*.Cu" "*.Mask")
			(remove_unused_layers no)
			(net "T11_BLAD3_EN")
			(clearance 0.1016)
			(thermal_gap 0.1016)
		)
		(pad "A38" thru_hole circle
			(at 1.999996 38.999922 270)
			(size 1.016 1.016)
			(drill 0.7112)
			(layers "*.Cu" "*.Mask")
			(remove_unused_layers no)
			(net "TP_T11_BLAD4_EN")
			(clearance 0.1016)
			(thermal_gap 0.1016)
		)
		(pad "A39" thru_hole circle
			(at 0 39.99992 270)
			(size 1.016 1.016)
			(drill 0.7112)
			(layers "*.Cu" "*.Mask")
			(remove_unused_layers no)
			(net "GND")
			(clearance 0.1016)
			(thermal_gap 0.1016)
		)
		(pad "A40" thru_hole circle
			(at 1.999996 40.999918 270)
			(size 1.016 1.016)
			(drill 0.7112)
			(layers "*.Cu" "*.Mask")
			(remove_unused_layers no)
			(net "T11_BLAD1_RXD")
			(clearance 0.1016)
			(thermal_gap 0.1016)
		)
		(pad "A41" thru_hole circle
			(at 0 41.999916 270)
			(size 1.016 1.016)
			(drill 0.7112)
			(layers "*.Cu" "*.Mask")
			(remove_unused_layers no)
			(net "T11_BLAD1_TXD")
			(clearance 0.1016)
			(thermal_gap 0.1016)
		)
		(pad "A42" thru_hole circle
			(at 1.999996 42.999914 270)
			(size 1.016 1.016)
			(drill 0.7112)
			(layers "*.Cu" "*.Mask")
			(remove_unused_layers no)
			(net "T11_BLAD2_RXD")
			(clearance 0.1016)
			(thermal_gap 0.1016)
		)
		(pad "A43" thru_hole circle
			(at 0 43.999912 270)
			(size 1.016 1.016)
			(drill 0.7112)
			(layers "*.Cu" "*.Mask")
			(remove_unused_layers no)
			(net "T11_BLAD2_TXD")
			(clearance 0.1016)
			(thermal_gap 0.1016)
		)
		(pad "A44" thru_hole circle
			(at 1.999996 44.99991 270)
			(size 1.016 1.016)
			(drill 0.7112)
			(layers "*.Cu" "*.Mask")
			(remove_unused_layers no)
			(net "GND")
			(clearance 0.1016)
			(thermal_gap 0.1016)
		)
		(pad "A45" thru_hole circle
			(at 0 45.999908 270)
			(size 1.016 1.016)
			(drill 0.7112)
			(layers "*.Cu" "*.Mask")
			(remove_unused_layers no)
			(net "T11_BLAD3_RXD")
			(clearance 0.1016)
			(thermal_gap 0.1016)
		)
		(pad "A46" thru_hole circle
			(at 1.999996 46.999906 270)
			(size 1.016 1.016)
			(drill 0.7112)
			(layers "*.Cu" "*.Mask")
			(remove_unused_layers no)
			(net "T11_BLAD3_TXD")
			(clearance 0.1016)
			(thermal_gap 0.1016)
		)
		(pad "A47" thru_hole circle
			(at 0 47.999904 270)
			(size 1.016 1.016)
			(drill 0.7112)
			(layers "*.Cu" "*.Mask")
			(remove_unused_layers no)
			(net "T11_BLAD4_RXD")
			(clearance 0.1016)
			(thermal_gap 0.1016)
		)
		(pad "A48" thru_hole circle
			(at 1.999996 48.999902 270)
			(size 1.016 1.016)
			(drill 0.7112)
			(layers "*.Cu" "*.Mask")
			(remove_unused_layers no)
			(net "T11_BLAD4_TXD")
			(clearance 0.1016)
			(thermal_gap 0.1016)
		)
		(pad "A49" thru_hole circle
			(at 0 49.9999 270)
			(size 1.016 1.016)
			(drill 0.7112)
			(layers "*.Cu" "*.Mask")
			(remove_unused_layers no)
			(net "GND")
			(clearance 0.1016)
			(thermal_gap 0.1016)
		)
		(pad "A50" thru_hole circle
			(at 1.999996 50.999898 270)
			(size 1.016 1.016)
			(drill 0.7112)
			(layers "*.Cu" "*.Mask")
			(remove_unused_layers no)
			(net "T9_BLAD1_EN")
			(clearance 0.1016)
			(thermal_gap 0.1016)
		)
		(pad "A51" thru_hole circle
			(at 0 51.999896 270)
			(size 1.016 1.016)
			(drill 0.7112)
			(layers "*.Cu" "*.Mask")
			(remove_unused_layers no)
			(net "TP_T9_BLAD2_EN")
			(clearance 0.1016)
			(thermal_gap 0.1016)
		)
		(pad "A52" thru_hole circle
			(at 1.999996 52.999894 270)
			(size 1.016 1.016)
			(drill 0.7112)
			(layers "*.Cu" "*.Mask")
			(remove_unused_layers no)
			(net "T9_BLAD3_EN")
			(clearance 0.1016)
			(thermal_gap 0.1016)
		)
		(pad "A53" thru_hole circle
			(at 0 53.999892 270)
			(size 1.016 1.016)
			(drill 0.7112)
			(layers "*.Cu" "*.Mask")
			(remove_unused_layers no)
			(net "TP_T9_BLAD4_EN")
			(clearance 0.1016)
			(thermal_gap 0.1016)
		)
		(pad "A54" thru_hole circle
			(at 1.999996 54.99989 270)
			(size 1.016 1.016)
			(drill 0.7112)
			(layers "*.Cu" "*.Mask")
			(remove_unused_layers no)
			(net "GND")
			(clearance 0.1016)
			(thermal_gap 0.1016)
		)
		(pad "A55" thru_hole circle
			(at 0 55.999888 270)
			(size 1.016 1.016)
			(drill 0.7112)
			(layers "*.Cu" "*.Mask")
			(remove_unused_layers no)
			(net "T9_BLAD1_RXD")
			(clearance 0.1016)
			(thermal_gap 0.1016)
		)
		(pad "A56" thru_hole circle
			(at 1.999996 56.999886 270)
			(size 1.016 1.016)
			(drill 0.7112)
			(layers "*.Cu" "*.Mask")
			(remove_unused_layers no)
			(net "T9_BLAD1_TXD")
			(clearance 0.1016)
			(thermal_gap 0.1016)
		)
		(pad "A57" thru_hole circle
			(at 0 57.999884 270)
			(size 1.016 1.016)
			(drill 0.7112)
			(layers "*.Cu" "*.Mask")
			(remove_unused_layers no)
			(net "T9_BLAD2_RXD")
			(clearance 0.1016)
			(thermal_gap 0.1016)
		)
		(pad "A58" thru_hole circle
			(at 1.999996 59.000136 270)
			(size 1.016 1.016)
			(drill 0.7112)
			(layers "*.Cu" "*.Mask")
			(remove_unused_layers no)
			(net "T9_BLAD2_TXD")
			(clearance 0.1016)
			(thermal_gap 0.1016)
		)
		(pad "A59" thru_hole circle
			(at 0 59.99988 270)
			(size 1.016 1.016)
			(drill 0.7112)
			(layers "*.Cu" "*.Mask")
			(remove_unused_layers no)
			(net "GND")
			(clearance 0.1016)
			(thermal_gap 0.1016)
		)
		(pad "A60" thru_hole circle
			(at 1.999996 61.000132 270)
			(size 1.016 1.016)
			(drill 0.7112)
			(layers "*.Cu" "*.Mask")
			(remove_unused_layers no)
			(net "T9_BLAD3_RXD")
			(clearance 0.1016)
			(thermal_gap 0.1016)
		)
		(pad "A61" thru_hole circle
			(at 0 61.999876 270)
			(size 1.016 1.016)
			(drill 0.7112)
			(layers "*.Cu" "*.Mask")
			(remove_unused_layers no)
			(net "T9_BLAD3_TXD")
			(clearance 0.1016)
			(thermal_gap 0.1016)
		)
		(pad "A62" thru_hole circle
			(at 1.999996 63.000128 270)
			(size 1.016 1.016)
			(drill 0.7112)
			(layers "*.Cu" "*.Mask")
			(remove_unused_layers no)
			(net "T9_BLAD4_RXD")
			(clearance 0.1016)
			(thermal_gap 0.1016)
		)
		(pad "A63" thru_hole circle
			(at 0 63.999872 270)
			(size 1.016 1.016)
			(drill 0.7112)
			(layers "*.Cu" "*.Mask")
			(remove_unused_layers no)
			(net "T9_BLAD4_TXD")
			(clearance 0.1016)
			(thermal_gap 0.1016)
		)
		(pad "A64" thru_hole circle
			(at 1.999996 65.000124 270)
			(size 1.016 1.016)
			(drill 0.7112)
			(layers "*.Cu" "*.Mask")
			(remove_unused_layers no)
			(net "GND")
			(clearance 0.1016)
			(thermal_gap 0.1016)
		)
		(pad "A65" thru_hole circle
			(at 0 65.999868 270)
			(size 1.016 1.016)
			(drill 0.7112)
			(layers "*.Cu" "*.Mask")
			(remove_unused_layers no)
			(net "T7_BLAD1_EN")
			(clearance 0.1016)
			(thermal_gap 0.1016)
		)
		(pad "A66" thru_hole circle
			(at 1.999996 67.00012 270)
			(size 1.016 1.016)
			(drill 0.7112)
			(layers "*.Cu" "*.Mask")
			(remove_unused_layers no)
			(net "TP_T7_BLAD2_EN")
			(clearance 0.1016)
			(thermal_gap 0.1016)
		)
		(pad "A67" thru_hole circle
			(at 0 67.999864 270)
			(size 1.016 1.016)
			(drill 0.7112)
			(layers "*.Cu" "*.Mask")
			(remove_unused_layers no)
			(net "T7_BLAD3_EN")
			(clearance 0.1016)
			(thermal_gap 0.1016)
		)
		(pad "A68" thru_hole circle
			(at 1.999996 69.000116 270)
			(size 1.016 1.016)
			(drill 0.7112)
			(layers "*.Cu" "*.Mask")
			(remove_unused_layers no)
			(net "TP_T7_BLAD4_EN")
			(clearance 0.1016)
			(thermal_gap 0.1016)
		)
		(pad "A69" thru_hole circle
			(at 0 70.000114 270)
			(size 1.016 1.016)
			(drill 0.7112)
			(layers "*.Cu" "*.Mask")
			(remove_unused_layers no)
			(net "GND")
			(clearance 0.1016)
			(thermal_gap 0.1016)
		)
		(pad "A70" thru_hole circle
			(at 1.999996 71.000112 270)
			(size 1.016 1.016)
			(drill 0.7112)
			(layers "*.Cu" "*.Mask")
			(remove_unused_layers no)
			(net "T7_BLAD1_RXD")
			(clearance 0.1016)
			(thermal_gap 0.1016)
		)
		(pad "A71" thru_hole circle
			(at 0 72.00011 270)
			(size 1.016 1.016)
			(drill 0.7112)
			(layers "*.Cu" "*.Mask")
			(remove_unused_layers no)
			(net "T7_BLAD1_TXD")
			(clearance 0.1016)
			(thermal_gap 0.1016)
		)
		(pad "A72" thru_hole circle
			(at 1.999996 73.000108 270)
			(size 1.016 1.016)
			(drill 0.7112)
			(layers "*.Cu" "*.Mask")
			(remove_unused_layers no)
			(net "T7_BLAD2_RXD")
			(clearance 0.1016)
			(thermal_gap 0.1016)
		)
		(pad "A73" thru_hole circle
			(at 0 74.000106 270)
			(size 1.016 1.016)
			(drill 0.7112)
			(layers "*.Cu" "*.Mask")
			(remove_unused_layers no)
			(net "T7_BLAD2_TXD")
			(clearance 0.1016)
			(thermal_gap 0.1016)
		)
		(pad "A74" thru_hole circle
			(at 1.999996 75.000104 270)
			(size 1.016 1.016)
			(drill 0.7112)
			(layers "*.Cu" "*.Mask")
			(remove_unused_layers no)
			(net "GND")
			(clearance 0.1016)
			(thermal_gap 0.1016)
		)
		(pad "A75" thru_hole circle
			(at 0 76.000102 270)
			(size 1.016 1.016)
			(drill 0.7112)
			(layers "*.Cu" "*.Mask")
			(remove_unused_layers no)
			(net "T7_BLAD3_RXD")
			(clearance 0.1016)
			(thermal_gap 0.1016)
		)
		(pad "A76" thru_hole circle
			(at 1.999996 77.0001 270)
			(size 1.016 1.016)
			(drill 0.7112)
			(layers "*.Cu" "*.Mask")
			(remove_unused_layers no)
			(net "T7_BLAD3_TXD")
			(clearance 0.1016)
			(thermal_gap 0.1016)
		)
		(pad "A77" thru_hole circle
			(at 0 78.000098 270)
			(size 1.016 1.016)
			(drill 0.7112)
			(layers "*.Cu" "*.Mask")
			(remove_unused_layers no)
			(net "T7_BLAD4_RXD")
			(clearance 0.1016)
			(thermal_gap 0.1016)
		)
		(pad "A78" thru_hole circle
			(at 1.999996 79.000096 270)
			(size 1.016 1.016)
			(drill 0.7112)
			(layers "*.Cu" "*.Mask")
			(remove_unused_layers no)
			(net "T7_BLAD4_TXD")
			(clearance 0.1016)
			(thermal_gap 0.1016)
		)
		(pad "A79" thru_hole circle
			(at 0 80.000094 270)
			(size 1.016 1.016)
			(drill 0.7112)
			(layers "*.Cu" "*.Mask")
			(remove_unused_layers no)
			(net "GND")
			(clearance 0.1016)
			(thermal_gap 0.1016)
		)
		(pad "A80" thru_hole circle
			(at 1.999996 81.000092 270)
			(size 1.016 1.016)
			(drill 0.7112)
			(layers "*.Cu" "*.Mask")
			(remove_unused_layers no)
			(net "PSU_ALERT_N")
			(clearance 0.1016)
			(thermal_gap 0.1016)
		)
		(pad "A81" thru_hole circle
			(at 0 82.00009 270)
			(size 1.016 1.016)
			(drill 0.7112)
			(layers "*.Cu" "*.Mask")
			(remove_unused_layers no)
			(net "T5_BLAD1_EN")
			(clearance 0.1016)
			(thermal_gap 0.1016)
		)
		(pad "A82" thru_hole circle
			(at 1.999996 83.000088 270)
			(size 1.016 1.016)
			(drill 0.7112)
			(layers "*.Cu" "*.Mask")
			(remove_unused_layers no)
			(net "TP_T5_BLAD2_EN")
			(clearance 0.1016)
			(thermal_gap 0.1016)
		)
		(pad "B1" thru_hole circle
			(at -2.499868 0 270)
			(size 1.016 1.016)
			(drill 0.7112)
			(layers "*.Cu" "*.Mask")
			(remove_unused_layers no)
			(net "GND")
			(clearance 0.1016)
			(thermal_gap 0.1016)
		)
		(pad "B2" thru_hole circle
			(at -4.499864 0.999998 270)
			(size 1.016 1.016)
			(drill 0.7112)
			(layers "*.Cu" "*.Mask")
			(remove_unused_layers no)
			(net "LAN2_P1_P")
			(clearance 0.1016)
			(thermal_gap 0.1016)
		)
		(pad "B3" thru_hole circle
			(at -2.499868 1.999996 270)
			(size 1.016 1.016)
			(drill 0.7112)
			(layers "*.Cu" "*.Mask")
			(remove_unused_layers no)
			(net "LAN2_P1_N")
			(clearance 0.1016)
			(thermal_gap 0.1016)
		)
		(pad "B4" thru_hole circle
			(at -4.499864 2.999994 270)
			(size 1.016 1.016)
			(drill 0.7112)
			(layers "*.Cu" "*.Mask")
			(remove_unused_layers no)
			(net "GND")
			(clearance 0.1016)
			(thermal_gap 0.1016)
		)
		(pad "B5" thru_hole circle
			(at -2.499868 3.999992 270)
			(size 1.016 1.016)
			(drill 0.7112)
			(layers "*.Cu" "*.Mask")
			(remove_unused_layers no)
			(net "LAN2_P2_P")
			(clearance 0.1016)
			(thermal_gap 0.1016)
		)
		(pad "B6" thru_hole circle
			(at -4.499864 4.99999 270)
			(size 1.016 1.016)
			(drill 0.7112)
			(layers "*.Cu" "*.Mask")
			(remove_unused_layers no)
			(net "LAN2_P2_N")
			(clearance 0.1016)
			(thermal_gap 0.1016)
		)
		(pad "B7" thru_hole circle
			(at -2.499868 5.999988 270)
			(size 1.016 1.016)
			(drill 0.7112)
			(layers "*.Cu" "*.Mask")
			(remove_unused_layers no)
			(net "GND")
			(clearance 0.1016)
			(thermal_gap 0.1016)
		)
		(pad "B8" thru_hole circle
			(at -4.499864 6.999986 270)
			(size 1.016 1.016)
			(drill 0.7112)
			(layers "*.Cu" "*.Mask")
			(remove_unused_layers no)
			(net "GND")
			(clearance 0.1016)
			(thermal_gap 0.1016)
		)
		(pad "B9" thru_hole circle
			(at -2.499868 7.999984 270)
			(size 1.016 1.016)
			(drill 0.7112)
			(layers "*.Cu" "*.Mask")
			(remove_unused_layers no)
			(net "GND")
			(clearance 0.1016)
			(thermal_gap 0.1016)
		)
		(pad "B10" thru_hole circle
			(at -4.499864 8.999982 270)
			(size 1.016 1.016)
			(drill 0.7112)
			(layers "*.Cu" "*.Mask")
			(remove_unused_layers no)
			(net "I2C_PDB_SCL")
			(clearance 0.1016)
			(thermal_gap 0.1016)
		)
		(pad "B11" thru_hole circle
			(at -2.499868 9.99998 270)
			(size 1.016 1.016)
			(drill 0.7112)
			(layers "*.Cu" "*.Mask")
			(remove_unused_layers no)
			(net "I2C_PDB_SDA")
			(clearance 0.1016)
			(thermal_gap 0.1016)
		)
		(pad "B12" thru_hole circle
			(at -4.499864 12.999974 270)
			(size 1.016 1.016)
			(drill 0.7112)
			(layers "*.Cu" "*.Mask")
			(remove_unused_layers no)
			(net "P3V3")
			(clearance 0.1016)
			(thermal_gap 0.1016)
		)
		(pad "B13" thru_hole circle
			(at -2.499868 13.999972 270)
			(size 1.016 1.016)
			(drill 0.7112)
			(layers "*.Cu" "*.Mask")
			(remove_unused_layers no)
			(net "GND3")
			(clearance 0.1016)
			(thermal_gap 0.1016)
		)
		(pad "B14" thru_hole circle
			(at -4.499864 14.99997 270)
			(size 1.016 1.016)
			(drill 0.7112)
			(layers "*.Cu" "*.Mask")
			(remove_unused_layers no)
			(net "Net_442")
			(clearance 0.1016)
			(thermal_gap 0.1016)
		)
		(pad "B15" thru_hole circle
			(at -2.499868 15.999968 270)
			(size 1.016 1.016)
			(drill 0.7112)
			(layers "*.Cu" "*.Mask")
			(remove_unused_layers no)
			(net "Net_441")
			(clearance 0.1016)
			(thermal_gap 0.1016)
		)
		(pad "B16" thru_hole circle
			(at -4.499864 16.999966 270)
			(size 1.016 1.016)
			(drill 0.7112)
			(layers "*.Cu" "*.Mask")
			(remove_unused_layers no)
			(net "GND4")
			(clearance 0.1016)
			(thermal_gap 0.1016)
		)
		(pad "B17" thru_hole circle
			(at -2.499868 17.999964 270)
			(size 1.016 1.016)
			(drill 0.7112)
			(layers "*.Cu" "*.Mask")
			(remove_unused_layers no)
			(net "Net_440")
			(clearance 0.1016)
			(thermal_gap 0.1016)
		)
		(pad "B18" thru_hole circle
			(at -4.499864 18.999962 270)
			(size 1.016 1.016)
			(drill 0.7112)
			(layers "*.Cu" "*.Mask")
			(remove_unused_layers no)
			(net "GND")
			(clearance 0.1016)
			(thermal_gap 0.1016)
		)
		(pad "B19" thru_hole circle
			(at -2.499868 19.99996 270)
			(size 1.016 1.016)
			(drill 0.7112)
			(layers "*.Cu" "*.Mask")
			(remove_unused_layers no)
			(net "Net_3")
			(clearance 0.1016)
			(thermal_gap 0.1016)
		)
		(pad "B20" thru_hole circle
			(at -4.499864 20.999958 270)
			(size 1.016 1.016)
			(drill 0.7112)
			(layers "*.Cu" "*.Mask")
			(remove_unused_layers no)
			(net "Net_8")
			(clearance 0.1016)
			(thermal_gap 0.1016)
		)
		(pad "B21" thru_hole circle
			(at -2.499868 21.999956 270)
			(size 1.016 1.016)
			(drill 0.7112)
			(layers "*.Cu" "*.Mask")
			(remove_unused_layers no)
			(net "GND6")
			(clearance 0.1016)
			(thermal_gap 0.1016)
		)
		(pad "B22" thru_hole circle
			(at -4.499864 22.999954 270)
			(size 1.016 1.016)
			(drill 0.7112)
			(layers "*.Cu" "*.Mask")
			(remove_unused_layers no)
			(net "GND7")
			(clearance 0.1016)
			(thermal_gap 0.1016)
		)
		(pad "B23" thru_hole circle
			(at -2.499868 23.999952 270)
			(size 1.016 1.016)
			(drill 0.7112)
			(layers "*.Cu" "*.Mask")
			(remove_unused_layers no)
			(net "Net_2")
			(clearance 0.1016)
			(thermal_gap 0.1016)
		)
		(pad "B24" thru_hole circle
			(at -4.499864 24.99995 270)
			(size 1.016 1.016)
			(drill 0.7112)
			(layers "*.Cu" "*.Mask")
			(remove_unused_layers no)
			(net "Net_7")
			(clearance 0.1016)
			(thermal_gap 0.1016)
		)
		(pad "B25" thru_hole circle
			(at -2.499868 25.999948 270)
			(size 1.016 1.016)
			(drill 0.7112)
			(layers "*.Cu" "*.Mask")
			(remove_unused_layers no)
			(net "GND8")
			(clearance 0.1016)
			(thermal_gap 0.1016)
		)
		(pad "B26" thru_hole circle
			(at -4.499864 26.999946 270)
			(size 1.016 1.016)
			(drill 0.7112)
			(layers "*.Cu" "*.Mask")
			(remove_unused_layers no)
			(net "GND")
			(clearance 0.1016)
			(thermal_gap 0.1016)
		)
		(pad "B27" thru_hole circle
			(at -2.499868 27.999944 270)
			(size 1.016 1.016)
			(drill 0.7112)
			(layers "*.Cu" "*.Mask")
			(remove_unused_layers no)
			(net "FAN1_TACH")
			(clearance 0.1016)
			(thermal_gap 0.1016)
		)
		(pad "B28" thru_hole circle
			(at -4.499864 28.999942 270)
			(size 1.016 1.016)
			(drill 0.7112)
			(layers "*.Cu" "*.Mask")
			(remove_unused_layers no)
			(net "FAN2_TACH")
			(clearance 0.1016)
			(thermal_gap 0.1016)
		)
		(pad "B29" thru_hole circle
			(at -2.499868 29.99994 270)
			(size 1.016 1.016)
			(drill 0.7112)
			(layers "*.Cu" "*.Mask")
			(remove_unused_layers no)
			(net "FAN3_TACH")
			(clearance 0.1016)
			(thermal_gap 0.1016)
		)
		(pad "B30" thru_hole circle
			(at -4.499864 30.999938 270)
			(size 1.016 1.016)
			(drill 0.7112)
			(layers "*.Cu" "*.Mask")
			(remove_unused_layers no)
			(net "GND")
			(clearance 0.1016)
			(thermal_gap 0.1016)
		)
		(pad "B31" thru_hole circle
			(at -2.499868 31.999936 270)
			(size 1.016 1.016)
			(drill 0.7112)
			(layers "*.Cu" "*.Mask")
			(remove_unused_layers no)
			(net "T12_BLAD1_EN")
			(clearance 0.1016)
			(thermal_gap 0.1016)
		)
		(pad "B32" thru_hole circle
			(at -4.499864 32.999934 270)
			(size 1.016 1.016)
			(drill 0.7112)
			(layers "*.Cu" "*.Mask")
			(remove_unused_layers no)
			(net "TP_T12_BLAD2_EN")
			(clearance 0.1016)
			(thermal_gap 0.1016)
		)
		(pad "B33" thru_hole circle
			(at -2.499868 33.999932 270)
			(size 1.016 1.016)
			(drill 0.7112)
			(layers "*.Cu" "*.Mask")
			(remove_unused_layers no)
			(net "T12_BLAD3_EN")
			(clearance 0.1016)
			(thermal_gap 0.1016)
		)
		(pad "B34" thru_hole circle
			(at -4.499864 34.99993 270)
			(size 1.016 1.016)
			(drill 0.7112)
			(layers "*.Cu" "*.Mask")
			(remove_unused_layers no)
			(net "TP_T12_BLAD4_EN")
			(clearance 0.1016)
			(thermal_gap 0.1016)
		)
		(pad "B35" thru_hole circle
			(at -2.499868 35.999928 270)
			(size 1.016 1.016)
			(drill 0.7112)
			(layers "*.Cu" "*.Mask")
			(remove_unused_layers no)
			(net "GND")
			(clearance 0.1016)
			(thermal_gap 0.1016)
		)
		(pad "B36" thru_hole circle
			(at -4.499864 36.999926 270)
			(size 1.016 1.016)
			(drill 0.7112)
			(layers "*.Cu" "*.Mask")
			(remove_unused_layers no)
			(net "T12_BLAD1_RXD")
			(clearance 0.1016)
			(thermal_gap 0.1016)
		)
		(pad "B37" thru_hole circle
			(at -2.499868 37.999924 270)
			(size 1.016 1.016)
			(drill 0.7112)
			(layers "*.Cu" "*.Mask")
			(remove_unused_layers no)
			(net "T12_BLAD1_TXD")
			(clearance 0.1016)
			(thermal_gap 0.1016)
		)
		(pad "B38" thru_hole circle
			(at -4.499864 38.999922 270)
			(size 1.016 1.016)
			(drill 0.7112)
			(layers "*.Cu" "*.Mask")
			(remove_unused_layers no)
			(net "T12_BLAD2_RXD")
			(clearance 0.1016)
			(thermal_gap 0.1016)
		)
		(pad "B39" thru_hole circle
			(at -2.499868 39.99992 270)
			(size 1.016 1.016)
			(drill 0.7112)
			(layers "*.Cu" "*.Mask")
			(remove_unused_layers no)
			(net "T12_BLAD2_TXD")
			(clearance 0.1016)
			(thermal_gap 0.1016)
		)
		(pad "B40" thru_hole circle
			(at -4.499864 40.999918 270)
			(size 1.016 1.016)
			(drill 0.7112)
			(layers "*.Cu" "*.Mask")
			(remove_unused_layers no)
			(net "GND")
			(clearance 0.1016)
			(thermal_gap 0.1016)
		)
		(pad "B41" thru_hole circle
			(at -2.499868 41.999916 270)
			(size 1.016 1.016)
			(drill 0.7112)
			(layers "*.Cu" "*.Mask")
			(remove_unused_layers no)
			(net "T12_BLAD3_RXD")
			(clearance 0.1016)
			(thermal_gap 0.1016)
		)
		(pad "B42" thru_hole circle
			(at -4.499864 42.999914 270)
			(size 1.016 1.016)
			(drill 0.7112)
			(layers "*.Cu" "*.Mask")
			(remove_unused_layers no)
			(net "T12_BLAD3_TXD")
			(clearance 0.1016)
			(thermal_gap 0.1016)
		)
		(pad "B43" thru_hole circle
			(at -2.499868 43.999912 270)
			(size 1.016 1.016)
			(drill 0.7112)
			(layers "*.Cu" "*.Mask")
			(remove_unused_layers no)
			(net "T12_BLAD4_RXD")
			(clearance 0.1016)
			(thermal_gap 0.1016)
		)
		(pad "B44" thru_hole circle
			(at -4.499864 44.99991 270)
			(size 1.016 1.016)
			(drill 0.7112)
			(layers "*.Cu" "*.Mask")
			(remove_unused_layers no)
			(net "T12_BLAD4_TXD")
			(clearance 0.1016)
			(thermal_gap 0.1016)
		)
		(pad "B45" thru_hole circle
			(at -2.499868 45.999908 270)
			(size 1.016 1.016)
			(drill 0.7112)
			(layers "*.Cu" "*.Mask")
			(remove_unused_layers no)
			(net "GND")
			(clearance 0.1016)
			(thermal_gap 0.1016)
		)
		(pad "B46" thru_hole circle
			(at -4.499864 46.999906 270)
			(size 1.016 1.016)
			(drill 0.7112)
			(layers "*.Cu" "*.Mask")
			(remove_unused_layers no)
			(net "T10_BLAD1_EN")
			(clearance 0.1016)
			(thermal_gap 0.1016)
		)
		(pad "B47" thru_hole circle
			(at -2.499868 47.999904 270)
			(size 1.016 1.016)
			(drill 0.7112)
			(layers "*.Cu" "*.Mask")
			(remove_unused_layers no)
			(net "TP_T10_BLAD2_EN")
			(clearance 0.1016)
			(thermal_gap 0.1016)
		)
		(pad "B48" thru_hole circle
			(at -4.499864 48.999902 270)
			(size 1.016 1.016)
			(drill 0.7112)
			(layers "*.Cu" "*.Mask")
			(remove_unused_layers no)
			(net "T10_BLAD3_EN")
			(clearance 0.1016)
			(thermal_gap 0.1016)
		)
		(pad "B49" thru_hole circle
			(at -2.499868 49.9999 270)
			(size 1.016 1.016)
			(drill 0.7112)
			(layers "*.Cu" "*.Mask")
			(remove_unused_layers no)
			(net "TP_T10_BLAD4_EN")
			(clearance 0.1016)
			(thermal_gap 0.1016)
		)
		(pad "B50" thru_hole circle
			(at -4.499864 50.999898 270)
			(size 1.016 1.016)
			(drill 0.7112)
			(layers "*.Cu" "*.Mask")
			(remove_unused_layers no)
			(net "GND")
			(clearance 0.1016)
			(thermal_gap 0.1016)
		)
		(pad "B51" thru_hole circle
			(at -2.499868 51.999896 270)
			(size 1.016 1.016)
			(drill 0.7112)
			(layers "*.Cu" "*.Mask")
			(remove_unused_layers no)
			(net "T10_BLAD1_RXD")
			(clearance 0.1016)
			(thermal_gap 0.1016)
		)
		(pad "B52" thru_hole circle
			(at -4.499864 52.999894 270)
			(size 1.016 1.016)
			(drill 0.7112)
			(layers "*.Cu" "*.Mask")
			(remove_unused_layers no)
			(net "T10_BLAD1_TXD")
			(clearance 0.1016)
			(thermal_gap 0.1016)
		)
		(pad "B53" thru_hole circle
			(at -2.499868 53.999892 270)
			(size 1.016 1.016)
			(drill 0.7112)
			(layers "*.Cu" "*.Mask")
			(remove_unused_layers no)
			(net "T10_BLAD2_RXD")
			(clearance 0.1016)
			(thermal_gap 0.1016)
		)
		(pad "B54" thru_hole circle
			(at -4.499864 54.99989 270)
			(size 1.016 1.016)
			(drill 0.7112)
			(layers "*.Cu" "*.Mask")
			(remove_unused_layers no)
			(net "T10_BLAD2_TXD")
			(clearance 0.1016)
			(thermal_gap 0.1016)
		)
		(pad "B55" thru_hole circle
			(at -2.499868 55.999888 270)
			(size 1.016 1.016)
			(drill 0.7112)
			(layers "*.Cu" "*.Mask")
			(remove_unused_layers no)
			(net "GND")
			(clearance 0.1016)
			(thermal_gap 0.1016)
		)
		(pad "B56" thru_hole circle
			(at -4.499864 56.999886 270)
			(size 1.016 1.016)
			(drill 0.7112)
			(layers "*.Cu" "*.Mask")
			(remove_unused_layers no)
			(net "T10_BLAD3_RXD")
			(clearance 0.1016)
			(thermal_gap 0.1016)
		)
		(pad "B57" thru_hole circle
			(at -2.499868 57.999884 270)
			(size 1.016 1.016)
			(drill 0.7112)
			(layers "*.Cu" "*.Mask")
			(remove_unused_layers no)
			(net "T10_BLAD3_TXD")
			(clearance 0.1016)
			(thermal_gap 0.1016)
		)
		(pad "B58" thru_hole circle
			(at -4.499864 59.000136 270)
			(size 1.016 1.016)
			(drill 0.7112)
			(layers "*.Cu" "*.Mask")
			(remove_unused_layers no)
			(net "T10_BLAD4_RXD")
			(clearance 0.1016)
			(thermal_gap 0.1016)
		)
		(pad "B59" thru_hole circle
			(at -2.499868 59.99988 270)
			(size 1.016 1.016)
			(drill 0.7112)
			(layers "*.Cu" "*.Mask")
			(remove_unused_layers no)
			(net "T10_BLAD4_TXD")
			(clearance 0.1016)
			(thermal_gap 0.1016)
		)
		(pad "B60" thru_hole circle
			(at -4.499864 61.000132 270)
			(size 1.016 1.016)
			(drill 0.7112)
			(layers "*.Cu" "*.Mask")
			(remove_unused_layers no)
			(net "GND")
			(clearance 0.1016)
			(thermal_gap 0.1016)
		)
		(pad "B61" thru_hole circle
			(at -2.499868 61.999876 270)
			(size 1.016 1.016)
			(drill 0.7112)
			(layers "*.Cu" "*.Mask")
			(remove_unused_layers no)
			(net "T8_BLAD1_EN")
			(clearance 0.1016)
			(thermal_gap 0.1016)
		)
		(pad "B62" thru_hole circle
			(at -4.499864 63.000128 270)
			(size 1.016 1.016)
			(drill 0.7112)
			(layers "*.Cu" "*.Mask")
			(remove_unused_layers no)
			(net "TP_T8_BLAD2_EN")
			(clearance 0.1016)
			(thermal_gap 0.1016)
		)
		(pad "B63" thru_hole circle
			(at -2.499868 63.999872 270)
			(size 1.016 1.016)
			(drill 0.7112)
			(layers "*.Cu" "*.Mask")
			(remove_unused_layers no)
			(net "T8_BLAD3_EN")
			(clearance 0.1016)
			(thermal_gap 0.1016)
		)
		(pad "B64" thru_hole circle
			(at -4.499864 65.000124 270)
			(size 1.016 1.016)
			(drill 0.7112)
			(layers "*.Cu" "*.Mask")
			(remove_unused_layers no)
			(net "TP_T8_BLAD4_EN")
			(clearance 0.1016)
			(thermal_gap 0.1016)
		)
		(pad "B65" thru_hole circle
			(at -2.499868 65.999868 270)
			(size 1.016 1.016)
			(drill 0.7112)
			(layers "*.Cu" "*.Mask")
			(remove_unused_layers no)
			(net "GND")
			(clearance 0.1016)
			(thermal_gap 0.1016)
		)
		(pad "B66" thru_hole circle
			(at -4.499864 67.00012 270)
			(size 1.016 1.016)
			(drill 0.7112)
			(layers "*.Cu" "*.Mask")
			(remove_unused_layers no)
			(net "T8_BLAD1_RXD")
			(clearance 0.1016)
			(thermal_gap 0.1016)
		)
		(pad "B67" thru_hole circle
			(at -2.499868 67.999864 270)
			(size 1.016 1.016)
			(drill 0.7112)
			(layers "*.Cu" "*.Mask")
			(remove_unused_layers no)
			(net "T8_BLAD1_TXD")
			(clearance 0.1016)
			(thermal_gap 0.1016)
		)
		(pad "B68" thru_hole circle
			(at -4.499864 69.000116 270)
			(size 1.016 1.016)
			(drill 0.7112)
			(layers "*.Cu" "*.Mask")
			(remove_unused_layers no)
			(net "T8_BLAD2_RXD")
			(clearance 0.1016)
			(thermal_gap 0.1016)
		)
		(pad "B69" thru_hole circle
			(at -2.499868 70.000114 270)
			(size 1.016 1.016)
			(drill 0.7112)
			(layers "*.Cu" "*.Mask")
			(remove_unused_layers no)
			(net "T8_BLAD2_TXD")
			(clearance 0.1016)
			(thermal_gap 0.1016)
		)
		(pad "B70" thru_hole circle
			(at -4.499864 71.000112 270)
			(size 1.016 1.016)
			(drill 0.7112)
			(layers "*.Cu" "*.Mask")
			(remove_unused_layers no)
			(net "GND")
			(clearance 0.1016)
			(thermal_gap 0.1016)
		)
		(pad "B71" thru_hole circle
			(at -2.499868 72.00011 270)
			(size 1.016 1.016)
			(drill 0.7112)
			(layers "*.Cu" "*.Mask")
			(remove_unused_layers no)
			(net "T8_BLAD3_RXD")
			(clearance 0.1016)
			(thermal_gap 0.1016)
		)
		(pad "B72" thru_hole circle
			(at -4.499864 73.000108 270)
			(size 1.016 1.016)
			(drill 0.7112)
			(layers "*.Cu" "*.Mask")
			(remove_unused_layers no)
			(net "T8_BLAD3_TXD")
			(clearance 0.1016)
			(thermal_gap 0.1016)
		)
		(pad "B73" thru_hole circle
			(at -2.499868 74.000106 270)
			(size 1.016 1.016)
			(drill 0.7112)
			(layers "*.Cu" "*.Mask")
			(remove_unused_layers no)
			(net "T8_BLAD4_RXD")
			(clearance 0.1016)
			(thermal_gap 0.1016)
		)
		(pad "B74" thru_hole circle
			(at -4.499864 75.000104 270)
			(size 1.016 1.016)
			(drill 0.7112)
			(layers "*.Cu" "*.Mask")
			(remove_unused_layers no)
			(net "T8_BLAD4_TXD")
			(clearance 0.1016)
			(thermal_gap 0.1016)
		)
		(pad "B75" thru_hole circle
			(at -2.499868 76.000102 270)
			(size 1.016 1.016)
			(drill 0.7112)
			(layers "*.Cu" "*.Mask")
			(remove_unused_layers no)
			(net "GND")
			(clearance 0.1016)
			(thermal_gap 0.1016)
		)
		(pad "B76" thru_hole circle
			(at -4.499864 77.0001 270)
			(size 1.016 1.016)
			(drill 0.7112)
			(layers "*.Cu" "*.Mask")
			(remove_unused_layers no)
			(net "T6_BLAD1_EN")
			(clearance 0.1016)
			(thermal_gap 0.1016)
		)
		(pad "B77" thru_hole circle
			(at -2.499868 78.000098 270)
			(size 1.016 1.016)
			(drill 0.7112)
			(layers "*.Cu" "*.Mask")
			(remove_unused_layers no)
			(net "TP_T6_BLAD2_EN")
			(clearance 0.1016)
			(thermal_gap 0.1016)
		)
		(pad "B78" thru_hole circle
			(at -4.499864 79.000096 270)
			(size 1.016 1.016)
			(drill 0.7112)
			(layers "*.Cu" "*.Mask")
			(remove_unused_layers no)
			(net "T6_BLAD3_EN")
			(clearance 0.1016)
			(thermal_gap 0.1016)
		)
		(pad "B79" thru_hole circle
			(at -2.499868 80.000094 270)
			(size 1.016 1.016)
			(drill 0.7112)
			(layers "*.Cu" "*.Mask")
			(remove_unused_layers no)
			(net "TP_T6_BLAD4_EN")
			(clearance 0.1016)
			(thermal_gap 0.1016)
		)
		(pad "B80" thru_hole circle
			(at -4.499864 81.000092 270)
			(size 1.016 1.016)
			(drill 0.7112)
			(layers "*.Cu" "*.Mask")
			(remove_unused_layers no)
			(net "GND")
			(clearance 0.1016)
			(thermal_gap 0.1016)
		)
		(pad "B81" thru_hole circle
			(at -2.499868 82.00009 270)
			(size 1.016 1.016)
			(drill 0.7112)
			(layers "*.Cu" "*.Mask")
			(remove_unused_layers no)
			(net "T6_BLAD1_RXD")
			(clearance 0.1016)
			(thermal_gap 0.1016)
		)
		(pad "B82" thru_hole circle
			(at -4.499864 83.000088 270)
			(size 1.016 1.016)
			(drill 0.7112)
			(layers "*.Cu" "*.Mask")
			(remove_unused_layers no)
			(net "T6_BLAD1_TXD")
			(clearance 0.1016)
			(thermal_gap 0.1016)
		)
		(zone
			(layers "F.Cu" "B.Cu" "In1.Cu" "In2.Cu" "In3.Cu" "In4.Cu" "In5.Cu" "In6.Cu")
			(hatch none 0.5)
			(connect_pads
				(clearance 0)
			)
			(min_thickness 0.25)
			(keepout
				(tracks allowed)
				(vias not_allowed)
				(pads allowed)
				(copperpour not_allowed)
				(footprints allowed)
			)
			(placement
				(enabled no)
				(sheetname "")
			)
			(fill
				(thermal_gap 0.5)
				(thermal_bridge_width 0.5)
				(island_removal_mode 0)
			)
			(polygon
				(pts
					(xy 1.369822 -269.103856) (xy 3.732022 -269.103856) (xy 3.732022 -266.386056) (xy 6.678422 -266.386056)
					(xy 6.678422 -269.103856) (xy 9.015222 -269.103856) (xy 9.015222 -353.254056) (xy 1.369822 -353.254056)
				)
			)
		)
		(zone
			(layers "F.Cu" "B.Cu" "In1.Cu" "In2.Cu" "In3.Cu" "In4.Cu" "In5.Cu" "In6.Cu")
			(hatch none 0.5)
			(connect_pads
				(clearance 0)
			)
			(min_thickness 0.25)
			(keepout
				(tracks not_allowed)
				(vias allowed)
				(pads allowed)
				(copperpour not_allowed)
				(footprints allowed)
			)
			(placement
				(enabled no)
				(sheetname "")
			)
			(fill
				(thermal_gap 0.5)
				(thermal_bridge_width 0.5)
				(island_removal_mode 0)
			)
			(polygon
				(pts
					(arc
						(start 3.583686 -341.019892)
						(mid 3.675158 -341.555649)
						(end 3.939032 -342.030812)
					)
					(xy 4.567428 -342.030812)
					(arc
						(start 4.567428 -342.507062)
						(mid 5.201285 -342.635861)
						(end 5.834888 -342.505792)
					)
					(xy 5.834888 -342.038686)
					(arc
						(start 6.45414 -342.038686)
						(mid 5.740161 -339.496883)
						(end 3.583686 -341.019892)
					)
				)
			)
		)
		(zone
			(layers "F.Cu" "B.Cu" "In1.Cu" "In2.Cu" "In3.Cu" "In4.Cu" "In5.Cu" "In6.Cu")
			(hatch none 0.5)
			(connect_pads
				(clearance 0)
			)
			(min_thickness 0.25)
			(keepout
				(tracks not_allowed)
				(vias allowed)
				(pads allowed)
				(copperpour not_allowed)
				(footprints allowed)
			)
			(placement
				(enabled no)
				(sheetname "")
			)
			(fill
				(thermal_gap 0.5)
				(thermal_bridge_width 0.5)
				(island_removal_mode 0)
			)
			(polygon
				(pts
					(arc
						(start 6.813804 -267.869924)
						(mid 3.585972 -267.869924)
						(end 6.813804 -267.869924)
					)
				)
			)
		)
	)
	(footprint ""
		(layer "F.Cu")
		(at 26.102056 -271.14881)
		(property "Reference" "R77"
			(at -4.037838 -0.005334 0)
			(unlocked yes)
			(layer "F.SilkS")
			(effects
				(font
					(size 0.7874 0.5842)
					(thickness 0.1524)
				)
				(justify left)
			)
		)
		(property "Value" ""
			(at 0 0 0)
			(layer "F.Fab")
			(effects
				(font
					(size 1.27 1.27)
				)
			)
		)
		(duplicate_pad_numbers_are_jumpers no)
		(fp_line
			(start -0.7874 -0.4064)
			(end 0.7874 -0.4064)
			(stroke
				(width 0.1524)
				(type default)
			)
			(layer "F.SilkS")
		)
		(fp_line
			(start -0.7874 0.4064)
			(end -0.7874 -0.4064)
			(stroke
				(width 0.1524)
				(type default)
			)
			(layer "F.SilkS")
		)
		(fp_line
			(start 0.7874 -0.4064)
			(end 0.7874 0.4064)
			(stroke
				(width 0.1524)
				(type default)
			)
			(layer "F.SilkS")
		)
		(fp_line
			(start 0.7874 0.4064)
			(end -0.7874 0.4064)
			(stroke
				(width 0.1524)
				(type default)
			)
			(layer "F.SilkS")
		)
		(fp_poly
			(pts
				(xy -0.508 0.2794) (xy -0.508 0.2286) (xy -0.635 0.2286) (xy -0.635 -0.254) (xy -0.5334 -0.254)
				(xy -0.5334 -0.2794) (xy 0.5334 -0.2794) (xy 0.5334 -0.254) (xy 0.635 -0.254) (xy 0.635 0.254) (xy 0.5334 0.254)
				(xy 0.5334 0.2794)
			)
			(stroke
				(width 0)
				(type default)
			)
			(fill no)
			(layer "F.CrtYd")
		)
		(pad "1" smd rect
			(at 0.40005 0)
			(size 0.4572 0.508)
			(layers "F.Cu" "F.Mask" "F.Paste")
			(net "PSU4_RESET")
		)
		(pad "2" smd rect
			(at -0.40005 0)
			(size 0.4572 0.508)
			(layers "F.Cu" "F.Mask" "F.Paste")
			(net "GND")
		)
	)
	(footprint ""
		(layer "F.Cu")
		(at 68.639436 -374.919748 -90)
		(property "Reference" "C57"
			(at -3.246628 0.156972 90)
			(unlocked yes)
			(layer "F.SilkS")
			(effects
				(font
					(size 0.7874 0.5842)
					(thickness 0.1524)
				)
			)
		)
		(property "Value" ""
			(at 0 0 270)
			(layer "F.Fab")
			(effects
				(font
					(size 1.27 1.27)
				)
			)
		)
		(duplicate_pad_numbers_are_jumpers no)
		(fp_line
			(start -1.2954 0.5842)
			(end -1.2954 -0.5842)
			(stroke
				(width 0.1524)
				(type default)
			)
			(layer "F.SilkS")
		)
		(fp_line
			(start 1.2954 0.5842)
			(end -1.2954 0.5842)
			(stroke
				(width 0.1524)
				(type default)
			)
			(layer "F.SilkS")
		)
		(fp_line
			(start -1.2954 -0.5842)
			(end 1.2954 -0.5842)
			(stroke
				(width 0.1524)
				(type default)
			)
			(layer "F.SilkS")
		)
		(fp_line
			(start 0 -0.5842)
			(end 0 0.5842)
			(stroke
				(width 0.1524)
				(type default)
			)
			(layer "F.SilkS")
		)
		(fp_line
			(start 1.2954 -0.5842)
			(end 1.2954 0.5842)
			(stroke
				(width 0.1524)
				(type default)
			)
			(layer "F.SilkS")
		)
		(fp_poly
			(pts
				(xy 0.8636 -0.4572) (xy 0.8636 -0.3556) (xy 1.143 -0.3556) (xy 1.143 0.3556) (xy 0.8636 0.3556)
				(xy 0.8636 0.4572) (xy -0.8636 0.4572) (xy -0.8636 0.3556) (xy -1.143 0.3556) (xy -1.143 -0.3556)
				(xy -0.8636 -0.3556) (xy -0.8636 -0.4572)
			)
			(stroke
				(width 0)
				(type default)
			)
			(fill no)
			(layer "F.CrtYd")
		)
		(fp_line
			(start -0.884936 0.504952)
			(end -0.884936 -0.504952)
			(stroke
				(width 0.1)
				(type default)
			)
			(layer "F.Fab")
		)
		(fp_line
			(start 0.884936 0.504952)
			(end -0.884936 0.504952)
			(stroke
				(width 0.1)
				(type default)
			)
			(layer "F.Fab")
		)
		(fp_line
			(start -0.884936 -0.504952)
			(end 0.884936 -0.504952)
			(stroke
				(width 0.1)
				(type default)
			)
			(layer "F.Fab")
		)
		(fp_line
			(start 0.884936 -0.504952)
			(end 0.884936 0.504952)
			(stroke
				(width 0.1)
				(type default)
			)
			(layer "F.Fab")
		)
		(pad "1" smd rect
			(at 0.7366 0)
			(size 0.7112 0.8128)
			(layers "F.Cu" "F.Mask" "F.Paste")
			(net "P12V")
		)
		(pad "2" smd rect
			(at -0.7366 0)
			(size 0.7112 0.8128)
			(layers "F.Cu" "F.Mask" "F.Paste")
			(net "GND")
		)
	)
	(footprint ""
		(layer "F.Cu")
		(at 68.310252 -127.633476 90)
		(property "Reference" "C27"
			(at 1.193546 -0.121412 90)
			(unlocked yes)
			(layer "F.SilkS")
			(effects
				(font
					(size 0.7874 0.5842)
					(thickness 0.1524)
				)
				(justify left)
			)
		)
		(property "Value" ""
			(at 0 0 90)
			(layer "F.Fab")
			(effects
				(font
					(size 1.27 1.27)
				)
			)
		)
		(duplicate_pad_numbers_are_jumpers no)
		(fp_line
			(start 0.7874 -0.4064)
			(end 0.7874 0.4064)
			(stroke
				(width 0.1524)
				(type default)
			)
			(layer "F.SilkS")
		)
		(fp_line
			(start -0.7874 -0.4064)
			(end 0.7874 -0.4064)
			(stroke
				(width 0.1524)
				(type default)
			)
			(layer "F.SilkS")
		)
		(fp_line
			(start 0 0.381)
			(end 0 -0.381)
			(stroke
				(width 0.1524)
				(type default)
			)
			(layer "F.SilkS")
		)
		(fp_line
			(start 0.7874 0.4064)
			(end -0.7874 0.4064)
			(stroke
				(width 0.1524)
				(type default)
			)
			(layer "F.SilkS")
		)
		(fp_line
			(start -0.7874 0.4064)
			(end -0.7874 -0.4064)
			(stroke
				(width 0.1524)
				(type default)
			)
			(layer "F.SilkS")
		)
		(fp_poly
			(pts
				(xy -0.5334 0.254) (xy -0.635 0.254) (xy -0.635 0.2286) (xy -0.635 -0.254) (xy -0.5334 -0.254) (xy -0.5334 -0.2794)
				(xy 0.5334 -0.2794) (xy 0.5334 -0.254) (xy 0.635 -0.254) (xy 0.635 0.254) (xy 0.5334 0.254) (xy 0.5334 0.2794)
				(xy -0.508 0.2794) (xy -0.5334 0.2794)
			)
			(stroke
				(width 0)
				(type default)
			)
			(fill no)
			(layer "F.CrtYd")
		)
		(pad "1" smd rect
			(at 0.40005 0 90)
			(size 0.4572 0.508)
			(layers "F.Cu" "F.Mask" "F.Paste")
			(net "P12V")
		)
		(pad "2" smd rect
			(at -0.40005 0 90)
			(size 0.4572 0.508)
			(layers "F.Cu" "F.Mask" "F.Paste")
			(net "GND")
		)
	)
	(footprint ""
		(layer "F.Cu")
		(at 73.927716 -393.452604 90)
		(property "Reference" "C70"
			(at 1.084834 -0.053848 90)
			(unlocked yes)
			(layer "F.SilkS")
			(effects
				(font
					(size 0.7874 0.5842)
					(thickness 0.1524)
				)
				(justify left)
			)
		)
		(property "Value" ""
			(at 0 0 90)
			(layer "F.Fab")
			(effects
				(font
					(size 1.27 1.27)
				)
			)
		)
		(duplicate_pad_numbers_are_jumpers no)
		(fp_line
			(start 0.7874 -0.4064)
			(end 0.7874 0.4064)
			(stroke
				(width 0.1524)
				(type default)
			)
			(layer "F.SilkS")
		)
		(fp_line
			(start -0.7874 -0.4064)
			(end 0.7874 -0.4064)
			(stroke
				(width 0.1524)
				(type default)
			)
			(layer "F.SilkS")
		)
		(fp_line
			(start 0 0.381)
			(end 0 -0.381)
			(stroke
				(width 0.1524)
				(type default)
			)
			(layer "F.SilkS")
		)
		(fp_line
			(start 0.7874 0.4064)
			(end -0.7874 0.4064)
			(stroke
				(width 0.1524)
				(type default)
			)
			(layer "F.SilkS")
		)
		(fp_line
			(start -0.7874 0.4064)
			(end -0.7874 -0.4064)
			(stroke
				(width 0.1524)
				(type default)
			)
			(layer "F.SilkS")
		)
		(fp_poly
			(pts
				(xy -0.5334 0.254) (xy -0.635 0.254) (xy -0.635 0.2286) (xy -0.635 -0.254) (xy -0.5334 -0.254) (xy -0.5334 -0.2794)
				(xy 0.5334 -0.2794) (xy 0.5334 -0.254) (xy 0.635 -0.254) (xy 0.635 0.254) (xy 0.5334 0.254) (xy 0.5334 0.2794)
				(xy -0.508 0.2794) (xy -0.5334 0.2794)
			)
			(stroke
				(width 0)
				(type default)
			)
			(fill no)
			(layer "F.CrtYd")
		)
		(pad "1" smd rect
			(at 0.40005 0 90)
			(size 0.4572 0.508)
			(layers "F.Cu" "F.Mask" "F.Paste")
			(net "P12V")
		)
		(pad "2" smd rect
			(at -0.40005 0 90)
			(size 0.4572 0.508)
			(layers "F.Cu" "F.Mask" "F.Paste")
			(net "GND")
		)
	)
	(footprint ""
		(layer "F.Cu")
		(at 25.931622 -99.36988)
		(property "Reference" "R46"
			(at -4.080256 -0.075692 0)
			(unlocked yes)
			(layer "F.SilkS")
			(effects
				(font
					(size 0.7874 0.5842)
					(thickness 0.1524)
				)
				(justify left)
			)
		)
		(property "Value" ""
			(at 0 0 0)
			(layer "F.Fab")
			(effects
				(font
					(size 1.27 1.27)
				)
			)
		)
		(duplicate_pad_numbers_are_jumpers no)
		(fp_line
			(start -0.7874 -0.4064)
			(end 0.7874 -0.4064)
			(stroke
				(width 0.1524)
				(type default)
			)
			(layer "F.SilkS")
		)
		(fp_line
			(start -0.7874 0.4064)
			(end -0.7874 -0.4064)
			(stroke
				(width 0.1524)
				(type default)
			)
			(layer "F.SilkS")
		)
		(fp_line
			(start 0.7874 -0.4064)
			(end 0.7874 0.4064)
			(stroke
				(width 0.1524)
				(type default)
			)
			(layer "F.SilkS")
		)
		(fp_line
			(start 0.7874 0.4064)
			(end -0.7874 0.4064)
			(stroke
				(width 0.1524)
				(type default)
			)
			(layer "F.SilkS")
		)
		(fp_poly
			(pts
				(xy -0.508 0.2794) (xy -0.508 0.2286) (xy -0.635 0.2286) (xy -0.635 -0.254) (xy -0.5334 -0.254)
				(xy -0.5334 -0.2794) (xy 0.5334 -0.2794) (xy 0.5334 -0.254) (xy 0.635 -0.254) (xy 0.635 0.254) (xy 0.5334 0.254)
				(xy 0.5334 0.2794)
			)
			(stroke
				(width 0)
				(type default)
			)
			(fill no)
			(layer "F.CrtYd")
		)
		(pad "1" smd rect
			(at 0.40005 0)
			(size 0.4572 0.508)
			(layers "F.Cu" "F.Mask" "F.Paste")
			(net "PSU2_PS_KILL")
		)
		(pad "2" smd rect
			(at -0.40005 0)
			(size 0.4572 0.508)
			(layers "F.Cu" "F.Mask" "F.Paste")
			(net "GND")
		)
	)
	(footprint ""
		(layer "F.Cu")
		(at 46.408086 -239.669066 180)
		(property "Reference" "R89"
			(at 4.341114 0.123698 0)
			(unlocked yes)
			(layer "F.SilkS")
			(effects
				(font
					(size 0.7874 0.5842)
					(thickness 0.1524)
				)
				(justify left)
			)
		)
		(property "Value" ""
			(at 0 0 180)
			(layer "F.Fab")
			(effects
				(font
					(size 1.27 1.27)
				)
			)
		)
		(duplicate_pad_numbers_are_jumpers no)
		(fp_line
			(start 0.7874 0.4064)
			(end -0.7874 0.4064)
			(stroke
				(width 0.1524)
				(type default)
			)
			(layer "F.SilkS")
		)
		(fp_line
			(start 0.7874 -0.4064)
			(end 0.7874 0.4064)
			(stroke
				(width 0.1524)
				(type default)
			)
			(layer "F.SilkS")
		)
		(fp_line
			(start -0.7874 0.4064)
			(end -0.7874 -0.4064)
			(stroke
				(width 0.1524)
				(type default)
			)
			(layer "F.SilkS")
		)
		(fp_line
			(start -0.7874 -0.4064)
			(end 0.7874 -0.4064)
			(stroke
				(width 0.1524)
				(type default)
			)
			(layer "F.SilkS")
		)
		(fp_poly
			(pts
				(xy -0.508 0.2794) (xy -0.508 0.2286) (xy -0.635 0.2286) (xy -0.635 -0.254) (xy -0.5334 -0.254)
				(xy -0.5334 -0.2794) (xy 0.5334 -0.2794) (xy 0.5334 -0.254) (xy 0.635 -0.254) (xy 0.635 0.254) (xy 0.5334 0.254)
				(xy 0.5334 0.2794)
			)
			(stroke
				(width 0)
				(type default)
			)
			(fill no)
			(layer "F.CrtYd")
		)
		(pad "1" smd rect
			(at 0.40005 0 180)
			(size 0.4572 0.508)
			(layers "F.Cu" "F.Mask" "F.Paste")
			(net "PSU1_REMOTE_R_N")
		)
		(pad "2" smd rect
			(at -0.40005 0 180)
			(size 0.4572 0.508)
			(layers "F.Cu" "F.Mask" "F.Paste")
			(net "GND")
		)
	)
	(footprint ""
		(layer "F.Cu")
		(at 2.832862 -415.00044 -90)
		(property "Reference" "R151"
			(at -1.48717 0.13208 90)
			(unlocked yes)
			(layer "F.SilkS")
			(effects
				(font
					(size 0.7874 0.5842)
					(thickness 0.1524)
				)
				(justify left)
			)
		)
		(property "Value" ""
			(at 0 0 270)
			(layer "F.Fab")
			(effects
				(font
					(size 1.27 1.27)
				)
			)
		)
		(duplicate_pad_numbers_are_jumpers no)
		(fp_line
			(start -0.7874 0.4064)
			(end -0.7874 -0.4064)
			(stroke
				(width 0.1524)
				(type default)
			)
			(layer "F.SilkS")
		)
		(fp_line
			(start 0.7874 0.4064)
			(end -0.7874 0.4064)
			(stroke
				(width 0.1524)
				(type default)
			)
			(layer "F.SilkS")
		)
		(fp_line
			(start -0.7874 -0.4064)
			(end 0.7874 -0.4064)
			(stroke
				(width 0.1524)
				(type default)
			)
			(layer "F.SilkS")
		)
		(fp_line
			(start 0.7874 -0.4064)
			(end 0.7874 0.4064)
			(stroke
				(width 0.1524)
				(type default)
			)
			(layer "F.SilkS")
		)
		(fp_poly
			(pts
				(xy -0.508 0.2794) (xy -0.508 0.2286) (xy -0.635 0.2286) (xy -0.635 -0.254) (xy -0.5334 -0.254)
				(xy -0.5334 -0.2794) (xy 0.5334 -0.2794) (xy 0.5334 -0.254) (xy 0.635 -0.254) (xy 0.635 0.254) (xy 0.5334 0.254)
				(xy 0.5334 0.2794)
			)
			(stroke
				(width 0)
				(type default)
			)
			(fill no)
			(layer "F.CrtYd")
		)
		(pad "1" smd rect
			(at 0.40005 0 270)
			(size 0.4572 0.508)
			(layers "F.Cu" "F.Mask" "F.Paste")
			(net "N42132545")
		)
		(pad "2" smd rect
			(at -0.40005 0 270)
			(size 0.4572 0.508)
			(layers "F.Cu" "F.Mask" "F.Paste")
			(net "GND")
		)
	)
	(footprint ""
		(layer "F.Cu")
		(at 26.226008 -450.980556)
		(property "Reference" "R82"
			(at -3.522472 -0.815594 0)
			(unlocked yes)
			(layer "F.SilkS")
			(effects
				(font
					(size 0.7874 0.5842)
					(thickness 0.1524)
				)
				(justify left)
			)
		)
		(property "Value" ""
			(at 0 0 0)
			(layer "F.Fab")
			(effects
				(font
					(size 1.27 1.27)
				)
			)
		)
		(duplicate_pad_numbers_are_jumpers no)
		(fp_line
			(start -0.7874 -0.4064)
			(end 0.7874 -0.4064)
			(stroke
				(width 0.1524)
				(type default)
			)
			(layer "F.SilkS")
		)
		(fp_line
			(start -0.7874 0.4064)
			(end -0.7874 -0.4064)
			(stroke
				(width 0.1524)
				(type default)
			)
			(layer "F.SilkS")
		)
		(fp_line
			(start 0.7874 -0.4064)
			(end 0.7874 0.4064)
			(stroke
				(width 0.1524)
				(type default)
			)
			(layer "F.SilkS")
		)
		(fp_line
			(start 0.7874 0.4064)
			(end -0.7874 0.4064)
			(stroke
				(width 0.1524)
				(type default)
			)
			(layer "F.SilkS")
		)
		(fp_poly
			(pts
				(xy -0.508 0.2794) (xy -0.508 0.2286) (xy -0.635 0.2286) (xy -0.635 -0.254) (xy -0.5334 -0.254)
				(xy -0.5334 -0.2794) (xy 0.5334 -0.2794) (xy 0.5334 -0.254) (xy 0.635 -0.254) (xy 0.635 0.254) (xy 0.5334 0.254)
				(xy 0.5334 0.2794)
			)
			(stroke
				(width 0)
				(type default)
			)
			(fill no)
			(layer "F.CrtYd")
		)
		(pad "1" smd rect
			(at 0.40005 0)
			(size 0.4572 0.508)
			(layers "F.Cu" "F.Mask" "F.Paste")
			(net "PSU6_PS_KILL")
		)
		(pad "2" smd rect
			(at -0.40005 0)
			(size 0.4572 0.508)
			(layers "F.Cu" "F.Mask" "F.Paste")
			(net "P12V_STBY")
		)
	)
	(footprint ""
		(layer "F.Cu")
		(at 69.726556 -172.135546 90)
		(property "Reference" "C34"
			(at -4.082034 0.14097 90)
			(unlocked yes)
			(layer "F.SilkS")
			(effects
				(font
					(size 0.7874 0.5842)
					(thickness 0.1524)
				)
				(justify left)
			)
		)
		(property "Value" ""
			(at 0 0 90)
			(layer "F.Fab")
			(effects
				(font
					(size 1.27 1.27)
				)
			)
		)
		(duplicate_pad_numbers_are_jumpers no)
		(fp_line
			(start 0.7874 -0.4064)
			(end 0.7874 0.4064)
			(stroke
				(width 0.1524)
				(type default)
			)
			(layer "F.SilkS")
		)
		(fp_line
			(start -0.7874 -0.4064)
			(end 0.7874 -0.4064)
			(stroke
				(width 0.1524)
				(type default)
			)
			(layer "F.SilkS")
		)
		(fp_line
			(start 0 0.381)
			(end 0 -0.381)
			(stroke
				(width 0.1524)
				(type default)
			)
			(layer "F.SilkS")
		)
		(fp_line
			(start 0.7874 0.4064)
			(end -0.7874 0.4064)
			(stroke
				(width 0.1524)
				(type default)
			)
			(layer "F.SilkS")
		)
		(fp_line
			(start -0.7874 0.4064)
			(end -0.7874 -0.4064)
			(stroke
				(width 0.1524)
				(type default)
			)
			(layer "F.SilkS")
		)
		(fp_poly
			(pts
				(xy -0.5334 0.254) (xy -0.635 0.254) (xy -0.635 0.2286) (xy -0.635 -0.254) (xy -0.5334 -0.254) (xy -0.5334 -0.2794)
				(xy 0.5334 -0.2794) (xy 0.5334 -0.254) (xy 0.635 -0.254) (xy 0.635 0.254) (xy 0.5334 0.254) (xy 0.5334 0.2794)
				(xy -0.508 0.2794) (xy -0.5334 0.2794)
			)
			(stroke
				(width 0)
				(type default)
			)
			(fill no)
			(layer "F.CrtYd")
		)
		(pad "1" smd rect
			(at 0.40005 0 90)
			(size 0.4572 0.508)
			(layers "F.Cu" "F.Mask" "F.Paste")
			(net "P12V")
		)
		(pad "2" smd rect
			(at -0.40005 0 90)
			(size 0.4572 0.508)
			(layers "F.Cu" "F.Mask" "F.Paste")
			(net "GND")
		)
	)
	(footprint ""
		(layer "F.Cu")
		(at 25.931622 -96.872044)
		(property "Reference" "R68"
			(at -4.080256 -0.075692 0)
			(unlocked yes)
			(layer "F.SilkS")
			(effects
				(font
					(size 0.7874 0.5842)
					(thickness 0.1524)
				)
				(justify left)
			)
		)
		(property "Value" ""
			(at 0 0 0)
			(layer "F.Fab")
			(effects
				(font
					(size 1.27 1.27)
				)
			)
		)
		(duplicate_pad_numbers_are_jumpers no)
		(fp_line
			(start -0.7874 -0.4064)
			(end 0.7874 -0.4064)
			(stroke
				(width 0.1524)
				(type default)
			)
			(layer "F.SilkS")
		)
		(fp_line
			(start -0.7874 0.4064)
			(end -0.7874 -0.4064)
			(stroke
				(width 0.1524)
				(type default)
			)
			(layer "F.SilkS")
		)
		(fp_line
			(start 0.7874 -0.4064)
			(end 0.7874 0.4064)
			(stroke
				(width 0.1524)
				(type default)
			)
			(layer "F.SilkS")
		)
		(fp_line
			(start 0.7874 0.4064)
			(end -0.7874 0.4064)
			(stroke
				(width 0.1524)
				(type default)
			)
			(layer "F.SilkS")
		)
		(fp_poly
			(pts
				(xy -0.508 0.2794) (xy -0.508 0.2286) (xy -0.635 0.2286) (xy -0.635 -0.254) (xy -0.5334 -0.254)
				(xy -0.5334 -0.2794) (xy 0.5334 -0.2794) (xy 0.5334 -0.254) (xy 0.635 -0.254) (xy 0.635 0.254) (xy 0.5334 0.254)
				(xy 0.5334 0.2794)
			)
			(stroke
				(width 0)
				(type default)
			)
			(fill no)
			(layer "F.CrtYd")
		)
		(pad "1" smd rect
			(at 0.40005 0)
			(size 0.4572 0.508)
			(layers "F.Cu" "F.Mask" "F.Paste")
			(net "PSU2_RESET")
		)
		(pad "2" smd rect
			(at -0.40005 0)
			(size 0.4572 0.508)
			(layers "F.Cu" "F.Mask" "F.Paste")
			(net "P12V_STBY")
		)
	)
	(footprint ""
		(layer "F.Cu")
		(at 13.429234 -326.145652 180)
		(property "Reference" "R145"
			(at -1.746758 -0.079502 0)
			(unlocked yes)
			(layer "F.SilkS")
			(effects
				(font
					(size 0.7874 0.5842)
					(thickness 0.1524)
				)
				(justify left)
			)
		)
		(property "Value" ""
			(at 0 0 180)
			(layer "F.Fab")
			(effects
				(font
					(size 1.27 1.27)
				)
			)
		)
		(duplicate_pad_numbers_are_jumpers no)
		(fp_line
			(start 0.7874 0.4064)
			(end -0.7874 0.4064)
			(stroke
				(width 0.1524)
				(type default)
			)
			(layer "F.SilkS")
		)
		(fp_line
			(start 0.7874 -0.4064)
			(end 0.7874 0.4064)
			(stroke
				(width 0.1524)
				(type default)
			)
			(layer "F.SilkS")
		)
		(fp_line
			(start -0.7874 0.4064)
			(end -0.7874 -0.4064)
			(stroke
				(width 0.1524)
				(type default)
			)
			(layer "F.SilkS")
		)
		(fp_line
			(start -0.7874 -0.4064)
			(end 0.7874 -0.4064)
			(stroke
				(width 0.1524)
				(type default)
			)
			(layer "F.SilkS")
		)
		(fp_poly
			(pts
				(xy -0.508 0.2794) (xy -0.508 0.2286) (xy -0.635 0.2286) (xy -0.635 -0.254) (xy -0.5334 -0.254)
				(xy -0.5334 -0.2794) (xy 0.5334 -0.2794) (xy 0.5334 -0.254) (xy 0.635 -0.254) (xy 0.635 0.254) (xy 0.5334 0.254)
				(xy 0.5334 0.2794)
			)
			(stroke
				(width 0)
				(type default)
			)
			(fill no)
			(layer "F.CrtYd")
		)
		(pad "1" smd rect
			(at 0.40005 0 180)
			(size 0.4572 0.508)
			(layers "F.Cu" "F.Mask" "F.Paste")
			(net "FAN4_TACH")
		)
		(pad "2" smd rect
			(at -0.40005 0 180)
			(size 0.4572 0.508)
			(layers "F.Cu" "F.Mask" "F.Paste")
			(net "P12V")
		)
	)
	(footprint ""
		(layer "F.Cu")
		(at 91.399868 -197.81012)
		(property "Reference" "H20"
			(at -5.1308 -5.23113 0)
			(unlocked yes)
			(layer "F.SilkS")
			(effects
				(font
					(size 0.7874 0.5842)
					(thickness 0.1524)
				)
				(justify left)
			)
		)
		(property "Value" ""
			(at 0 0 0)
			(layer "F.Fab")
			(effects
				(font
					(size 1.27 1.27)
				)
			)
		)
		(duplicate_pad_numbers_are_jumpers no)
		(fp_circle
			(center 0 0)
			(end 4.826 0)
			(stroke
				(width 0.1524)
				(type default)
			)
			(fill no)
			(layer "F.SilkS")
		)
		(fp_circle
			(center 0 0)
			(end 4.826 0)
			(stroke
				(width 0.1524)
				(type default)
			)
			(fill no)
			(layer "B.SilkS")
		)
		(fp_poly
			(pts
				(arc
					(start 0 4.0132)
					(mid 0 -4.0132)
					(end 0 4.0132)
				)
			)
			(stroke
				(width 0)
				(type default)
			)
			(fill no)
			(layer "F.CrtYd")
		)
		(pad "" np_thru_hole circle
			(at 0 0)
			(size 8.001 8.001)
			(drill 8.001)
			(layers "*.Cu" "*.Mask")
			(clearance 0.381)
			(thermal_gap 0.381)
		)
		(zone
			(layers "F.Cu" "B.Cu" "In1.Cu" "In2.Cu" "In3.Cu" "In4.Cu" "In5.Cu" "In6.Cu")
			(hatch none 0.5)
			(connect_pads
				(clearance 0)
			)
			(min_thickness 0.25)
			(keepout
				(tracks not_allowed)
				(vias allowed)
				(pads allowed)
				(copperpour not_allowed)
				(footprints allowed)
			)
			(placement
				(enabled no)
				(sheetname "")
			)
			(fill
				(thermal_gap 0.5)
				(thermal_bridge_width 0.5)
				(island_removal_mode 0)
			)
			(polygon
				(pts
					(arc
						(start 91.399868 -193.28892)
						(mid 91.399868 -202.33132)
						(end 91.399868 -193.28892)
					)
				)
			)
		)
	)
	(footprint ""
		(layer "F.Cu")
		(at 39.873936 -22.379432 180)
		(property "Reference" "R1"
			(at -2.42951 0.191262 0)
			(unlocked yes)
			(layer "F.SilkS")
			(effects
				(font
					(size 0.7874 0.5842)
					(thickness 0.1524)
				)
				(justify left)
			)
		)
		(property "Value" ""
			(at 0 0 180)
			(layer "F.Fab")
			(effects
				(font
					(size 1.27 1.27)
				)
			)
		)
		(duplicate_pad_numbers_are_jumpers no)
		(fp_line
			(start 0.7874 0.4064)
			(end -0.7874 0.4064)
			(stroke
				(width 0.1524)
				(type default)
			)
			(layer "F.SilkS")
		)
		(fp_line
			(start 0.7874 -0.4064)
			(end 0.7874 0.4064)
			(stroke
				(width 0.1524)
				(type default)
			)
			(layer "F.SilkS")
		)
		(fp_line
			(start -0.7874 0.4064)
			(end -0.7874 -0.4064)
			(stroke
				(width 0.1524)
				(type default)
			)
			(layer "F.SilkS")
		)
		(fp_line
			(start -0.7874 -0.4064)
			(end 0.7874 -0.4064)
			(stroke
				(width 0.1524)
				(type default)
			)
			(layer "F.SilkS")
		)
		(fp_poly
			(pts
				(xy -0.508 0.2794) (xy -0.508 0.2286) (xy -0.635 0.2286) (xy -0.635 -0.254) (xy -0.5334 -0.254)
				(xy -0.5334 -0.2794) (xy 0.5334 -0.2794) (xy 0.5334 -0.254) (xy 0.635 -0.254) (xy 0.635 0.254) (xy 0.5334 0.254)
				(xy 0.5334 0.2794)
			)
			(stroke
				(width 0)
				(type default)
			)
			(fill no)
			(layer "F.CrtYd")
		)
		(pad "1" smd rect
			(at 0.40005 0 180)
			(size 0.4572 0.508)
			(layers "F.Cu" "F.Mask" "F.Paste")
			(net "PSU1_REMOTE_P")
		)
		(pad "2" smd rect
			(at -0.40005 0 180)
			(size 0.4572 0.508)
			(layers "F.Cu" "F.Mask" "F.Paste")
			(net "P12V")
		)
	)
	(footprint ""
		(layer "F.Cu")
		(at 68.972938 -64.481456 -90)
		(property "Reference" "C8"
			(at -2.737104 0.062992 90)
			(unlocked yes)
			(layer "F.SilkS")
			(effects
				(font
					(size 0.7874 0.5842)
					(thickness 0.1524)
				)
			)
		)
		(property "Value" ""
			(at 0 0 270)
			(layer "F.Fab")
			(effects
				(font
					(size 1.27 1.27)
				)
			)
		)
		(duplicate_pad_numbers_are_jumpers no)
		(fp_line
			(start -1.2954 0.5842)
			(end -1.2954 -0.5842)
			(stroke
				(width 0.1524)
				(type default)
			)
			(layer "F.SilkS")
		)
		(fp_line
			(start 1.2954 0.5842)
			(end -1.2954 0.5842)
			(stroke
				(width 0.1524)
				(type default)
			)
			(layer "F.SilkS")
		)
		(fp_line
			(start -1.2954 -0.5842)
			(end 1.2954 -0.5842)
			(stroke
				(width 0.1524)
				(type default)
			)
			(layer "F.SilkS")
		)
		(fp_line
			(start 0 -0.5842)
			(end 0 0.5842)
			(stroke
				(width 0.1524)
				(type default)
			)
			(layer "F.SilkS")
		)
		(fp_line
			(start 1.2954 -0.5842)
			(end 1.2954 0.5842)
			(stroke
				(width 0.1524)
				(type default)
			)
			(layer "F.SilkS")
		)
		(fp_poly
			(pts
				(xy 0.8636 -0.4572) (xy 0.8636 -0.3556) (xy 1.143 -0.3556) (xy 1.143 0.3556) (xy 0.8636 0.3556)
				(xy 0.8636 0.4572) (xy -0.8636 0.4572) (xy -0.8636 0.3556) (xy -1.143 0.3556) (xy -1.143 -0.3556)
				(xy -0.8636 -0.3556) (xy -0.8636 -0.4572)
			)
			(stroke
				(width 0)
				(type default)
			)
			(fill no)
			(layer "F.CrtYd")
		)
		(fp_line
			(start -0.884936 0.504952)
			(end -0.884936 -0.504952)
			(stroke
				(width 0.1)
				(type default)
			)
			(layer "F.Fab")
		)
		(fp_line
			(start 0.884936 0.504952)
			(end -0.884936 0.504952)
			(stroke
				(width 0.1)
				(type default)
			)
			(layer "F.Fab")
		)
		(fp_line
			(start -0.884936 -0.504952)
			(end 0.884936 -0.504952)
			(stroke
				(width 0.1)
				(type default)
			)
			(layer "F.Fab")
		)
		(fp_line
			(start 0.884936 -0.504952)
			(end 0.884936 0.504952)
			(stroke
				(width 0.1)
				(type default)
			)
			(layer "F.Fab")
		)
		(pad "1" smd rect
			(at 0.7366 0)
			(size 0.7112 0.8128)
			(layers "F.Cu" "F.Mask" "F.Paste")
			(net "P12V")
		)
		(pad "2" smd rect
			(at -0.7366 0)
			(size 0.7112 0.8128)
			(layers "F.Cu" "F.Mask" "F.Paste")
			(net "GND")
		)
	)
	(footprint ""
		(layer "F.Cu")
		(at 68.716144 -117.627146 180)
		(property "Reference" "R116"
			(at 1.552448 -1.398016 0)
			(unlocked yes)
			(layer "F.SilkS")
			(effects
				(font
					(size 0.7874 0.5842)
					(thickness 0.1524)
				)
				(justify left)
			)
		)
		(property "Value" ""
			(at 0 0 180)
			(layer "F.Fab")
			(effects
				(font
					(size 1.27 1.27)
				)
			)
		)
		(duplicate_pad_numbers_are_jumpers no)
		(fp_line
			(start 0.7874 0.4064)
			(end -0.7874 0.4064)
			(stroke
				(width 0.1524)
				(type default)
			)
			(layer "F.SilkS")
		)
		(fp_line
			(start 0.7874 -0.4064)
			(end 0.7874 0.4064)
			(stroke
				(width 0.1524)
				(type default)
			)
			(layer "F.SilkS")
		)
		(fp_line
			(start -0.7874 0.4064)
			(end -0.7874 -0.4064)
			(stroke
				(width 0.1524)
				(type default)
			)
			(layer "F.SilkS")
		)
		(fp_line
			(start -0.7874 -0.4064)
			(end 0.7874 -0.4064)
			(stroke
				(width 0.1524)
				(type default)
			)
			(layer "F.SilkS")
		)
		(fp_poly
			(pts
				(xy -0.508 0.2794) (xy -0.508 0.2286) (xy -0.635 0.2286) (xy -0.635 -0.254) (xy -0.5334 -0.254)
				(xy -0.5334 -0.2794) (xy 0.5334 -0.2794) (xy 0.5334 -0.254) (xy 0.635 -0.254) (xy 0.635 0.254) (xy 0.5334 0.254)
				(xy 0.5334 0.2794)
			)
			(stroke
				(width 0)
				(type default)
			)
			(fill no)
			(layer "F.CrtYd")
		)
		(pad "1" smd rect
			(at 0.40005 0 180)
			(size 0.4572 0.508)
			(layers "F.Cu" "F.Mask" "F.Paste")
			(net "PSU2_REMOTE_R2_N")
		)
		(pad "2" smd rect
			(at -0.40005 0 180)
			(size 0.4572 0.508)
			(layers "F.Cu" "F.Mask" "F.Paste")
			(net "GND")
		)
	)
	(footprint ""
		(layer "F.Cu")
		(at 70.997572 -350.498664 90)
		(property "Reference" "C61"
			(at 1.158748 0.151892 90)
			(unlocked yes)
			(layer "F.SilkS")
			(effects
				(font
					(size 0.7874 0.5842)
					(thickness 0.1524)
				)
				(justify left)
			)
		)
		(property "Value" ""
			(at 0 0 90)
			(layer "F.Fab")
			(effects
				(font
					(size 1.27 1.27)
				)
			)
		)
		(duplicate_pad_numbers_are_jumpers no)
		(fp_line
			(start 0.7874 -0.4064)
			(end 0.7874 0.4064)
			(stroke
				(width 0.1524)
				(type default)
			)
			(layer "F.SilkS")
		)
		(fp_line
			(start -0.7874 -0.4064)
			(end 0.7874 -0.4064)
			(stroke
				(width 0.1524)
				(type default)
			)
			(layer "F.SilkS")
		)
		(fp_line
			(start 0 0.381)
			(end 0 -0.381)
			(stroke
				(width 0.1524)
				(type default)
			)
			(layer "F.SilkS")
		)
		(fp_line
			(start 0.7874 0.4064)
			(end -0.7874 0.4064)
			(stroke
				(width 0.1524)
				(type default)
			)
			(layer "F.SilkS")
		)
		(fp_line
			(start -0.7874 0.4064)
			(end -0.7874 -0.4064)
			(stroke
				(width 0.1524)
				(type default)
			)
			(layer "F.SilkS")
		)
		(fp_poly
			(pts
				(xy -0.5334 0.254) (xy -0.635 0.254) (xy -0.635 0.2286) (xy -0.635 -0.254) (xy -0.5334 -0.254) (xy -0.5334 -0.2794)
				(xy 0.5334 -0.2794) (xy 0.5334 -0.254) (xy 0.635 -0.254) (xy 0.635 0.254) (xy 0.5334 0.254) (xy 0.5334 0.2794)
				(xy -0.508 0.2794) (xy -0.5334 0.2794)
			)
			(stroke
				(width 0)
				(type default)
			)
			(fill no)
			(layer "F.CrtYd")
		)
		(pad "1" smd rect
			(at 0.40005 0 90)
			(size 0.4572 0.508)
			(layers "F.Cu" "F.Mask" "F.Paste")
			(net "P12V")
		)
		(pad "2" smd rect
			(at -0.40005 0 90)
			(size 0.4572 0.508)
			(layers "F.Cu" "F.Mask" "F.Paste")
			(net "GND")
		)
	)
	(footprint ""
		(layer "F.Cu")
		(at 50.100738 -62.882272 180)
		(property "Reference" "CE3"
			(at -4.025646 2.458974 0)
			(unlocked yes)
			(layer "F.SilkS")
			(effects
				(font
					(size 0.7874 0.5842)
					(thickness 0.1524)
				)
				(justify left)
			)
		)
		(property "Value" ""
			(at 0 0 180)
			(layer "F.Fab")
			(effects
				(font
					(size 1.27 1.27)
				)
			)
		)
		(duplicate_pad_numbers_are_jumpers no)
		(fp_line
			(start 0 -4.2672)
			(end 0 4.2672)
			(stroke
				(width 0.1524)
				(type default)
			)
			(layer "F.SilkS")
		)
		(fp_circle
			(center 0 0)
			(end -4.2672 0)
			(stroke
				(width 0.1524)
				(type default)
			)
			(fill no)
			(layer "F.SilkS")
		)
		(fp_poly
			(pts
				(arc
					(start 0 -4.2672)
					(mid 4.2672 0)
					(end 0 4.2672)
				)
			)
			(stroke
				(width 0)
				(type default)
			)
			(fill yes)
			(layer "F.SilkS")
		)
		(fp_poly
			(pts
				(xy -2.5146 -0.762) (xy -0.9906 -0.762) (xy -0.9906 0.762) (xy -2.5146 0.762)
			)
			(stroke
				(width 0)
				(type default)
			)
			(fill no)
			(layer "B.CrtYd")
		)
		(fp_poly
			(pts
				(arc
					(start 1.7526 0.762)
					(mid 2.291415 -0.538815)
					(end 0.9906 0)
				)
				(arc
					(start 0.9906 0.0254)
					(mid 1.206345 0.546255)
					(end 1.7272 0.762)
				)
			)
			(stroke
				(width 0)
				(type default)
			)
			(fill no)
			(layer "B.CrtYd")
		)
		(fp_poly
			(pts
				(arc
					(start -4.2672 0)
					(mid 4.2672 0)
					(end -4.2672 0)
				)
			)
			(stroke
				(width 0)
				(type default)
			)
			(fill no)
			(layer "F.CrtYd")
		)
		(fp_circle
			(center 0 0)
			(end -4.2672 0)
			(stroke
				(width 0.1)
				(type default)
			)
			(fill no)
			(layer "F.Fab")
		)
		(fp_text user "+"
			(at -5.750306 -0.61595 180)
			(unlocked yes)
			(layer "F.SilkS")
			(effects
				(font
					(size 1.905 1.4224)
					(thickness 0.1524)
				)
				(justify left)
			)
		)
		(fp_text user "+"
			(at -5.6642 -0.34925 180)
			(unlocked yes)
			(layer "F.Fab")
			(effects
				(font
					(size 1.905 1.4224)
					(thickness 0.000001)
				)
				(justify left)
			)
		)
		(pad "1" thru_hole rect
			(at -1.75006 0 180)
			(size 1.397 1.397)
			(drill 0.9144)
			(layers "*.Cu" "*.Mask")
			(remove_unused_layers no)
			(net "P12V")
			(clearance 0.0127)
			(thermal_gap 0.0127)
			(padstack
				(mode front_inner_back)
				(layer "Inner"
					(shape circle)
					(size 1.397 1.397)
					(clearance 0.0127)
				)
				(layer "B.Cu"
					(shape rect)
					(size 1.397 1.397)
					(clearance 0.0127)
				)
			)
		)
		(pad "2" thru_hole circle
			(at 1.75006 0 180)
			(size 1.397 1.397)
			(drill 0.9144)
			(layers "*.Cu" "*.Mask")
			(remove_unused_layers no)
			(net "GND")
			(clearance 0.0127)
			(thermal_gap 0.0127)
		)
	)
	(footprint ""
		(layer "F.Cu")
		(at 81.29143 -508.115824 -90)
		(property "Reference" "C79"
			(at 3.578606 0.032512 90)
			(unlocked yes)
			(layer "F.SilkS")
			(effects
				(font
					(size 0.7874 0.5842)
					(thickness 0.1524)
				)
				(justify left)
			)
		)
		(property "Value" ""
			(at 0 0 270)
			(layer "F.Fab")
			(effects
				(font
					(size 1.27 1.27)
				)
			)
		)
		(duplicate_pad_numbers_are_jumpers no)
		(fp_line
			(start -0.7874 0.4064)
			(end -0.7874 -0.4064)
			(stroke
				(width 0.1524)
				(type default)
			)
			(layer "F.SilkS")
		)
		(fp_line
			(start 0.7874 0.4064)
			(end -0.7874 0.4064)
			(stroke
				(width 0.1524)
				(type default)
			)
			(layer "F.SilkS")
		)
		(fp_line
			(start 0 0.381)
			(end 0 -0.381)
			(stroke
				(width 0.1524)
				(type default)
			)
			(layer "F.SilkS")
		)
		(fp_line
			(start -0.7874 -0.4064)
			(end 0.7874 -0.4064)
			(stroke
				(width 0.1524)
				(type default)
			)
			(layer "F.SilkS")
		)
		(fp_line
			(start 0.7874 -0.4064)
			(end 0.7874 0.4064)
			(stroke
				(width 0.1524)
				(type default)
			)
			(layer "F.SilkS")
		)
		(fp_poly
			(pts
				(xy -0.5334 0.254) (xy -0.635 0.254) (xy -0.635 0.2286) (xy -0.635 -0.254) (xy -0.5334 -0.254) (xy -0.5334 -0.2794)
				(xy 0.5334 -0.2794) (xy 0.5334 -0.254) (xy 0.635 -0.254) (xy 0.635 0.254) (xy 0.5334 0.254) (xy 0.5334 0.2794)
				(xy -0.508 0.2794) (xy -0.5334 0.2794)
			)
			(stroke
				(width 0)
				(type default)
			)
			(fill no)
			(layer "F.CrtYd")
		)
		(pad "1" smd rect
			(at 0.40005 0 270)
			(size 0.4572 0.508)
			(layers "F.Cu" "F.Mask" "F.Paste")
			(net "P12V")
		)
		(pad "2" smd rect
			(at -0.40005 0 270)
			(size 0.4572 0.508)
			(layers "F.Cu" "F.Mask" "F.Paste")
			(net "GND")
		)
	)
	(footprint ""
		(layer "F.Cu")
		(at 67.101974 -216.615772 90)
		(property "Reference" "C42"
			(at 1.20523 -0.200406 90)
			(unlocked yes)
			(layer "F.SilkS")
			(effects
				(font
					(size 0.7874 0.5842)
					(thickness 0.1524)
				)
				(justify left)
			)
		)
		(property "Value" ""
			(at 0 0 90)
			(layer "F.Fab")
			(effects
				(font
					(size 1.27 1.27)
				)
			)
		)
		(duplicate_pad_numbers_are_jumpers no)
		(fp_line
			(start 0.7874 -0.4064)
			(end 0.7874 0.4064)
			(stroke
				(width 0.1524)
				(type default)
			)
			(layer "F.SilkS")
		)
		(fp_line
			(start -0.7874 -0.4064)
			(end 0.7874 -0.4064)
			(stroke
				(width 0.1524)
				(type default)
			)
			(layer "F.SilkS")
		)
		(fp_line
			(start 0 0.381)
			(end 0 -0.381)
			(stroke
				(width 0.1524)
				(type default)
			)
			(layer "F.SilkS")
		)
		(fp_line
			(start 0.7874 0.4064)
			(end -0.7874 0.4064)
			(stroke
				(width 0.1524)
				(type default)
			)
			(layer "F.SilkS")
		)
		(fp_line
			(start -0.7874 0.4064)
			(end -0.7874 -0.4064)
			(stroke
				(width 0.1524)
				(type default)
			)
			(layer "F.SilkS")
		)
		(fp_poly
			(pts
				(xy -0.5334 0.254) (xy -0.635 0.254) (xy -0.635 0.2286) (xy -0.635 -0.254) (xy -0.5334 -0.254) (xy -0.5334 -0.2794)
				(xy 0.5334 -0.2794) (xy 0.5334 -0.254) (xy 0.635 -0.254) (xy 0.635 0.254) (xy 0.5334 0.254) (xy 0.5334 0.2794)
				(xy -0.508 0.2794) (xy -0.5334 0.2794)
			)
			(stroke
				(width 0)
				(type default)
			)
			(fill no)
			(layer "F.CrtYd")
		)
		(pad "1" smd rect
			(at 0.40005 0 90)
			(size 0.4572 0.508)
			(layers "F.Cu" "F.Mask" "F.Paste")
			(net "P12V")
		)
		(pad "2" smd rect
			(at -0.40005 0 90)
			(size 0.4572 0.508)
			(layers "F.Cu" "F.Mask" "F.Paste")
			(net "GND")
		)
	)
	(footprint ""
		(layer "F.Cu")
		(at 79.524606 -18.749772 -90)
		(property "Reference" "C5"
			(at -1.75133 0.0254 90)
			(unlocked yes)
			(layer "F.SilkS")
			(effects
				(font
					(size 0.7874 0.5842)
					(thickness 0.1524)
				)
				(justify left)
			)
		)
		(property "Value" ""
			(at 0 0 270)
			(layer "F.Fab")
			(effects
				(font
					(size 1.27 1.27)
				)
			)
		)
		(duplicate_pad_numbers_are_jumpers no)
		(fp_line
			(start -0.7874 0.4064)
			(end -0.7874 -0.4064)
			(stroke
				(width 0.1524)
				(type default)
			)
			(layer "F.SilkS")
		)
		(fp_line
			(start 0.7874 0.4064)
			(end -0.7874 0.4064)
			(stroke
				(width 0.1524)
				(type default)
			)
			(layer "F.SilkS")
		)
		(fp_line
			(start 0 0.381)
			(end 0 -0.381)
			(stroke
				(width 0.1524)
				(type default)
			)
			(layer "F.SilkS")
		)
		(fp_line
			(start -0.7874 -0.4064)
			(end 0.7874 -0.4064)
			(stroke
				(width 0.1524)
				(type default)
			)
			(layer "F.SilkS")
		)
		(fp_line
			(start 0.7874 -0.4064)
			(end 0.7874 0.4064)
			(stroke
				(width 0.1524)
				(type default)
			)
			(layer "F.SilkS")
		)
		(fp_poly
			(pts
				(xy -0.5334 0.254) (xy -0.635 0.254) (xy -0.635 0.2286) (xy -0.635 -0.254) (xy -0.5334 -0.254) (xy -0.5334 -0.2794)
				(xy 0.5334 -0.2794) (xy 0.5334 -0.254) (xy 0.635 -0.254) (xy 0.635 0.254) (xy 0.5334 0.254) (xy 0.5334 0.2794)
				(xy -0.508 0.2794) (xy -0.5334 0.2794)
			)
			(stroke
				(width 0)
				(type default)
			)
			(fill no)
			(layer "F.CrtYd")
		)
		(pad "1" smd rect
			(at 0.40005 0 270)
			(size 0.4572 0.508)
			(layers "F.Cu" "F.Mask" "F.Paste")
			(net "P12V")
		)
		(pad "2" smd rect
			(at -0.40005 0 270)
			(size 0.4572 0.508)
			(layers "F.Cu" "F.Mask" "F.Paste")
			(net "GND")
		)
	)
	(footprint ""
		(layer "F.Cu")
		(at 39.581836 -376.389646 -90)
		(property "Reference" "R102"
			(at -0.894842 -0.166878 90)
			(unlocked yes)
			(layer "F.SilkS")
			(effects
				(font
					(size 0.7874 0.5842)
					(thickness 0.1524)
				)
				(justify left)
			)
		)
		(property "Value" ""
			(at 0 0 270)
			(layer "F.Fab")
			(effects
				(font
					(size 1.27 1.27)
				)
			)
		)
		(duplicate_pad_numbers_are_jumpers no)
		(fp_line
			(start -0.7874 0.4064)
			(end -0.7874 -0.4064)
			(stroke
				(width 0.1524)
				(type default)
			)
			(layer "F.SilkS")
		)
		(fp_line
			(start 0.7874 0.4064)
			(end -0.7874 0.4064)
			(stroke
				(width 0.1524)
				(type default)
			)
			(layer "F.SilkS")
		)
		(fp_line
			(start -0.7874 -0.4064)
			(end 0.7874 -0.4064)
			(stroke
				(width 0.1524)
				(type default)
			)
			(layer "F.SilkS")
		)
		(fp_line
			(start 0.7874 -0.4064)
			(end 0.7874 0.4064)
			(stroke
				(width 0.1524)
				(type default)
			)
			(layer "F.SilkS")
		)
		(fp_poly
			(pts
				(xy -0.508 0.2794) (xy -0.508 0.2286) (xy -0.635 0.2286) (xy -0.635 -0.254) (xy -0.5334 -0.254)
				(xy -0.5334 -0.2794) (xy 0.5334 -0.2794) (xy 0.5334 -0.254) (xy 0.635 -0.254) (xy 0.635 0.254) (xy 0.5334 0.254)
				(xy 0.5334 0.2794)
			)
			(stroke
				(width 0)
				(type default)
			)
			(fill no)
			(layer "F.CrtYd")
		)
		(pad "1" smd rect
			(at 0.40005 0 270)
			(size 0.4572 0.508)
			(layers "F.Cu" "F.Mask" "F.Paste")
			(net "PSU5_REMOTE_P")
		)
		(pad "2" smd rect
			(at -0.40005 0 270)
			(size 0.4572 0.508)
			(layers "F.Cu" "F.Mask" "F.Paste")
			(net "PSU5_REMOTE_R_P")
		)
	)
	(footprint ""
		(layer "F.Cu")
		(at 76.299568 -393.452604 90)
		(property "Reference" "C68"
			(at 1.084834 0.192786 90)
			(unlocked yes)
			(layer "F.SilkS")
			(effects
				(font
					(size 0.7874 0.5842)
					(thickness 0.1524)
				)
				(justify left)
			)
		)
		(property "Value" ""
			(at 0 0 90)
			(layer "F.Fab")
			(effects
				(font
					(size 1.27 1.27)
				)
			)
		)
		(duplicate_pad_numbers_are_jumpers no)
		(fp_line
			(start 0.7874 -0.4064)
			(end 0.7874 0.4064)
			(stroke
				(width 0.1524)
				(type default)
			)
			(layer "F.SilkS")
		)
		(fp_line
			(start -0.7874 -0.4064)
			(end 0.7874 -0.4064)
			(stroke
				(width 0.1524)
				(type default)
			)
			(layer "F.SilkS")
		)
		(fp_line
			(start 0 0.381)
			(end 0 -0.381)
			(stroke
				(width 0.1524)
				(type default)
			)
			(layer "F.SilkS")
		)
		(fp_line
			(start 0.7874 0.4064)
			(end -0.7874 0.4064)
			(stroke
				(width 0.1524)
				(type default)
			)
			(layer "F.SilkS")
		)
		(fp_line
			(start -0.7874 0.4064)
			(end -0.7874 -0.4064)
			(stroke
				(width 0.1524)
				(type default)
			)
			(layer "F.SilkS")
		)
		(fp_poly
			(pts
				(xy -0.5334 0.254) (xy -0.635 0.254) (xy -0.635 0.2286) (xy -0.635 -0.254) (xy -0.5334 -0.254) (xy -0.5334 -0.2794)
				(xy 0.5334 -0.2794) (xy 0.5334 -0.254) (xy 0.635 -0.254) (xy 0.635 0.254) (xy 0.5334 0.254) (xy 0.5334 0.2794)
				(xy -0.508 0.2794) (xy -0.5334 0.2794)
			)
			(stroke
				(width 0)
				(type default)
			)
			(fill no)
			(layer "F.CrtYd")
		)
		(pad "1" smd rect
			(at 0.40005 0 90)
			(size 0.4572 0.508)
			(layers "F.Cu" "F.Mask" "F.Paste")
			(net "P12V")
		)
		(pad "2" smd rect
			(at -0.40005 0 90)
			(size 0.4572 0.508)
			(layers "F.Cu" "F.Mask" "F.Paste")
			(net "GND")
		)
	)
	(footprint ""
		(layer "F.Cu")
		(at 26.102056 -273.532854)
		(property "Reference" "R76"
			(at -4.037838 -0.005334 0)
			(unlocked yes)
			(layer "F.SilkS")
			(effects
				(font
					(size 0.7874 0.5842)
					(thickness 0.1524)
				)
				(justify left)
			)
		)
		(property "Value" ""
			(at 0 0 0)
			(layer "F.Fab")
			(effects
				(font
					(size 1.27 1.27)
				)
			)
		)
		(duplicate_pad_numbers_are_jumpers no)
		(fp_line
			(start -0.7874 -0.4064)
			(end 0.7874 -0.4064)
			(stroke
				(width 0.1524)
				(type default)
			)
			(layer "F.SilkS")
		)
		(fp_line
			(start -0.7874 0.4064)
			(end -0.7874 -0.4064)
			(stroke
				(width 0.1524)
				(type default)
			)
			(layer "F.SilkS")
		)
		(fp_line
			(start 0.7874 -0.4064)
			(end 0.7874 0.4064)
			(stroke
				(width 0.1524)
				(type default)
			)
			(layer "F.SilkS")
		)
		(fp_line
			(start 0.7874 0.4064)
			(end -0.7874 0.4064)
			(stroke
				(width 0.1524)
				(type default)
			)
			(layer "F.SilkS")
		)
		(fp_poly
			(pts
				(xy -0.508 0.2794) (xy -0.508 0.2286) (xy -0.635 0.2286) (xy -0.635 -0.254) (xy -0.5334 -0.254)
				(xy -0.5334 -0.2794) (xy 0.5334 -0.2794) (xy 0.5334 -0.254) (xy 0.635 -0.254) (xy 0.635 0.254) (xy 0.5334 0.254)
				(xy 0.5334 0.2794)
			)
			(stroke
				(width 0)
				(type default)
			)
			(fill no)
			(layer "F.CrtYd")
		)
		(pad "1" smd rect
			(at 0.40005 0)
			(size 0.4572 0.508)
			(layers "F.Cu" "F.Mask" "F.Paste")
			(net "PSU4_RESET")
		)
		(pad "2" smd rect
			(at -0.40005 0)
			(size 0.4572 0.508)
			(layers "F.Cu" "F.Mask" "F.Paste")
			(net "P12V_STBY")
		)
	)
	(footprint ""
		(layer "F.Cu")
		(at 20.97532 -173.53534 -90)
		(property "Reference" "U3"
			(at -0.45974 -4.01193 0)
			(unlocked yes)
			(layer "F.SilkS")
			(effects
				(font
					(size 0.7874 0.5842)
					(thickness 0.1524)
				)
				(justify left)
			)
		)
		(property "Value" ""
			(at 0 0 270)
			(layer "F.Fab")
			(effects
				(font
					(size 1.27 1.27)
				)
			)
		)
		(duplicate_pad_numbers_are_jumpers no)
		(fp_line
			(start -2.5146 1.4224)
			(end -2.5146 0.4572)
			(stroke
				(width 0.1524)
				(type default)
			)
			(layer "F.SilkS")
		)
		(fp_line
			(start 2.5146 1.4224)
			(end -2.5146 1.4224)
			(stroke
				(width 0.1524)
				(type default)
			)
			(layer "F.SilkS")
		)
		(fp_line
			(start -2.5146 0.4572)
			(end -2.0574 0)
			(stroke
				(width 0.1524)
				(type default)
			)
			(layer "F.SilkS")
		)
		(fp_line
			(start -2.0574 0)
			(end -2.5146 -0.4572)
			(stroke
				(width 0.1524)
				(type default)
			)
			(layer "F.SilkS")
		)
		(fp_line
			(start -2.5146 -0.4572)
			(end -2.5146 -1.4224)
			(stroke
				(width 0.1524)
				(type default)
			)
			(layer "F.SilkS")
		)
		(fp_line
			(start -2.5146 -1.4224)
			(end 2.5146 -1.4224)
			(stroke
				(width 0.1524)
				(type default)
			)
			(layer "F.SilkS")
		)
		(fp_line
			(start 2.5146 -1.4224)
			(end 2.5146 1.4224)
			(stroke
				(width 0.1524)
				(type default)
			)
			(layer "F.SilkS")
		)
		(fp_circle
			(center -1.905 0.889)
			(end -1.905 0.635)
			(stroke
				(width 0.1524)
				(type default)
			)
			(fill no)
			(layer "F.SilkS")
		)
		(fp_poly
			(pts
				(xy -2.1844 3.5052) (xy -2.1844 2.0066) (xy -2.5146 2.0066) (xy -2.5146 -2.0066) (xy -2.1844 -2.0066)
				(xy -2.1844 -3.5052) (xy 2.1844 -3.5052) (xy 2.1844 -2.0066) (xy 2.5146 -2.0066) (xy 2.5146 2.0066)
				(xy 2.1844 2.0066) (xy 2.1844 3.5052)
			)
			(stroke
				(width 0)
				(type default)
			)
			(fill no)
			(layer "F.CrtYd")
		)
		(pad "1" smd rect
			(at -1.905 2.6416 270)
			(size 0.5588 1.7272)
			(layers "F.Cu" "F.Mask" "F.Paste")
			(net "N42263600")
		)
		(pad "2" smd rect
			(at -0.635 2.6416 270)
			(size 0.5588 1.7272)
			(layers "F.Cu" "F.Mask" "F.Paste")
			(net "GND")
		)
		(pad "3" smd rect
			(at 0.635 2.6416 270)
			(size 0.5588 1.7272)
			(layers "F.Cu" "F.Mask" "F.Paste")
			(net "GND")
		)
		(pad "4" smd rect
			(at 1.905 2.6416 270)
			(size 0.5588 1.7272)
			(layers "F.Cu" "F.Mask" "F.Paste")
			(net "Net_452")
		)
		(pad "5" smd rect
			(at 1.905 -2.6416 270)
			(size 0.5588 1.7272)
			(layers "F.Cu" "F.Mask" "F.Paste")
			(net "Net_451")
		)
		(pad "6" smd rect
			(at 0.635 -2.6416 270)
			(size 0.5588 1.7272)
			(layers "F.Cu" "F.Mask" "F.Paste")
			(net "GND")
		)
		(pad "7" smd rect
			(at -0.635 -2.6416 270)
			(size 0.5588 1.7272)
			(layers "F.Cu" "F.Mask" "F.Paste")
			(net "GND")
		)
		(pad "8" smd rect
			(at -1.905 -2.6416 270)
			(size 0.5588 1.7272)
			(layers "F.Cu" "F.Mask" "F.Paste")
			(net "N42264085")
		)
	)
	(footprint ""
		(layer "F.Cu")
		(at 72.932798 -473.59951 180)
		(property "Reference" "R131"
			(at 0.900176 1.046988 0)
			(unlocked yes)
			(layer "F.SilkS")
			(effects
				(font
					(size 0.7874 0.5842)
					(thickness 0.1524)
				)
				(justify left)
			)
		)
		(property "Value" ""
			(at 0 0 180)
			(layer "F.Fab")
			(effects
				(font
					(size 1.27 1.27)
				)
			)
		)
		(duplicate_pad_numbers_are_jumpers no)
		(fp_line
			(start 0.7874 0.4064)
			(end -0.7874 0.4064)
			(stroke
				(width 0.1524)
				(type default)
			)
			(layer "F.SilkS")
		)
		(fp_line
			(start 0.7874 -0.4064)
			(end 0.7874 0.4064)
			(stroke
				(width 0.1524)
				(type default)
			)
			(layer "F.SilkS")
		)
		(fp_line
			(start -0.7874 0.4064)
			(end -0.7874 -0.4064)
			(stroke
				(width 0.1524)
				(type default)
			)
			(layer "F.SilkS")
		)
		(fp_line
			(start -0.7874 -0.4064)
			(end 0.7874 -0.4064)
			(stroke
				(width 0.1524)
				(type default)
			)
			(layer "F.SilkS")
		)
		(fp_poly
			(pts
				(xy -0.508 0.2794) (xy -0.508 0.2286) (xy -0.635 0.2286) (xy -0.635 -0.254) (xy -0.5334 -0.254)
				(xy -0.5334 -0.2794) (xy 0.5334 -0.2794) (xy 0.5334 -0.254) (xy 0.635 -0.254) (xy 0.635 0.254) (xy 0.5334 0.254)
				(xy 0.5334 0.2794)
			)
			(stroke
				(width 0)
				(type default)
			)
			(fill no)
			(layer "F.CrtYd")
		)
		(pad "1" smd rect
			(at 0.40005 0 180)
			(size 0.4572 0.508)
			(layers "F.Cu" "F.Mask" "F.Paste")
			(net "PSU6_REMOTE_R2_P")
		)
		(pad "2" smd rect
			(at -0.40005 0 180)
			(size 0.4572 0.508)
			(layers "F.Cu" "F.Mask" "F.Paste")
			(net "P12V")
		)
	)
	(footprint ""
		(layer "F.Cu")
		(at 26.068274 -183.06923)
		(property "Reference" "R55"
			(at -3.997198 0.128524 0)
			(unlocked yes)
			(layer "F.SilkS")
			(effects
				(font
					(size 0.7874 0.5842)
					(thickness 0.1524)
				)
				(justify left)
			)
		)
		(property "Value" ""
			(at 0 0 0)
			(layer "F.Fab")
			(effects
				(font
					(size 1.27 1.27)
				)
			)
		)
		(duplicate_pad_numbers_are_jumpers no)
		(fp_line
			(start -0.7874 -0.4064)
			(end 0.7874 -0.4064)
			(stroke
				(width 0.1524)
				(type default)
			)
			(layer "F.SilkS")
		)
		(fp_line
			(start -0.7874 0.4064)
			(end -0.7874 -0.4064)
			(stroke
				(width 0.1524)
				(type default)
			)
			(layer "F.SilkS")
		)
		(fp_line
			(start 0.7874 -0.4064)
			(end 0.7874 0.4064)
			(stroke
				(width 0.1524)
				(type default)
			)
			(layer "F.SilkS")
		)
		(fp_line
			(start 0.7874 0.4064)
			(end -0.7874 0.4064)
			(stroke
				(width 0.1524)
				(type default)
			)
			(layer "F.SilkS")
		)
		(fp_poly
			(pts
				(xy -0.508 0.2794) (xy -0.508 0.2286) (xy -0.635 0.2286) (xy -0.635 -0.254) (xy -0.5334 -0.254)
				(xy -0.5334 -0.2794) (xy 0.5334 -0.2794) (xy 0.5334 -0.254) (xy 0.635 -0.254) (xy 0.635 0.254) (xy 0.5334 0.254)
				(xy 0.5334 0.2794)
			)
			(stroke
				(width 0)
				(type default)
			)
			(fill no)
			(layer "F.CrtYd")
		)
		(pad "1" smd rect
			(at 0.40005 0)
			(size 0.4572 0.508)
			(layers "F.Cu" "F.Mask" "F.Paste")
			(net "PSU3_RESET")
		)
		(pad "2" smd rect
			(at -0.40005 0)
			(size 0.4572 0.508)
			(layers "F.Cu" "F.Mask" "F.Paste")
			(net "GND")
		)
	)
	(footprint ""
		(layer "F.Cu")
		(at 66.82994 -32.569912 180)
		(property "Reference" "R111"
			(at 1.090422 -1.06934 0)
			(unlocked yes)
			(layer "F.SilkS")
			(effects
				(font
					(size 0.7874 0.5842)
					(thickness 0.1524)
				)
				(justify left)
			)
		)
		(property "Value" ""
			(at 0 0 180)
			(layer "F.Fab")
			(effects
				(font
					(size 1.27 1.27)
				)
			)
		)
		(duplicate_pad_numbers_are_jumpers no)
		(fp_line
			(start 0.7874 0.4064)
			(end -0.7874 0.4064)
			(stroke
				(width 0.1524)
				(type default)
			)
			(layer "F.SilkS")
		)
		(fp_line
			(start 0.7874 -0.4064)
			(end 0.7874 0.4064)
			(stroke
				(width 0.1524)
				(type default)
			)
			(layer "F.SilkS")
		)
		(fp_line
			(start -0.7874 0.4064)
			(end -0.7874 -0.4064)
			(stroke
				(width 0.1524)
				(type default)
			)
			(layer "F.SilkS")
		)
		(fp_line
			(start -0.7874 -0.4064)
			(end 0.7874 -0.4064)
			(stroke
				(width 0.1524)
				(type default)
			)
			(layer "F.SilkS")
		)
		(fp_poly
			(pts
				(xy -0.508 0.2794) (xy -0.508 0.2286) (xy -0.635 0.2286) (xy -0.635 -0.254) (xy -0.5334 -0.254)
				(xy -0.5334 -0.2794) (xy 0.5334 -0.2794) (xy 0.5334 -0.254) (xy 0.635 -0.254) (xy 0.635 0.254) (xy 0.5334 0.254)
				(xy 0.5334 0.2794)
			)
			(stroke
				(width 0)
				(type default)
			)
			(fill no)
			(layer "F.CrtYd")
		)
		(pad "1" smd rect
			(at 0.40005 0 180)
			(size 0.4572 0.508)
			(layers "F.Cu" "F.Mask" "F.Paste")
			(net "PSU1_REMOTE_R2_P")
		)
		(pad "2" smd rect
			(at -0.40005 0 180)
			(size 0.4572 0.508)
			(layers "F.Cu" "F.Mask" "F.Paste")
			(net "P12V")
		)
	)
	(footprint ""
		(layer "F.Cu")
		(at 72.802242 -463.542634 -90)
		(property "Reference" "C72"
			(at -2.840736 0.698754 90)
			(unlocked yes)
			(layer "F.SilkS")
			(effects
				(font
					(size 0.7874 0.5842)
					(thickness 0.1524)
				)
				(justify left)
			)
		)
		(property "Value" ""
			(at 0 0 270)
			(layer "F.Fab")
			(effects
				(font
					(size 1.27 1.27)
				)
			)
		)
		(duplicate_pad_numbers_are_jumpers no)
		(fp_line
			(start -0.7874 0.4064)
			(end -0.7874 -0.4064)
			(stroke
				(width 0.1524)
				(type default)
			)
			(layer "F.SilkS")
		)
		(fp_line
			(start 0.7874 0.4064)
			(end -0.7874 0.4064)
			(stroke
				(width 0.1524)
				(type default)
			)
			(layer "F.SilkS")
		)
		(fp_line
			(start 0 0.381)
			(end 0 -0.381)
			(stroke
				(width 0.1524)
				(type default)
			)
			(layer "F.SilkS")
		)
		(fp_line
			(start -0.7874 -0.4064)
			(end 0.7874 -0.4064)
			(stroke
				(width 0.1524)
				(type default)
			)
			(layer "F.SilkS")
		)
		(fp_line
			(start 0.7874 -0.4064)
			(end 0.7874 0.4064)
			(stroke
				(width 0.1524)
				(type default)
			)
			(layer "F.SilkS")
		)
		(fp_poly
			(pts
				(xy -0.5334 0.254) (xy -0.635 0.254) (xy -0.635 0.2286) (xy -0.635 -0.254) (xy -0.5334 -0.254) (xy -0.5334 -0.2794)
				(xy 0.5334 -0.2794) (xy 0.5334 -0.254) (xy 0.635 -0.254) (xy 0.635 0.254) (xy 0.5334 0.254) (xy 0.5334 0.2794)
				(xy -0.508 0.2794) (xy -0.5334 0.2794)
			)
			(stroke
				(width 0)
				(type default)
			)
			(fill no)
			(layer "F.CrtYd")
		)
		(pad "1" smd rect
			(at 0.40005 0 270)
			(size 0.4572 0.508)
			(layers "F.Cu" "F.Mask" "F.Paste")
			(net "P12V")
		)
		(pad "2" smd rect
			(at -0.40005 0 270)
			(size 0.4572 0.508)
			(layers "F.Cu" "F.Mask" "F.Paste")
			(net "GND")
		)
	)
	(footprint ""
		(layer "F.Cu")
		(at 40.056562 -281.140662 180)
		(property "Reference" "R25"
			(at -1.619504 -0.058166 0)
			(unlocked yes)
			(layer "F.SilkS")
			(effects
				(font
					(size 0.7874 0.5842)
					(thickness 0.1524)
				)
				(justify left)
			)
		)
		(property "Value" ""
			(at 0 0 180)
			(layer "F.Fab")
			(effects
				(font
					(size 1.27 1.27)
				)
			)
		)
		(duplicate_pad_numbers_are_jumpers no)
		(fp_line
			(start 0.7874 0.4064)
			(end -0.7874 0.4064)
			(stroke
				(width 0.1524)
				(type default)
			)
			(layer "F.SilkS")
		)
		(fp_line
			(start 0.7874 -0.4064)
			(end 0.7874 0.4064)
			(stroke
				(width 0.1524)
				(type default)
			)
			(layer "F.SilkS")
		)
		(fp_line
			(start -0.7874 0.4064)
			(end -0.7874 -0.4064)
			(stroke
				(width 0.1524)
				(type default)
			)
			(layer "F.SilkS")
		)
		(fp_line
			(start -0.7874 -0.4064)
			(end 0.7874 -0.4064)
			(stroke
				(width 0.1524)
				(type default)
			)
			(layer "F.SilkS")
		)
		(fp_poly
			(pts
				(xy -0.508 0.2794) (xy -0.508 0.2286) (xy -0.635 0.2286) (xy -0.635 -0.254) (xy -0.5334 -0.254)
				(xy -0.5334 -0.2794) (xy 0.5334 -0.2794) (xy 0.5334 -0.254) (xy 0.635 -0.254) (xy 0.635 0.254) (xy 0.5334 0.254)
				(xy 0.5334 0.2794)
			)
			(stroke
				(width 0)
				(type default)
			)
			(fill no)
			(layer "F.CrtYd")
		)
		(pad "1" smd rect
			(at 0.40005 0 180)
			(size 0.4572 0.508)
			(layers "F.Cu" "F.Mask" "F.Paste")
			(net "PSU4_RETURN")
		)
		(pad "2" smd rect
			(at -0.40005 0 180)
			(size 0.4572 0.508)
			(layers "F.Cu" "F.Mask" "F.Paste")
			(net "GND")
		)
	)
	(footprint ""
		(layer "F.Cu")
		(at 50.217578 -84.273644 180)
		(property "Reference" "CE4"
			(at 1.809242 -5.224018 0)
			(unlocked yes)
			(layer "F.SilkS")
			(effects
				(font
					(size 0.7874 0.5842)
					(thickness 0.1524)
				)
				(justify left)
			)
		)
		(property "Value" ""
			(at 0 0 180)
			(layer "F.Fab")
			(effects
				(font
					(size 1.27 1.27)
				)
			)
		)
		(duplicate_pad_numbers_are_jumpers no)
		(fp_line
			(start 0 -4.2672)
			(end 0 4.2672)
			(stroke
				(width 0.1524)
				(type default)
			)
			(layer "F.SilkS")
		)
		(fp_circle
			(center 0 0)
			(end -4.2672 0)
			(stroke
				(width 0.1524)
				(type default)
			)
			(fill no)
			(layer "F.SilkS")
		)
		(fp_poly
			(pts
				(arc
					(start 0 -4.2672)
					(mid 4.2672 0)
					(end 0 4.2672)
				)
			)
			(stroke
				(width 0)
				(type default)
			)
			(fill yes)
			(layer "F.SilkS")
		)
		(fp_poly
			(pts
				(xy -2.5146 -0.762) (xy -0.9906 -0.762) (xy -0.9906 0.762) (xy -2.5146 0.762)
			)
			(stroke
				(width 0)
				(type default)
			)
			(fill no)
			(layer "B.CrtYd")
		)
		(fp_poly
			(pts
				(arc
					(start 1.7526 0.762)
					(mid 2.291415 -0.538815)
					(end 0.9906 0)
				)
				(arc
					(start 0.9906 0.0254)
					(mid 1.206345 0.546255)
					(end 1.7272 0.762)
				)
			)
			(stroke
				(width 0)
				(type default)
			)
			(fill no)
			(layer "B.CrtYd")
		)
		(fp_poly
			(pts
				(arc
					(start -4.2672 0)
					(mid 4.2672 0)
					(end -4.2672 0)
				)
			)
			(stroke
				(width 0)
				(type default)
			)
			(fill no)
			(layer "F.CrtYd")
		)
		(fp_circle
			(center 0 0)
			(end -4.2672 0)
			(stroke
				(width 0.1)
				(type default)
			)
			(fill no)
			(layer "F.Fab")
		)
		(fp_text user "+"
			(at -3.604514 -4.129786 180)
			(unlocked yes)
			(layer "F.SilkS")
			(effects
				(font
					(size 1.905 1.4224)
					(thickness 0.1524)
				)
				(justify left)
			)
		)
		(fp_text user "+"
			(at -5.6642 -0.34925 180)
			(unlocked yes)
			(layer "F.Fab")
			(effects
				(font
					(size 1.905 1.4224)
					(thickness 0.000001)
				)
				(justify left)
			)
		)
		(pad "1" thru_hole rect
			(at -1.75006 0 180)
			(size 1.397 1.397)
			(drill 0.9144)
			(layers "*.Cu" "*.Mask")
			(remove_unused_layers no)
			(net "P12V")
			(clearance 0.0127)
			(thermal_gap 0.0127)
			(padstack
				(mode front_inner_back)
				(layer "Inner"
					(shape circle)
					(size 1.397 1.397)
					(clearance 0.0127)
				)
				(layer "B.Cu"
					(shape rect)
					(size 1.397 1.397)
					(clearance 0.0127)
				)
			)
		)
		(pad "2" thru_hole circle
			(at 1.75006 0 180)
			(size 1.397 1.397)
			(drill 0.9144)
			(layers "*.Cu" "*.Mask")
			(remove_unused_layers no)
			(net "GND")
			(clearance 0.0127)
			(thermal_gap 0.0127)
		)
	)
	(footprint ""
		(layer "F.Cu")
		(at 25.874472 -367.771426 180)
		(property "Reference" "R53"
			(at 3.856228 0.385064 0)
			(unlocked yes)
			(layer "F.SilkS")
			(effects
				(font
					(size 0.7874 0.5842)
					(thickness 0.1524)
				)
				(justify left)
			)
		)
		(property "Value" ""
			(at 0 0 180)
			(layer "F.Fab")
			(effects
				(font
					(size 1.27 1.27)
				)
			)
		)
		(duplicate_pad_numbers_are_jumpers no)
		(fp_line
			(start 0.7874 0.4064)
			(end -0.7874 0.4064)
			(stroke
				(width 0.1524)
				(type default)
			)
			(layer "F.SilkS")
		)
		(fp_line
			(start 0.7874 -0.4064)
			(end 0.7874 0.4064)
			(stroke
				(width 0.1524)
				(type default)
			)
			(layer "F.SilkS")
		)
		(fp_line
			(start -0.7874 0.4064)
			(end -0.7874 -0.4064)
			(stroke
				(width 0.1524)
				(type default)
			)
			(layer "F.SilkS")
		)
		(fp_line
			(start -0.7874 -0.4064)
			(end 0.7874 -0.4064)
			(stroke
				(width 0.1524)
				(type default)
			)
			(layer "F.SilkS")
		)
		(fp_poly
			(pts
				(xy -0.508 0.2794) (xy -0.508 0.2286) (xy -0.635 0.2286) (xy -0.635 -0.254) (xy -0.5334 -0.254)
				(xy -0.5334 -0.2794) (xy 0.5334 -0.2794) (xy 0.5334 -0.254) (xy 0.635 -0.254) (xy 0.635 0.254) (xy 0.5334 0.254)
				(xy 0.5334 0.2794)
			)
			(stroke
				(width 0)
				(type default)
			)
			(fill no)
			(layer "F.CrtYd")
		)
		(pad "1" smd rect
			(at 0.40005 0 180)
			(size 0.4572 0.508)
			(layers "F.Cu" "F.Mask" "F.Paste")
			(net "GND")
		)
		(pad "2" smd rect
			(at -0.40005 0 180)
			(size 0.4572 0.508)
			(layers "F.Cu" "F.Mask" "F.Paste")
			(net "PSU5_PS_ON_N")
		)
	)
	(footprint ""
		(layer "F.Cu")
		(at 11.444224 -461.694022)
		(property "Reference" "J20"
			(at -5.522214 -4.48056 0)
			(unlocked yes)
			(layer "F.SilkS")
			(effects
				(font
					(size 0.7874 0.5842)
					(thickness 0.1524)
				)
				(justify left)
			)
		)
		(property "Value" ""
			(at 0 0 0)
			(layer "F.Fab")
			(effects
				(font
					(size 1.27 1.27)
				)
			)
		)
		(duplicate_pad_numbers_are_jumpers no)
		(fp_line
			(start -8.949944 17.100042)
			(end -8.949944 20.699984)
			(stroke
				(width 0.1524)
				(type default)
			)
			(layer "F.SilkS")
		)
		(fp_line
			(start -8.949944 20.699984)
			(end -7.349998 20.699984)
			(stroke
				(width 0.1524)
				(type default)
			)
			(layer "F.SilkS")
		)
		(fp_line
			(start -7.349998 -3.299968)
			(end 2.450084 -3.299968)
			(stroke
				(width 0.1524)
				(type default)
			)
			(layer "F.SilkS")
		)
		(fp_line
			(start -7.349998 -2.899918)
			(end 2.450084 -2.899918)
			(stroke
				(width 0.1524)
				(type default)
			)
			(layer "F.SilkS")
		)
		(fp_line
			(start -7.349998 17.100042)
			(end -8.949944 17.100042)
			(stroke
				(width 0.1524)
				(type default)
			)
			(layer "F.SilkS")
		)
		(fp_line
			(start -7.349998 40.699944)
			(end -7.349998 -3.299968)
			(stroke
				(width 0.1524)
				(type default)
			)
			(layer "F.SilkS")
		)
		(fp_line
			(start -7.349998 41.099994)
			(end -7.349998 40.699944)
			(stroke
				(width 0.1524)
				(type default)
			)
			(layer "F.SilkS")
		)
		(fp_line
			(start 2.450084 -3.299968)
			(end 2.450084 -2.899918)
			(stroke
				(width 0.1524)
				(type default)
			)
			(layer "F.SilkS")
		)
		(fp_line
			(start 2.450084 -2.899918)
			(end 2.450084 40.699944)
			(stroke
				(width 0.1524)
				(type default)
			)
			(layer "F.SilkS")
		)
		(fp_line
			(start 2.450084 40.699944)
			(end -7.349998 40.699944)
			(stroke
				(width 0.1524)
				(type default)
			)
			(layer "F.SilkS")
		)
		(fp_line
			(start 2.450084 40.699944)
			(end 2.450084 41.099994)
			(stroke
				(width 0.1524)
				(type default)
			)
			(layer "F.SilkS")
		)
		(fp_line
			(start 2.450084 41.099994)
			(end -7.349998 41.099994)
			(stroke
				(width 0.1524)
				(type default)
			)
			(layer "F.SilkS")
		)
		(fp_poly
			(pts
				(xy 0.042418 -5.091176) (xy -1.227582 -5.091176) (xy -0.567182 -3.567176)
			)
			(stroke
				(width 0)
				(type default)
			)
			(fill yes)
			(layer "F.SilkS")
		)
		(fp_poly
			(pts
				(xy -7.349998 17.100042) (xy -8.949944 17.100042) (xy -8.949944 20.699984) (xy -7.349998 20.699984)
			)
			(stroke
				(width 0)
				(type default)
			)
			(fill yes)
			(layer "F.SilkS")
		)
		(fp_poly
			(pts
				(xy 1.0414 -1.0414) (xy -6.5278 -1.0414) (xy -6.5532 -1.0414) (xy -6.5532 38.8366) (xy -6.5278 38.8366)
				(xy 1.0414 38.8366)
			)
			(stroke
				(width 0)
				(type default)
			)
			(fill no)
			(layer "B.CrtYd")
		)
		(fp_poly
			(pts
				(xy -8.949944 17.100042) (xy -7.349998 17.100042) (xy -7.349998 -3.299968) (xy 2.450084 -3.299968)
				(xy 2.450084 41.099994) (xy -7.349998 41.099994) (xy -7.349998 20.699984) (xy -8.949944 20.699984)
			)
			(stroke
				(width 0)
				(type default)
			)
			(fill no)
			(layer "F.CrtYd")
		)
		(fp_line
			(start -8.949944 17.100042)
			(end -8.949944 20.699984)
			(stroke
				(width 0.1)
				(type default)
			)
			(layer "F.Fab")
		)
		(fp_line
			(start -8.949944 20.699984)
			(end -7.349998 20.699984)
			(stroke
				(width 0.1)
				(type default)
			)
			(layer "F.Fab")
		)
		(fp_line
			(start -7.349998 -3.299968)
			(end 2.450084 -3.299968)
			(stroke
				(width 0.1)
				(type default)
			)
			(layer "F.Fab")
		)
		(fp_line
			(start -7.349998 -2.899918)
			(end -7.349998 -3.299968)
			(stroke
				(width 0.1)
				(type default)
			)
			(layer "F.Fab")
		)
		(fp_line
			(start -7.349998 -2.899918)
			(end 2.44983 -2.899918)
			(stroke
				(width 0.1)
				(type default)
			)
			(layer "F.Fab")
		)
		(fp_line
			(start -7.349998 17.100042)
			(end -8.949944 17.100042)
			(stroke
				(width 0.1)
				(type default)
			)
			(layer "F.Fab")
		)
		(fp_line
			(start -7.349998 40.699944)
			(end -7.349998 -2.899918)
			(stroke
				(width 0.1)
				(type default)
			)
			(layer "F.Fab")
		)
		(fp_line
			(start -7.349998 41.099994)
			(end -7.349998 40.699944)
			(stroke
				(width 0.1)
				(type default)
			)
			(layer "F.Fab")
		)
		(fp_line
			(start 2.44983 -2.899918)
			(end 2.44983 40.699944)
			(stroke
				(width 0.1)
				(type default)
			)
			(layer "F.Fab")
		)
		(fp_line
			(start 2.44983 40.699944)
			(end -7.349998 40.699944)
			(stroke
				(width 0.1)
				(type default)
			)
			(layer "F.Fab")
		)
		(fp_line
			(start 2.450084 -3.299968)
			(end 2.450084 -2.899918)
			(stroke
				(width 0.1)
				(type default)
			)
			(layer "F.Fab")
		)
		(fp_line
			(start 2.450084 40.699944)
			(end 2.450084 41.099994)
			(stroke
				(width 0.1)
				(type default)
			)
			(layer "F.Fab")
		)
		(fp_line
			(start 2.450084 41.099994)
			(end -7.349998 41.099994)
			(stroke
				(width 0.1)
				(type default)
			)
			(layer "F.Fab")
		)
		(fp_poly
			(pts
				(xy 0.409956 -4.940808) (xy -0.860044 -4.940808) (xy -0.199644 -3.416808)
			)
			(stroke
				(width 0)
				(type default)
			)
			(fill yes)
			(layer "F.Fab")
		)
		(fp_text user "11"
			(at -9.198356 -0.33655 0)
			(unlocked yes)
			(layer "F.SilkS")
			(effects
				(font
					(size 0.7874 0.5842)
					(thickness 0.1524)
				)
				(justify left)
			)
		)
		(fp_text user "20"
			(at -6.240526 42.137076 0)
			(unlocked yes)
			(layer "F.SilkS")
			(effects
				(font
					(size 0.7874 0.5842)
					(thickness 0.1524)
				)
				(justify left)
			)
		)
		(fp_text user "1"
			(at -1.67767 -4.278122 0)
			(unlocked yes)
			(layer "F.SilkS")
			(effects
				(font
					(size 0.7874 0.5842)
					(thickness 0.1524)
				)
				(justify left)
			)
		)
		(fp_text user "10"
			(at -0.358902 42.337482 0)
			(unlocked yes)
			(layer "F.SilkS")
			(effects
				(font
					(size 0.7874 0.5842)
					(thickness 0.1524)
				)
				(justify left)
			)
		)
		(fp_text user "11"
			(at -7.229856 -2.581656 90)
			(unlocked yes)
			(layer "B.SilkS")
			(effects
				(font
					(size 0.7874 0.5842)
					(thickness 0.1524)
				)
				(justify left mirror)
			)
		)
		(fp_text user "20"
			(at -5.506212 40.406574 270)
			(unlocked yes)
			(layer "B.SilkS")
			(effects
				(font
					(size 0.7874 0.5842)
					(thickness 0.1524)
				)
				(justify left mirror)
			)
		)
		(fp_text user "1"
			(at -0.316738 -2.194306 90)
			(unlocked yes)
			(layer "B.SilkS")
			(effects
				(font
					(size 0.7874 0.5842)
					(thickness 0.1524)
				)
				(justify left mirror)
			)
		)
		(fp_text user "10"
			(at -0.15875 40.350948 270)
			(unlocked yes)
			(layer "B.SilkS")
			(effects
				(font
					(size 0.7874 0.5842)
					(thickness 0.1524)
				)
				(justify left mirror)
			)
		)
		(fp_text user "11"
			(at -5.506212 -1.086612 270)
			(unlocked yes)
			(layer "B.Fab")
			(effects
				(font
					(size 0.7874 0.5842)
					(thickness 0.000001)
				)
				(justify left mirror)
			)
		)
		(fp_text user "20"
			(at -5.506212 40.406574 270)
			(unlocked yes)
			(layer "B.Fab")
			(effects
				(font
					(size 0.7874 0.5842)
					(thickness 0.000001)
				)
				(justify left mirror)
			)
		)
		(fp_text user "10"
			(at -0.15875 40.350948 270)
			(unlocked yes)
			(layer "B.Fab")
			(effects
				(font
					(size 0.7874 0.5842)
					(thickness 0.000001)
				)
				(justify left mirror)
			)
		)
		(fp_text user "1"
			(at 0.01905 -1.112012 270)
			(unlocked yes)
			(layer "B.Fab")
			(effects
				(font
					(size 0.7874 0.5842)
					(thickness 0.000001)
				)
				(justify left mirror)
			)
		)
		(fp_text user "20"
			(at -5.506212 41.264332 270)
			(unlocked yes)
			(layer "F.Fab")
			(effects
				(font
					(size 0.7874 0.5842)
					(thickness 0.000001)
				)
				(justify left)
			)
		)
		(fp_text user "11"
			(at -5.455412 -4.713224 270)
			(unlocked yes)
			(layer "F.Fab")
			(effects
				(font
					(size 0.7874 0.5842)
					(thickness 0.000001)
				)
				(justify left)
			)
		)
		(fp_text user "10"
			(at -0.183896 41.102534 270)
			(unlocked yes)
			(layer "F.Fab")
			(effects
				(font
					(size 0.7874 0.5842)
					(thickness 0.000001)
				)
				(justify left)
			)
		)
		(fp_text user "1"
			(at 0.53086 -3.95732 270)
			(unlocked yes)
			(layer "F.Fab")
			(effects
				(font
					(size 0.7874 0.5842)
					(thickness 0.000001)
				)
				(justify left)
			)
		)
		(pad "1" thru_hole rect
			(at 0 0 270)
			(size 1.9558 1.9558)
			(drill 1.4478)
			(layers "*.Cu" "*.Mask")
			(remove_unused_layers no)
			(net "FAN1_TACH")
			(clearance 0)
			(padstack
				(mode front_inner_back)
				(layer "Inner"
					(shape circle)
					(size 1.9558 1.9558)
					(clearance 0)
				)
				(layer "B.Cu"
					(shape rect)
					(size 1.9558 1.9558)
					(clearance 0)
				)
			)
		)
		(pad "2" thru_hole circle
			(at 0 4.19989 270)
			(size 1.9558 1.9558)
			(drill 1.4478)
			(layers "*.Cu" "*.Mask")
			(remove_unused_layers no)
			(net "P12V")
			(clearance 0)
		)
		(pad "3" thru_hole circle
			(at 0 8.400034 270)
			(size 1.9558 1.9558)
			(drill 1.4478)
			(layers "*.Cu" "*.Mask")
			(remove_unused_layers no)
			(net "P12V")
			(clearance 0)
		)
		(pad "4" thru_hole circle
			(at 0 12.599924 270)
			(size 1.9558 1.9558)
			(drill 1.4478)
			(layers "*.Cu" "*.Mask")
			(remove_unused_layers no)
			(net "FAN2_TACH")
			(clearance 0)
		)
		(pad "5" thru_hole circle
			(at 0 16.800068 270)
			(size 1.9558 1.9558)
			(drill 1.4478)
			(layers "*.Cu" "*.Mask")
			(remove_unused_layers no)
			(net "P12V")
			(clearance 0)
		)
		(pad "6" thru_hole circle
			(at 0 20.999958 270)
			(size 1.9558 1.9558)
			(drill 1.4478)
			(layers "*.Cu" "*.Mask")
			(remove_unused_layers no)
			(net "P12V")
			(clearance 0)
		)
		(pad "7" thru_hole circle
			(at 0 25.200102 270)
			(size 1.9558 1.9558)
			(drill 1.4478)
			(layers "*.Cu" "*.Mask")
			(remove_unused_layers no)
			(net "FAN3_TACH")
			(clearance 0)
		)
		(pad "8" thru_hole circle
			(at 0 29.399992 270)
			(size 1.9558 1.9558)
			(drill 1.4478)
			(layers "*.Cu" "*.Mask")
			(remove_unused_layers no)
			(net "P12V")
			(clearance 0)
		)
		(pad "9" thru_hole circle
			(at 0 33.599882 270)
			(size 1.9558 1.9558)
			(drill 1.4478)
			(layers "*.Cu" "*.Mask")
			(remove_unused_layers no)
			(net "P12V")
			(clearance 0)
		)
		(pad "10" thru_hole circle
			(at 0 37.800026 270)
			(size 1.9558 1.9558)
			(drill 1.4478)
			(layers "*.Cu" "*.Mask")
			(remove_unused_layers no)
			(net "FAN4_TACH")
			(clearance 0)
		)
		(pad "11" thru_hole circle
			(at -5.500116 0 270)
			(size 1.9558 1.9558)
			(drill 1.4478)
			(layers "*.Cu" "*.Mask")
			(remove_unused_layers no)
			(net "FAN5_TACH")
			(clearance 0)
		)
		(pad "12" thru_hole circle
			(at -5.500116 4.19989 270)
			(size 1.9558 1.9558)
			(drill 1.4478)
			(layers "*.Cu" "*.Mask")
			(remove_unused_layers no)
			(net "GND")
			(clearance 0)
		)
		(pad "13" thru_hole circle
			(at -5.500116 8.400034 270)
			(size 1.9558 1.9558)
			(drill 1.4478)
			(layers "*.Cu" "*.Mask")
			(remove_unused_layers no)
			(net "GND")
			(clearance 0)
		)
		(pad "14" thru_hole circle
			(at -5.500116 12.599924 270)
			(size 1.9558 1.9558)
			(drill 1.4478)
			(layers "*.Cu" "*.Mask")
			(remove_unused_layers no)
			(net "FAN6_TACH")
			(clearance 0)
		)
		(pad "15" thru_hole circle
			(at -5.500116 16.800068 270)
			(size 1.9558 1.9558)
			(drill 1.4478)
			(layers "*.Cu" "*.Mask")
			(remove_unused_layers no)
			(net "GND")
			(clearance 0)
		)
		(pad "16" thru_hole circle
			(at -5.500116 20.999958 270)
			(size 1.9558 1.9558)
			(drill 1.4478)
			(layers "*.Cu" "*.Mask")
			(remove_unused_layers no)
			(net "GND")
			(clearance 0)
		)
		(pad "17" thru_hole circle
			(at -5.500116 25.200102 270)
			(size 1.9558 1.9558)
			(drill 1.4478)
			(layers "*.Cu" "*.Mask")
			(remove_unused_layers no)
			(net "FAN_PWM")
			(clearance 0)
		)
		(pad "18" thru_hole circle
			(at -5.500116 29.399992 270)
			(size 1.9558 1.9558)
			(drill 1.4478)
			(layers "*.Cu" "*.Mask")
			(remove_unused_layers no)
			(net "GND")
			(clearance 0)
		)
		(pad "19" thru_hole circle
			(at -5.500116 33.599882 270)
			(size 1.9558 1.9558)
			(drill 1.4478)
			(layers "*.Cu" "*.Mask")
			(remove_unused_layers no)
			(net "GND")
			(clearance 0)
		)
		(pad "20" thru_hole circle
			(at -5.500116 37.800026 270)
			(size 1.9558 1.9558)
			(drill 1.4478)
			(layers "*.Cu" "*.Mask")
			(remove_unused_layers no)
			(net "FAN_PWM")
			(clearance 0)
		)
	)
	(footprint ""
		(layer "F.Cu")
		(at 68.607686 -172.135546 90)
		(property "Reference" "C35"
			(at -4.082034 0.060706 90)
			(unlocked yes)
			(layer "F.SilkS")
			(effects
				(font
					(size 0.7874 0.5842)
					(thickness 0.1524)
				)
				(justify left)
			)
		)
		(property "Value" ""
			(at 0 0 90)
			(layer "F.Fab")
			(effects
				(font
					(size 1.27 1.27)
				)
			)
		)
		(duplicate_pad_numbers_are_jumpers no)
		(fp_line
			(start 0.7874 -0.4064)
			(end 0.7874 0.4064)
			(stroke
				(width 0.1524)
				(type default)
			)
			(layer "F.SilkS")
		)
		(fp_line
			(start -0.7874 -0.4064)
			(end 0.7874 -0.4064)
			(stroke
				(width 0.1524)
				(type default)
			)
			(layer "F.SilkS")
		)
		(fp_line
			(start 0 0.381)
			(end 0 -0.381)
			(stroke
				(width 0.1524)
				(type default)
			)
			(layer "F.SilkS")
		)
		(fp_line
			(start 0.7874 0.4064)
			(end -0.7874 0.4064)
			(stroke
				(width 0.1524)
				(type default)
			)
			(layer "F.SilkS")
		)
		(fp_line
			(start -0.7874 0.4064)
			(end -0.7874 -0.4064)
			(stroke
				(width 0.1524)
				(type default)
			)
			(layer "F.SilkS")
		)
		(fp_poly
			(pts
				(xy -0.5334 0.254) (xy -0.635 0.254) (xy -0.635 0.2286) (xy -0.635 -0.254) (xy -0.5334 -0.254) (xy -0.5334 -0.2794)
				(xy 0.5334 -0.2794) (xy 0.5334 -0.254) (xy 0.635 -0.254) (xy 0.635 0.254) (xy 0.5334 0.254) (xy 0.5334 0.2794)
				(xy -0.508 0.2794) (xy -0.5334 0.2794)
			)
			(stroke
				(width 0)
				(type default)
			)
			(fill no)
			(layer "F.CrtYd")
		)
		(pad "1" smd rect
			(at 0.40005 0 90)
			(size 0.4572 0.508)
			(layers "F.Cu" "F.Mask" "F.Paste")
			(net "P12V")
		)
		(pad "2" smd rect
			(at -0.40005 0 90)
			(size 0.4572 0.508)
			(layers "F.Cu" "F.Mask" "F.Paste")
			(net "GND")
		)
	)
	(footprint ""
		(layer "F.Cu")
		(at 39.459154 -111.174022 -90)
		(property "Reference" "R90"
			(at -1.104392 -0.0254 90)
			(unlocked yes)
			(layer "F.SilkS")
			(effects
				(font
					(size 0.7874 0.5842)
					(thickness 0.1524)
				)
				(justify left)
			)
		)
		(property "Value" ""
			(at 0 0 270)
			(layer "F.Fab")
			(effects
				(font
					(size 1.27 1.27)
				)
			)
		)
		(duplicate_pad_numbers_are_jumpers no)
		(fp_line
			(start -0.7874 0.4064)
			(end -0.7874 -0.4064)
			(stroke
				(width 0.1524)
				(type default)
			)
			(layer "F.SilkS")
		)
		(fp_line
			(start 0.7874 0.4064)
			(end -0.7874 0.4064)
			(stroke
				(width 0.1524)
				(type default)
			)
			(layer "F.SilkS")
		)
		(fp_line
			(start -0.7874 -0.4064)
			(end 0.7874 -0.4064)
			(stroke
				(width 0.1524)
				(type default)
			)
			(layer "F.SilkS")
		)
		(fp_line
			(start 0.7874 -0.4064)
			(end 0.7874 0.4064)
			(stroke
				(width 0.1524)
				(type default)
			)
			(layer "F.SilkS")
		)
		(fp_poly
			(pts
				(xy -0.508 0.2794) (xy -0.508 0.2286) (xy -0.635 0.2286) (xy -0.635 -0.254) (xy -0.5334 -0.254)
				(xy -0.5334 -0.2794) (xy 0.5334 -0.2794) (xy 0.5334 -0.254) (xy 0.635 -0.254) (xy 0.635 0.254) (xy 0.5334 0.254)
				(xy 0.5334 0.2794)
			)
			(stroke
				(width 0)
				(type default)
			)
			(fill no)
			(layer "F.CrtYd")
		)
		(pad "1" smd rect
			(at 0.40005 0 270)
			(size 0.4572 0.508)
			(layers "F.Cu" "F.Mask" "F.Paste")
			(net "PSU2_REMOTE_P")
		)
		(pad "2" smd rect
			(at -0.40005 0 270)
			(size 0.4572 0.508)
			(layers "F.Cu" "F.Mask" "F.Paste")
			(net "PSU2_REMOTE_R_P")
		)
	)
	(footprint ""
		(layer "F.Cu")
		(at 50.083466 -482.70668 180)
		(property "Reference" "CE21"
			(at -4.321048 2.407666 0)
			(unlocked yes)
			(layer "F.SilkS")
			(effects
				(font
					(size 0.7874 0.5842)
					(thickness 0.1524)
				)
				(justify left)
			)
		)
		(property "Value" ""
			(at 0 0 180)
			(layer "F.Fab")
			(effects
				(font
					(size 1.27 1.27)
				)
			)
		)
		(duplicate_pad_numbers_are_jumpers no)
		(fp_line
			(start 0 -4.2672)
			(end 0 4.2672)
			(stroke
				(width 0.1524)
				(type default)
			)
			(layer "F.SilkS")
		)
		(fp_circle
			(center 0 0)
			(end -4.2672 0)
			(stroke
				(width 0.1524)
				(type default)
			)
			(fill no)
			(layer "F.SilkS")
		)
		(fp_poly
			(pts
				(arc
					(start 0 -4.2672)
					(mid 4.2672 0)
					(end 0 4.2672)
				)
			)
			(stroke
				(width 0)
				(type default)
			)
			(fill yes)
			(layer "F.SilkS")
		)
		(fp_poly
			(pts
				(xy -2.5146 -0.762) (xy -0.9906 -0.762) (xy -0.9906 0.762) (xy -2.5146 0.762)
			)
			(stroke
				(width 0)
				(type default)
			)
			(fill no)
			(layer "B.CrtYd")
		)
		(fp_poly
			(pts
				(arc
					(start 1.7526 0.762)
					(mid 2.291415 -0.538815)
					(end 0.9906 0)
				)
				(arc
					(start 0.9906 0.0254)
					(mid 1.206345 0.546255)
					(end 1.7272 0.762)
				)
			)
			(stroke
				(width 0)
				(type default)
			)
			(fill no)
			(layer "B.CrtYd")
		)
		(fp_poly
			(pts
				(arc
					(start -4.2672 0)
					(mid 4.2672 0)
					(end -4.2672 0)
				)
			)
			(stroke
				(width 0)
				(type default)
			)
			(fill no)
			(layer "F.CrtYd")
		)
		(fp_circle
			(center 0 0)
			(end -4.2672 0)
			(stroke
				(width 0.1)
				(type default)
			)
			(fill no)
			(layer "F.Fab")
		)
		(fp_text user "+"
			(at -5.960364 -0.43053 180)
			(unlocked yes)
			(layer "F.SilkS")
			(effects
				(font
					(size 1.905 1.4224)
					(thickness 0.1524)
				)
				(justify left)
			)
		)
		(fp_text user "+"
			(at -5.6642 -0.34925 180)
			(unlocked yes)
			(layer "F.Fab")
			(effects
				(font
					(size 1.905 1.4224)
					(thickness 0.000001)
				)
				(justify left)
			)
		)
		(pad "1" thru_hole rect
			(at -1.75006 0 180)
			(size 1.397 1.397)
			(drill 0.9144)
			(layers "*.Cu" "*.Mask")
			(remove_unused_layers no)
			(net "P12V")
			(clearance 0.0127)
			(thermal_gap 0.0127)
			(padstack
				(mode front_inner_back)
				(layer "Inner"
					(shape circle)
					(size 1.397 1.397)
					(clearance 0.0127)
				)
				(layer "B.Cu"
					(shape rect)
					(size 1.397 1.397)
					(clearance 0.0127)
				)
			)
		)
		(pad "2" thru_hole circle
			(at 1.75006 0 180)
			(size 1.397 1.397)
			(drill 0.9144)
			(layers "*.Cu" "*.Mask")
			(remove_unused_layers no)
			(net "GND")
			(clearance 0.0127)
			(thermal_gap 0.0127)
		)
	)
	(footprint ""
		(layer "F.Cu")
		(at 20.388326 -177.804572 -90)
		(property "Reference" "R158"
			(at 1.054354 4.446778 90)
			(unlocked yes)
			(layer "F.SilkS")
			(effects
				(font
					(size 0.7874 0.5842)
					(thickness 0.1524)
				)
				(justify left)
			)
		)
		(property "Value" ""
			(at 0 0 270)
			(layer "F.Fab")
			(effects
				(font
					(size 1.27 1.27)
				)
			)
		)
		(duplicate_pad_numbers_are_jumpers no)
		(fp_line
			(start -0.7874 0.4064)
			(end -0.7874 -0.4064)
			(stroke
				(width 0.1524)
				(type default)
			)
			(layer "F.SilkS")
		)
		(fp_line
			(start 0.7874 0.4064)
			(end -0.7874 0.4064)
			(stroke
				(width 0.1524)
				(type default)
			)
			(layer "F.SilkS")
		)
		(fp_line
			(start -0.7874 -0.4064)
			(end 0.7874 -0.4064)
			(stroke
				(width 0.1524)
				(type default)
			)
			(layer "F.SilkS")
		)
		(fp_line
			(start 0.7874 -0.4064)
			(end 0.7874 0.4064)
			(stroke
				(width 0.1524)
				(type default)
			)
			(layer "F.SilkS")
		)
		(fp_poly
			(pts
				(xy -0.508 0.2794) (xy -0.508 0.2286) (xy -0.635 0.2286) (xy -0.635 -0.254) (xy -0.5334 -0.254)
				(xy -0.5334 -0.2794) (xy 0.5334 -0.2794) (xy 0.5334 -0.254) (xy 0.635 -0.254) (xy 0.635 0.254) (xy 0.5334 0.254)
				(xy 0.5334 0.2794)
			)
			(stroke
				(width 0)
				(type default)
			)
			(fill no)
			(layer "F.CrtYd")
		)
		(pad "1" smd rect
			(at 0.40005 0 270)
			(size 0.4572 0.508)
			(layers "F.Cu" "F.Mask" "F.Paste")
			(net "P12V")
		)
		(pad "2" smd rect
			(at -0.40005 0 270)
			(size 0.4572 0.508)
			(layers "F.Cu" "F.Mask" "F.Paste")
			(net "N42263600")
		)
	)
	(footprint ""
		(layer "F.Cu")
		(at 26.068274 -187.950348)
		(property "Reference" "R71"
			(at -3.997198 0.128524 0)
			(unlocked yes)
			(layer "F.SilkS")
			(effects
				(font
					(size 0.7874 0.5842)
					(thickness 0.1524)
				)
				(justify left)
			)
		)
		(property "Value" ""
			(at 0 0 0)
			(layer "F.Fab")
			(effects
				(font
					(size 1.27 1.27)
				)
			)
		)
		(duplicate_pad_numbers_are_jumpers no)
		(fp_line
			(start -0.7874 -0.4064)
			(end 0.7874 -0.4064)
			(stroke
				(width 0.1524)
				(type default)
			)
			(layer "F.SilkS")
		)
		(fp_line
			(start -0.7874 0.4064)
			(end -0.7874 -0.4064)
			(stroke
				(width 0.1524)
				(type default)
			)
			(layer "F.SilkS")
		)
		(fp_line
			(start 0.7874 -0.4064)
			(end 0.7874 0.4064)
			(stroke
				(width 0.1524)
				(type default)
			)
			(layer "F.SilkS")
		)
		(fp_line
			(start 0.7874 0.4064)
			(end -0.7874 0.4064)
			(stroke
				(width 0.1524)
				(type default)
			)
			(layer "F.SilkS")
		)
		(fp_poly
			(pts
				(xy -0.508 0.2794) (xy -0.508 0.2286) (xy -0.635 0.2286) (xy -0.635 -0.254) (xy -0.5334 -0.254)
				(xy -0.5334 -0.2794) (xy 0.5334 -0.2794) (xy 0.5334 -0.254) (xy 0.635 -0.254) (xy 0.635 0.254) (xy 0.5334 0.254)
				(xy 0.5334 0.2794)
			)
			(stroke
				(width 0)
				(type default)
			)
			(fill no)
			(layer "F.CrtYd")
		)
		(pad "1" smd rect
			(at 0.40005 0)
			(size 0.4572 0.508)
			(layers "F.Cu" "F.Mask" "F.Paste")
			(net "PSU3_PS_KILL")
		)
		(pad "2" smd rect
			(at -0.40005 0)
			(size 0.4572 0.508)
			(layers "F.Cu" "F.Mask" "F.Paste")
			(net "GND")
		)
	)
	(footprint ""
		(layer "F.Cu")
		(at 39.858188 -287.573212 180)
		(property "Reference" "R15"
			(at -1.140714 0.062738 0)
			(unlocked yes)
			(layer "F.SilkS")
			(effects
				(font
					(size 0.7874 0.5842)
					(thickness 0.1524)
				)
				(justify left)
			)
		)
		(property "Value" ""
			(at 0 0 180)
			(layer "F.Fab")
			(effects
				(font
					(size 1.27 1.27)
				)
			)
		)
		(duplicate_pad_numbers_are_jumpers no)
		(fp_line
			(start 0.7874 0.4064)
			(end -0.7874 0.4064)
			(stroke
				(width 0.1524)
				(type default)
			)
			(layer "F.SilkS")
		)
		(fp_line
			(start 0.7874 -0.4064)
			(end 0.7874 0.4064)
			(stroke
				(width 0.1524)
				(type default)
			)
			(layer "F.SilkS")
		)
		(fp_line
			(start -0.7874 0.4064)
			(end -0.7874 -0.4064)
			(stroke
				(width 0.1524)
				(type default)
			)
			(layer "F.SilkS")
		)
		(fp_line
			(start -0.7874 -0.4064)
			(end 0.7874 -0.4064)
			(stroke
				(width 0.1524)
				(type default)
			)
			(layer "F.SilkS")
		)
		(fp_poly
			(pts
				(xy -0.508 0.2794) (xy -0.508 0.2286) (xy -0.635 0.2286) (xy -0.635 -0.254) (xy -0.5334 -0.254)
				(xy -0.5334 -0.2794) (xy 0.5334 -0.2794) (xy 0.5334 -0.254) (xy 0.635 -0.254) (xy 0.635 0.254) (xy 0.5334 0.254)
				(xy 0.5334 0.2794)
			)
			(stroke
				(width 0)
				(type default)
			)
			(fill no)
			(layer "F.CrtYd")
		)
		(pad "1" smd rect
			(at 0.40005 0 180)
			(size 0.4572 0.508)
			(layers "F.Cu" "F.Mask" "F.Paste")
			(net "PSU4_REMOTE_P")
		)
		(pad "2" smd rect
			(at -0.40005 0 180)
			(size 0.4572 0.508)
			(layers "F.Cu" "F.Mask" "F.Paste")
			(net "P12V")
		)
	)
	(footprint ""
		(layer "F.Cu")
		(at 13.964666 -70.993 -90)
		(property "Reference" "J23"
			(at -4.44754 5.76199 0)
			(unlocked yes)
			(layer "F.SilkS")
			(effects
				(font
					(size 0.7874 0.5842)
					(thickness 0.1524)
				)
				(justify left)
			)
		)
		(property "Value" ""
			(at 0 0 270)
			(layer "F.Fab")
			(effects
				(font
					(size 1.27 1.27)
				)
			)
		)
		(duplicate_pad_numbers_are_jumpers no)
		(fp_line
			(start -3.370072 12.830048)
			(end -3.370072 -3.81)
			(stroke
				(width 0.1524)
				(type default)
			)
			(layer "F.SilkS")
		)
		(fp_line
			(start 12.260072 12.830048)
			(end -3.370072 12.830048)
			(stroke
				(width 0.1524)
				(type default)
			)
			(layer "F.SilkS")
		)
		(fp_line
			(start -3.370072 -3.81)
			(end 12.260072 -3.81)
			(stroke
				(width 0.1524)
				(type default)
			)
			(layer "F.SilkS")
		)
		(fp_line
			(start 12.260072 -3.81)
			(end 12.260072 12.830048)
			(stroke
				(width 0.1524)
				(type default)
			)
			(layer "F.SilkS")
		)
		(fp_poly
			(pts
				(xy -3.560064 -0.233934) (xy -4.459224 0.215646) (xy -4.459224 -0.683514)
			)
			(stroke
				(width 0)
				(type default)
			)
			(fill yes)
			(layer "F.SilkS")
		)
		(fp_poly
			(pts
				(xy -0.762 0.762) (xy 8.382 0.762) (xy 8.382 -1.8034) (xy 9.652 -1.8034) (xy 9.652 -3.302) (xy 0.508 -3.302)
				(xy 0.508 -0.762) (xy -0.762 -0.762)
			)
			(stroke
				(width 0)
				(type default)
			)
			(fill no)
			(layer "B.CrtYd")
		)
		(fp_poly
			(pts
				(arc
					(start -1.27 4.4196)
					(mid -1.27 8.2804)
					(end -1.27 4.4196)
				)
			)
			(stroke
				(width 0)
				(type default)
			)
			(fill no)
			(layer "B.CrtYd")
		)
		(fp_poly
			(pts
				(arc
					(start 10.16 4.4196)
					(mid 10.16 8.2804)
					(end 10.16 4.4196)
				)
			)
			(stroke
				(width 0)
				(type default)
			)
			(fill no)
			(layer "B.CrtYd")
		)
		(fp_poly
			(pts
				(xy -3.370072 12.830048) (xy 12.260072 12.830048) (xy 12.260072 -3.81) (xy -3.370072 -3.81)
			)
			(stroke
				(width 0)
				(type default)
			)
			(fill no)
			(layer "F.CrtYd")
		)
		(fp_line
			(start -3.370072 12.830048)
			(end -3.370072 -3.81)
			(stroke
				(width 0.1)
				(type default)
			)
			(layer "F.Fab")
		)
		(fp_line
			(start 12.260072 12.830048)
			(end -3.370072 12.830048)
			(stroke
				(width 0.1)
				(type default)
			)
			(layer "F.Fab")
		)
		(fp_line
			(start -3.370072 -3.81)
			(end 12.260072 -3.81)
			(stroke
				(width 0.1)
				(type default)
			)
			(layer "F.Fab")
		)
		(fp_line
			(start 12.260072 -3.81)
			(end 12.260072 12.830048)
			(stroke
				(width 0.1)
				(type default)
			)
			(layer "F.Fab")
		)
		(fp_poly
			(pts
				(xy -3.576828 0) (xy -5.0038 0.713486) (xy -5.0038 -0.713486)
			)
			(stroke
				(width 0)
				(type default)
			)
			(fill yes)
			(layer "F.Fab")
		)
		(fp_text user "1"
			(at -4.26085 0.74803 0)
			(unlocked yes)
			(layer "F.SilkS")
			(effects
				(font
					(size 0.7874 0.5842)
					(thickness 0.1524)
				)
			)
		)
		(fp_text user "7"
			(at 12.93241 -0.070866 0)
			(unlocked yes)
			(layer "F.SilkS")
			(effects
				(font
					(size 0.7874 0.5842)
					(thickness 0.1524)
				)
			)
		)
		(fp_text user "2"
			(at -4.078224 -2.544826 0)
			(unlocked yes)
			(layer "F.SilkS")
			(effects
				(font
					(size 0.7874 0.5842)
					(thickness 0.1524)
				)
			)
		)
		(fp_text user "8"
			(at 12.901676 -2.696718 0)
			(unlocked yes)
			(layer "F.SilkS")
			(effects
				(font
					(size 0.7874 0.5842)
					(thickness 0.1524)
				)
			)
		)
		(fp_text user "1"
			(at -1.526286 0.037846 0)
			(unlocked yes)
			(layer "B.SilkS")
			(effects
				(font
					(size 0.7874 0.5842)
					(thickness 0.1524)
				)
				(justify mirror)
			)
		)
		(fp_text user "7"
			(at 9.031732 -0.064516 0)
			(unlocked yes)
			(layer "B.SilkS")
			(effects
				(font
					(size 0.7874 0.5842)
					(thickness 0.1524)
				)
				(justify mirror)
			)
		)
		(fp_text user "8"
			(at 10.25652 -2.445766 0)
			(unlocked yes)
			(layer "B.SilkS")
			(effects
				(font
					(size 0.7874 0.5842)
					(thickness 0.1524)
				)
				(justify mirror)
			)
		)
		(fp_text user "2"
			(at -0.230886 -2.629154 0)
			(unlocked yes)
			(layer "B.SilkS")
			(effects
				(font
					(size 0.7874 0.5842)
					(thickness 0.1524)
				)
				(justify mirror)
			)
		)
		(fp_text user "7"
			(at 8.8138 0.238252 270)
			(unlocked yes)
			(layer "B.Fab")
			(effects
				(font
					(size 0.7874 0.5842)
					(thickness 0.000001)
				)
				(justify mirror)
			)
		)
		(fp_text user "1"
			(at -1.2954 0.085852 270)
			(unlocked yes)
			(layer "B.Fab")
			(effects
				(font
					(size 0.7874 0.5842)
					(thickness 0.000001)
				)
				(justify mirror)
			)
		)
		(fp_text user "8"
			(at 10.0838 -2.403348 270)
			(unlocked yes)
			(layer "B.Fab")
			(effects
				(font
					(size 0.7874 0.5842)
					(thickness 0.000001)
				)
				(justify mirror)
			)
		)
		(fp_text user "2"
			(at 0 -2.581148 270)
			(unlocked yes)
			(layer "B.Fab")
			(effects
				(font
					(size 0.7874 0.5842)
					(thickness 0.000001)
				)
				(justify mirror)
			)
		)
		(fp_text user "7"
			(at 12.7762 -0.091948 270)
			(unlocked yes)
			(layer "F.Fab")
			(effects
				(font
					(size 0.7874 0.5842)
					(thickness 0.000001)
				)
			)
		)
		(fp_text user "1"
			(at -3.9116 -0.930148 270)
			(unlocked yes)
			(layer "F.Fab")
			(effects
				(font
					(size 0.7874 0.5842)
					(thickness 0.000001)
				)
			)
		)
		(fp_text user "2"
			(at -3.9624 -2.428748 270)
			(unlocked yes)
			(layer "F.Fab")
			(effects
				(font
					(size 0.7874 0.5842)
					(thickness 0.000001)
				)
			)
		)
		(fp_text user "8"
			(at 12.7762 -2.555748 270)
			(unlocked yes)
			(layer "F.Fab")
			(effects
				(font
					(size 0.7874 0.5842)
					(thickness 0.000001)
				)
			)
		)
		(pad "" np_thru_hole circle
			(at -1.27 6.35 270)
			(size 3.3528 3.3528)
			(drill 3.3528)
			(layers "*.Cu" "*.Mask")
			(clearance 0.381)
			(thermal_gap 0.381)
		)
		(pad "" np_thru_hole circle
			(at 10.16 6.35 270)
			(size 3.3528 3.3528)
			(drill 3.3528)
			(layers "*.Cu" "*.Mask")
			(clearance 0.381)
			(thermal_gap 0.381)
		)
		(pad "1" thru_hole rect
			(at 0 0 270)
			(size 1.397 1.397)
			(drill 0.9906)
			(layers "*.Cu" "*.Mask")
			(remove_unused_layers no)
			(net "UART_RTS_P5_L_N")
			(clearance 0.0508)
			(thermal_gap 0.0508)
			(padstack
				(mode front_inner_back)
				(layer "Inner"
					(shape circle)
					(size 1.397 1.397)
					(clearance 0.0508)
				)
				(layer "B.Cu"
					(shape rect)
					(size 1.397 1.397)
					(clearance 0.0508)
				)
			)
		)
		(pad "2" thru_hole circle
			(at 1.27 -2.54 270)
			(size 1.397 1.397)
			(drill 0.9906)
			(layers "*.Cu" "*.Mask")
			(remove_unused_layers no)
			(net "UART_DSR_P5_L_N")
			(clearance 0.0508)
			(thermal_gap 0.0508)
		)
		(pad "3" thru_hole circle
			(at 2.54 0 270)
			(size 1.397 1.397)
			(drill 0.9906)
			(layers "*.Cu" "*.Mask")
			(remove_unused_layers no)
			(net "UART_RX_P5_L")
			(clearance 0.0508)
			(thermal_gap 0.0508)
		)
		(pad "4" thru_hole circle
			(at 3.81 -2.54 270)
			(size 1.397 1.397)
			(drill 0.9906)
			(layers "*.Cu" "*.Mask")
			(remove_unused_layers no)
			(net "UART_RI_P5_L_N")
			(clearance 0.0508)
			(thermal_gap 0.0508)
		)
		(pad "5" thru_hole circle
			(at 5.08 0 270)
			(size 1.397 1.397)
			(drill 0.9906)
			(layers "*.Cu" "*.Mask")
			(remove_unused_layers no)
			(net "GND")
			(clearance 0.0508)
			(thermal_gap 0.0508)
		)
		(pad "6" thru_hole circle
			(at 6.35 -2.54 270)
			(size 1.397 1.397)
			(drill 0.9906)
			(layers "*.Cu" "*.Mask")
			(remove_unused_layers no)
			(net "UART_TX_P5_L")
			(clearance 0.0508)
			(thermal_gap 0.0508)
		)
		(pad "7" thru_hole circle
			(at 7.62 0 270)
			(size 1.397 1.397)
			(drill 0.9906)
			(layers "*.Cu" "*.Mask")
			(remove_unused_layers no)
			(net "UART_DTR_P5_L_N")
			(clearance 0.0508)
			(thermal_gap 0.0508)
		)
		(pad "8" thru_hole circle
			(at 8.89 -2.54 270)
			(size 1.397 1.397)
			(drill 0.9906)
			(layers "*.Cu" "*.Mask")
			(remove_unused_layers no)
			(net "UART_CTS_P5_L_N")
			(clearance 0.0508)
			(thermal_gap 0.0508)
		)
		(zone
			(layers "F.Cu" "B.Cu" "In1.Cu" "In2.Cu" "In3.Cu" "In4.Cu" "In5.Cu" "In6.Cu")
			(hatch none 0.5)
			(connect_pads
				(clearance 0)
			)
			(min_thickness 0.25)
			(keepout
				(tracks not_allowed)
				(vias allowed)
				(pads allowed)
				(copperpour not_allowed)
				(footprints allowed)
			)
			(placement
				(enabled no)
				(sheetname "")
			)
			(fill
				(thermal_gap 0.5)
				(thermal_bridge_width 0.5)
				(island_removal_mode 0)
			)
			(polygon
				(pts
					(arc
						(start 9.697466 -72.263)
						(mid 5.531866 -72.263)
						(end 9.697466 -72.263)
					)
				)
			)
		)
		(zone
			(layers "F.Cu" "B.Cu" "In1.Cu" "In2.Cu" "In3.Cu" "In4.Cu" "In5.Cu" "In6.Cu")
			(hatch none 0.5)
			(connect_pads
				(clearance 0)
			)
			(min_thickness 0.25)
			(keepout
				(tracks not_allowed)
				(vias allowed)
				(pads allowed)
				(copperpour not_allowed)
				(footprints allowed)
			)
			(placement
				(enabled no)
				(sheetname "")
			)
			(fill
				(thermal_gap 0.5)
				(thermal_bridge_width 0.5)
				(island_removal_mode 0)
			)
			(polygon
				(pts
					(arc
						(start 9.697466 -60.833)
						(mid 5.531866 -60.833)
						(end 9.697466 -60.833)
					)
				)
			)
		)
	)
	(footprint ""
		(layer "F.Cu")
		(at 18.264886 -330.45527 -90)
		(property "Reference" "R34"
			(at 3.685032 -0.234188 90)
			(unlocked yes)
			(layer "F.SilkS")
			(effects
				(font
					(size 0.7874 0.5842)
					(thickness 0.1524)
				)
				(justify left)
			)
		)
		(property "Value" ""
			(at 0 0 270)
			(layer "F.Fab")
			(effects
				(font
					(size 1.27 1.27)
				)
			)
		)
		(duplicate_pad_numbers_are_jumpers no)
		(fp_line
			(start -0.7874 0.4064)
			(end -0.7874 -0.4064)
			(stroke
				(width 0.1524)
				(type default)
			)
			(layer "F.SilkS")
		)
		(fp_line
			(start 0.7874 0.4064)
			(end -0.7874 0.4064)
			(stroke
				(width 0.1524)
				(type default)
			)
			(layer "F.SilkS")
		)
		(fp_line
			(start -0.7874 -0.4064)
			(end 0.7874 -0.4064)
			(stroke
				(width 0.1524)
				(type default)
			)
			(layer "F.SilkS")
		)
		(fp_line
			(start 0.7874 -0.4064)
			(end 0.7874 0.4064)
			(stroke
				(width 0.1524)
				(type default)
			)
			(layer "F.SilkS")
		)
		(fp_poly
			(pts
				(xy -0.508 0.2794) (xy -0.508 0.2286) (xy -0.635 0.2286) (xy -0.635 -0.254) (xy -0.5334 -0.254)
				(xy -0.5334 -0.2794) (xy 0.5334 -0.2794) (xy 0.5334 -0.254) (xy 0.635 -0.254) (xy 0.635 0.254) (xy 0.5334 0.254)
				(xy 0.5334 0.2794)
			)
			(stroke
				(width 0)
				(type default)
			)
			(fill no)
			(layer "F.CrtYd")
		)
		(pad "1" smd rect
			(at 0.40005 0 270)
			(size 0.4572 0.508)
			(layers "F.Cu" "F.Mask" "F.Paste")
			(net "P3V3")
		)
		(pad "2" smd rect
			(at -0.40005 0 270)
			(size 0.4572 0.508)
			(layers "F.Cu" "F.Mask" "F.Paste")
			(net "FRU_A0")
		)
	)
	(footprint ""
		(layer "F.Cu")
		(at 75.151996 -241.518694 -90)
		(property "Reference" "C38"
			(at 0.73406 -3.85445 90)
			(unlocked yes)
			(layer "F.SilkS")
			(effects
				(font
					(size 0.7874 0.5842)
					(thickness 0.1524)
				)
				(justify left)
			)
		)
		(property "Value" ""
			(at 0 0 270)
			(layer "F.Fab")
			(effects
				(font
					(size 1.27 1.27)
				)
			)
		)
		(duplicate_pad_numbers_are_jumpers no)
		(fp_line
			(start -0.7874 0.4064)
			(end -0.7874 -0.4064)
			(stroke
				(width 0.1524)
				(type default)
			)
			(layer "F.SilkS")
		)
		(fp_line
			(start 0.7874 0.4064)
			(end -0.7874 0.4064)
			(stroke
				(width 0.1524)
				(type default)
			)
			(layer "F.SilkS")
		)
		(fp_line
			(start 0 0.381)
			(end 0 -0.381)
			(stroke
				(width 0.1524)
				(type default)
			)
			(layer "F.SilkS")
		)
		(fp_line
			(start -0.7874 -0.4064)
			(end 0.7874 -0.4064)
			(stroke
				(width 0.1524)
				(type default)
			)
			(layer "F.SilkS")
		)
		(fp_line
			(start 0.7874 -0.4064)
			(end 0.7874 0.4064)
			(stroke
				(width 0.1524)
				(type default)
			)
			(layer "F.SilkS")
		)
		(fp_poly
			(pts
				(xy -0.5334 0.254) (xy -0.635 0.254) (xy -0.635 0.2286) (xy -0.635 -0.254) (xy -0.5334 -0.254) (xy -0.5334 -0.2794)
				(xy 0.5334 -0.2794) (xy 0.5334 -0.254) (xy 0.635 -0.254) (xy 0.635 0.254) (xy 0.5334 0.254) (xy 0.5334 0.2794)
				(xy -0.508 0.2794) (xy -0.5334 0.2794)
			)
			(stroke
				(width 0)
				(type default)
			)
			(fill no)
			(layer "F.CrtYd")
		)
		(pad "1" smd rect
			(at 0.40005 0 270)
			(size 0.4572 0.508)
			(layers "F.Cu" "F.Mask" "F.Paste")
			(net "P12V")
		)
		(pad "2" smd rect
			(at -0.40005 0 270)
			(size 0.4572 0.508)
			(layers "F.Cu" "F.Mask" "F.Paste")
			(net "GND")
		)
	)
	(footprint ""
		(layer "F.Cu")
		(at 14.923008 -330.497434 -90)
		(property "Reference" "R35"
			(at 3.685032 -0.234188 90)
			(unlocked yes)
			(layer "F.SilkS")
			(effects
				(font
					(size 0.7874 0.5842)
					(thickness 0.1524)
				)
				(justify left)
			)
		)
		(property "Value" ""
			(at 0 0 270)
			(layer "F.Fab")
			(effects
				(font
					(size 1.27 1.27)
				)
			)
		)
		(duplicate_pad_numbers_are_jumpers no)
		(fp_line
			(start -0.7874 0.4064)
			(end -0.7874 -0.4064)
			(stroke
				(width 0.1524)
				(type default)
			)
			(layer "F.SilkS")
		)
		(fp_line
			(start 0.7874 0.4064)
			(end -0.7874 0.4064)
			(stroke
				(width 0.1524)
				(type default)
			)
			(layer "F.SilkS")
		)
		(fp_line
			(start -0.7874 -0.4064)
			(end 0.7874 -0.4064)
			(stroke
				(width 0.1524)
				(type default)
			)
			(layer "F.SilkS")
		)
		(fp_line
			(start 0.7874 -0.4064)
			(end 0.7874 0.4064)
			(stroke
				(width 0.1524)
				(type default)
			)
			(layer "F.SilkS")
		)
		(fp_poly
			(pts
				(xy -0.508 0.2794) (xy -0.508 0.2286) (xy -0.635 0.2286) (xy -0.635 -0.254) (xy -0.5334 -0.254)
				(xy -0.5334 -0.2794) (xy 0.5334 -0.2794) (xy 0.5334 -0.254) (xy 0.635 -0.254) (xy 0.635 0.254) (xy 0.5334 0.254)
				(xy 0.5334 0.2794)
			)
			(stroke
				(width 0)
				(type default)
			)
			(fill no)
			(layer "F.CrtYd")
		)
		(pad "1" smd rect
			(at 0.40005 0 270)
			(size 0.4572 0.508)
			(layers "F.Cu" "F.Mask" "F.Paste")
			(net "P3V3")
		)
		(pad "2" smd rect
			(at -0.40005 0 270)
			(size 0.4572 0.508)
			(layers "F.Cu" "F.Mask" "F.Paste")
			(net "FRU_A1")
		)
	)
	(footprint ""
		(layer "F.Cu")
		(at 50.284126 -395.548358 180)
		(property "Reference" "CE18"
			(at -3.83413 -2.721864 0)
			(unlocked yes)
			(layer "F.SilkS")
			(effects
				(font
					(size 0.7874 0.5842)
					(thickness 0.1524)
				)
				(justify left)
			)
		)
		(property "Value" ""
			(at 0 0 180)
			(layer "F.Fab")
			(effects
				(font
					(size 1.27 1.27)
				)
			)
		)
		(duplicate_pad_numbers_are_jumpers no)
		(fp_line
			(start 0 -4.2672)
			(end 0 4.2672)
			(stroke
				(width 0.1524)
				(type default)
			)
			(layer "F.SilkS")
		)
		(fp_circle
			(center 0 0)
			(end -4.2672 0)
			(stroke
				(width 0.1524)
				(type default)
			)
			(fill no)
			(layer "F.SilkS")
		)
		(fp_poly
			(pts
				(arc
					(start 0 -4.2672)
					(mid 4.2672 0)
					(end 0 4.2672)
				)
			)
			(stroke
				(width 0)
				(type default)
			)
			(fill yes)
			(layer "F.SilkS")
		)
		(fp_poly
			(pts
				(xy -2.5146 -0.762) (xy -0.9906 -0.762) (xy -0.9906 0.762) (xy -2.5146 0.762)
			)
			(stroke
				(width 0)
				(type default)
			)
			(fill no)
			(layer "B.CrtYd")
		)
		(fp_poly
			(pts
				(arc
					(start 1.7526 0.762)
					(mid 2.291415 -0.538815)
					(end 0.9906 0)
				)
				(arc
					(start 0.9906 0.0254)
					(mid 1.206345 0.546255)
					(end 1.7272 0.762)
				)
			)
			(stroke
				(width 0)
				(type default)
			)
			(fill no)
			(layer "B.CrtYd")
		)
		(fp_poly
			(pts
				(arc
					(start -4.2672 0)
					(mid 4.2672 0)
					(end -4.2672 0)
				)
			)
			(stroke
				(width 0)
				(type default)
			)
			(fill no)
			(layer "F.CrtYd")
		)
		(fp_circle
			(center 0 0)
			(end -4.2672 0)
			(stroke
				(width 0.1)
				(type default)
			)
			(fill no)
			(layer "F.Fab")
		)
		(fp_text user "+"
			(at -5.834634 -1.153414 180)
			(unlocked yes)
			(layer "F.SilkS")
			(effects
				(font
					(size 1.905 1.4224)
					(thickness 0.1524)
				)
				(justify left)
			)
		)
		(fp_text user "+"
			(at -5.6642 -0.34925 180)
			(unlocked yes)
			(layer "F.Fab")
			(effects
				(font
					(size 1.905 1.4224)
					(thickness 0.000001)
				)
				(justify left)
			)
		)
		(pad "1" thru_hole rect
			(at -1.75006 0 180)
			(size 1.397 1.397)
			(drill 0.9144)
			(layers "*.Cu" "*.Mask")
			(remove_unused_layers no)
			(net "P12V")
			(clearance 0.0127)
			(thermal_gap 0.0127)
			(padstack
				(mode front_inner_back)
				(layer "Inner"
					(shape circle)
					(size 1.397 1.397)
					(clearance 0.0127)
				)
				(layer "B.Cu"
					(shape rect)
					(size 1.397 1.397)
					(clearance 0.0127)
				)
			)
		)
		(pad "2" thru_hole circle
			(at 1.75006 0 180)
			(size 1.397 1.397)
			(drill 0.9144)
			(layers "*.Cu" "*.Mask")
			(remove_unused_layers no)
			(net "GND")
			(clearance 0.0127)
			(thermal_gap 0.0127)
		)
	)
	(footprint ""
		(layer "F.Cu")
		(at 13.853922 -330.480924 -90)
		(property "Reference" "R39"
			(at 3.685032 -0.234188 90)
			(unlocked yes)
			(layer "F.SilkS")
			(effects
				(font
					(size 0.7874 0.5842)
					(thickness 0.1524)
				)
				(justify left)
			)
		)
		(property "Value" ""
			(at 0 0 270)
			(layer "F.Fab")
			(effects
				(font
					(size 1.27 1.27)
				)
			)
		)
		(duplicate_pad_numbers_are_jumpers no)
		(fp_line
			(start -0.7874 0.4064)
			(end -0.7874 -0.4064)
			(stroke
				(width 0.1524)
				(type default)
			)
			(layer "F.SilkS")
		)
		(fp_line
			(start 0.7874 0.4064)
			(end -0.7874 0.4064)
			(stroke
				(width 0.1524)
				(type default)
			)
			(layer "F.SilkS")
		)
		(fp_line
			(start -0.7874 -0.4064)
			(end 0.7874 -0.4064)
			(stroke
				(width 0.1524)
				(type default)
			)
			(layer "F.SilkS")
		)
		(fp_line
			(start 0.7874 -0.4064)
			(end 0.7874 0.4064)
			(stroke
				(width 0.1524)
				(type default)
			)
			(layer "F.SilkS")
		)
		(fp_poly
			(pts
				(xy -0.508 0.2794) (xy -0.508 0.2286) (xy -0.635 0.2286) (xy -0.635 -0.254) (xy -0.5334 -0.254)
				(xy -0.5334 -0.2794) (xy 0.5334 -0.2794) (xy 0.5334 -0.254) (xy 0.635 -0.254) (xy 0.635 0.254) (xy 0.5334 0.254)
				(xy 0.5334 0.2794)
			)
			(stroke
				(width 0)
				(type default)
			)
			(fill no)
			(layer "F.CrtYd")
		)
		(pad "1" smd rect
			(at 0.40005 0 270)
			(size 0.4572 0.508)
			(layers "F.Cu" "F.Mask" "F.Paste")
			(net "GND")
		)
		(pad "2" smd rect
			(at -0.40005 0 270)
			(size 0.4572 0.508)
			(layers "F.Cu" "F.Mask" "F.Paste")
			(net "FRU_A2")
		)
	)
	(footprint ""
		(layer "F.Cu")
		(at 39.979854 -375.988326 180)
		(property "Reference" "R14"
			(at -2.032762 0.011938 0)
			(unlocked yes)
			(layer "F.SilkS")
			(effects
				(font
					(size 0.7874 0.5842)
					(thickness 0.1524)
				)
				(justify left)
			)
		)
		(property "Value" ""
			(at 0 0 180)
			(layer "F.Fab")
			(effects
				(font
					(size 1.27 1.27)
				)
			)
		)
		(duplicate_pad_numbers_are_jumpers no)
		(fp_line
			(start 0.7874 0.4064)
			(end -0.7874 0.4064)
			(stroke
				(width 0.1524)
				(type default)
			)
			(layer "F.SilkS")
		)
		(fp_line
			(start 0.7874 -0.4064)
			(end 0.7874 0.4064)
			(stroke
				(width 0.1524)
				(type default)
			)
			(layer "F.SilkS")
		)
		(fp_line
			(start -0.7874 0.4064)
			(end -0.7874 -0.4064)
			(stroke
				(width 0.1524)
				(type default)
			)
			(layer "F.SilkS")
		)
		(fp_line
			(start -0.7874 -0.4064)
			(end 0.7874 -0.4064)
			(stroke
				(width 0.1524)
				(type default)
			)
			(layer "F.SilkS")
		)
		(fp_poly
			(pts
				(xy -0.508 0.2794) (xy -0.508 0.2286) (xy -0.635 0.2286) (xy -0.635 -0.254) (xy -0.5334 -0.254)
				(xy -0.5334 -0.2794) (xy 0.5334 -0.2794) (xy 0.5334 -0.254) (xy 0.635 -0.254) (xy 0.635 0.254) (xy 0.5334 0.254)
				(xy 0.5334 0.2794)
			)
			(stroke
				(width 0)
				(type default)
			)
			(fill no)
			(layer "F.CrtYd")
		)
		(pad "1" smd rect
			(at 0.40005 0 180)
			(size 0.4572 0.508)
			(layers "F.Cu" "F.Mask" "F.Paste")
			(net "PSU5_REMOTE_P")
		)
		(pad "2" smd rect
			(at -0.40005 0 180)
			(size 0.4572 0.508)
			(layers "F.Cu" "F.Mask" "F.Paste")
			(net "P12V")
		)
	)
	(footprint ""
		(layer "F.Cu")
		(at 77.999844 -478.300034)
		(property "Reference" "H13"
			(at -3.29692 -5.248656 0)
			(unlocked yes)
			(layer "F.SilkS")
			(effects
				(font
					(size 0.7874 0.5842)
					(thickness 0.1524)
				)
				(justify left)
			)
		)
		(property "Value" ""
			(at 0 0 0)
			(layer "F.Fab")
			(effects
				(font
					(size 1.27 1.27)
				)
			)
		)
		(duplicate_pad_numbers_are_jumpers no)
		(fp_line
			(start -3.4163 0)
			(end -3.4163 -0.4953)
			(stroke
				(width 0.1524)
				(type default)
			)
			(layer "F.SilkS")
		)
		(fp_line
			(start -3.4163 0.4953)
			(end -3.4163 0)
			(stroke
				(width 0.1524)
				(type default)
			)
			(layer "F.SilkS")
		)
		(fp_line
			(start 3.4163 -0.4953)
			(end 3.4163 0.4953)
			(stroke
				(width 0.1524)
				(type default)
			)
			(layer "F.SilkS")
		)
		(fp_arc
			(start -3.4163 -0.4953)
			(mid -2.415689 -2.910989)
			(end 0 -3.9116)
			(stroke
				(width 0.1524)
				(type default)
			)
			(layer "F.SilkS")
		)
		(fp_arc
			(start 0 -3.9116)
			(mid 2.415689 -2.910989)
			(end 3.4163 -0.4953)
			(stroke
				(width 0.1524)
				(type default)
			)
			(layer "F.SilkS")
		)
		(fp_arc
			(start 0 3.9116)
			(mid -2.415689 2.910989)
			(end -3.4163 0.4953)
			(stroke
				(width 0.1524)
				(type default)
			)
			(layer "F.SilkS")
		)
		(fp_arc
			(start 3.4163 0.4953)
			(mid 2.415689 2.910989)
			(end 0 3.9116)
			(stroke
				(width 0.1524)
				(type default)
			)
			(layer "F.SilkS")
		)
		(fp_line
			(start -3.4163 0)
			(end -3.4163 -0.4953)
			(stroke
				(width 0.1524)
				(type default)
			)
			(layer "B.SilkS")
		)
		(fp_line
			(start -3.4163 0.4953)
			(end -3.4163 0)
			(stroke
				(width 0.1524)
				(type default)
			)
			(layer "B.SilkS")
		)
		(fp_line
			(start 3.4163 -0.4953)
			(end 3.4163 0.4953)
			(stroke
				(width 0.1524)
				(type default)
			)
			(layer "B.SilkS")
		)
		(fp_arc
			(start -3.4163 -0.4953)
			(mid -2.415689 -2.910989)
			(end 0 -3.9116)
			(stroke
				(width 0.1524)
				(type default)
			)
			(layer "B.SilkS")
		)
		(fp_arc
			(start 0 -3.9116)
			(mid 2.415689 -2.910989)
			(end 3.4163 -0.4953)
			(stroke
				(width 0.1524)
				(type default)
			)
			(layer "B.SilkS")
		)
		(fp_arc
			(start 0 3.9116)
			(mid -2.415689 2.910989)
			(end -3.4163 0.4953)
			(stroke
				(width 0.1524)
				(type default)
			)
			(layer "B.SilkS")
		)
		(fp_arc
			(start 3.4163 0.4953)
			(mid 2.415689 2.910989)
			(end 0 3.9116)
			(stroke
				(width 0.1524)
				(type default)
			)
			(layer "B.SilkS")
		)
		(fp_poly
			(pts
				(arc
					(start -2.853944 -0.499872)
					(mid 0 -3.353816)
					(end 2.853944 -0.499872)
				)
				(arc
					(start 2.853944 0.499872)
					(mid 0 3.35407)
					(end -2.853944 0.499872)
				)
			)
			(stroke
				(width 0)
				(type default)
			)
			(fill no)
			(layer "B.CrtYd")
		)
		(fp_poly
			(pts
				(arc
					(start -2.853944 -0.499872)
					(mid 0 -3.353816)
					(end 2.853944 -0.499872)
				)
				(arc
					(start 2.853944 0.499872)
					(mid 0 3.35407)
					(end -2.853944 0.499872)
				)
			)
			(stroke
				(width 0)
				(type default)
			)
			(fill no)
			(layer "F.CrtYd")
		)
		(pad "" np_thru_hole oval
			(at 0 0)
			(size 5.207 6.1976)
			(drill oval 5.207 6.1976)
			(layers "*.Cu" "*.Mask")
			(clearance 0.381)
			(thermal_gap 0.381)
		)
		(zone
			(layers "F.Cu" "B.Cu" "In1.Cu" "In2.Cu" "In3.Cu" "In4.Cu" "In5.Cu" "In6.Cu")
			(hatch none 0.5)
			(connect_pads
				(clearance 0)
			)
			(min_thickness 0.25)
			(keepout
				(tracks not_allowed)
				(vias allowed)
				(pads allowed)
				(copperpour not_allowed)
				(footprints allowed)
			)
			(placement
				(enabled no)
				(sheetname "")
			)
			(fill
				(thermal_gap 0.5)
				(thermal_bridge_width 0.5)
				(island_removal_mode 0)
			)
			(polygon
				(pts
					(xy 74.888344 -478.300034)
					(arc
						(start 74.888344 -478.795334)
						(mid 75.799681 -480.995497)
						(end 77.999844 -481.906834)
					)
					(arc
						(start 77.999844 -481.906834)
						(mid 80.200007 -480.995497)
						(end 81.111344 -478.795334)
					)
					(arc
						(start 81.111344 -477.804734)
						(mid 80.200007 -475.604571)
						(end 77.999844 -474.693234)
					)
					(arc
						(start 77.999844 -474.693234)
						(mid 75.799681 -475.604571)
						(end 74.888344 -477.804734)
					)
				)
			)
		)
	)
	(footprint ""
		(layer "F.Cu")
		(at 71.815198 -197.392544 -90)
		(property "Reference" "C31"
			(at 3.603498 -0.336804 90)
			(unlocked yes)
			(layer "F.SilkS")
			(effects
				(font
					(size 0.7874 0.5842)
					(thickness 0.1524)
				)
				(justify left)
			)
		)
		(property "Value" ""
			(at 0 0 270)
			(layer "F.Fab")
			(effects
				(font
					(size 1.27 1.27)
				)
			)
		)
		(duplicate_pad_numbers_are_jumpers no)
		(fp_line
			(start -0.7874 0.4064)
			(end -0.7874 -0.4064)
			(stroke
				(width 0.1524)
				(type default)
			)
			(layer "F.SilkS")
		)
		(fp_line
			(start 0.7874 0.4064)
			(end -0.7874 0.4064)
			(stroke
				(width 0.1524)
				(type default)
			)
			(layer "F.SilkS")
		)
		(fp_line
			(start 0 0.381)
			(end 0 -0.381)
			(stroke
				(width 0.1524)
				(type default)
			)
			(layer "F.SilkS")
		)
		(fp_line
			(start -0.7874 -0.4064)
			(end 0.7874 -0.4064)
			(stroke
				(width 0.1524)
				(type default)
			)
			(layer "F.SilkS")
		)
		(fp_line
			(start 0.7874 -0.4064)
			(end 0.7874 0.4064)
			(stroke
				(width 0.1524)
				(type default)
			)
			(layer "F.SilkS")
		)
		(fp_poly
			(pts
				(xy -0.5334 0.254) (xy -0.635 0.254) (xy -0.635 0.2286) (xy -0.635 -0.254) (xy -0.5334 -0.254) (xy -0.5334 -0.2794)
				(xy 0.5334 -0.2794) (xy 0.5334 -0.254) (xy 0.635 -0.254) (xy 0.635 0.254) (xy 0.5334 0.254) (xy 0.5334 0.2794)
				(xy -0.508 0.2794) (xy -0.5334 0.2794)
			)
			(stroke
				(width 0)
				(type default)
			)
			(fill no)
			(layer "F.CrtYd")
		)
		(pad "1" smd rect
			(at 0.40005 0 270)
			(size 0.4572 0.508)
			(layers "F.Cu" "F.Mask" "F.Paste")
			(net "P12V")
		)
		(pad "2" smd rect
			(at -0.40005 0 270)
			(size 0.4572 0.508)
			(layers "F.Cu" "F.Mask" "F.Paste")
			(net "GND")
		)
	)
	(footprint ""
		(layer "F.Cu")
		(at 77.254354 -18.749772 -90)
		(property "Reference" "C3"
			(at -1.75133 0.09906 90)
			(unlocked yes)
			(layer "F.SilkS")
			(effects
				(font
					(size 0.7874 0.5842)
					(thickness 0.1524)
				)
				(justify left)
			)
		)
		(property "Value" ""
			(at 0 0 270)
			(layer "F.Fab")
			(effects
				(font
					(size 1.27 1.27)
				)
			)
		)
		(duplicate_pad_numbers_are_jumpers no)
		(fp_line
			(start -0.7874 0.4064)
			(end -0.7874 -0.4064)
			(stroke
				(width 0.1524)
				(type default)
			)
			(layer "F.SilkS")
		)
		(fp_line
			(start 0.7874 0.4064)
			(end -0.7874 0.4064)
			(stroke
				(width 0.1524)
				(type default)
			)
			(layer "F.SilkS")
		)
		(fp_line
			(start 0 0.381)
			(end 0 -0.381)
			(stroke
				(width 0.1524)
				(type default)
			)
			(layer "F.SilkS")
		)
		(fp_line
			(start -0.7874 -0.4064)
			(end 0.7874 -0.4064)
			(stroke
				(width 0.1524)
				(type default)
			)
			(layer "F.SilkS")
		)
		(fp_line
			(start 0.7874 -0.4064)
			(end 0.7874 0.4064)
			(stroke
				(width 0.1524)
				(type default)
			)
			(layer "F.SilkS")
		)
		(fp_poly
			(pts
				(xy -0.5334 0.254) (xy -0.635 0.254) (xy -0.635 0.2286) (xy -0.635 -0.254) (xy -0.5334 -0.254) (xy -0.5334 -0.2794)
				(xy 0.5334 -0.2794) (xy 0.5334 -0.254) (xy 0.635 -0.254) (xy 0.635 0.254) (xy 0.5334 0.254) (xy 0.5334 0.2794)
				(xy -0.508 0.2794) (xy -0.5334 0.2794)
			)
			(stroke
				(width 0)
				(type default)
			)
			(fill no)
			(layer "F.CrtYd")
		)
		(pad "1" smd rect
			(at 0.40005 0 270)
			(size 0.4572 0.508)
			(layers "F.Cu" "F.Mask" "F.Paste")
			(net "P12V")
		)
		(pad "2" smd rect
			(at -0.40005 0 270)
			(size 0.4572 0.508)
			(layers "F.Cu" "F.Mask" "F.Paste")
			(net "GND")
		)
	)
	(footprint ""
		(layer "F.Cu")
		(at 50.417984 -217.485976 180)
		(property "Reference" "CE11"
			(at -4.932426 0.531114 0)
			(unlocked yes)
			(layer "F.SilkS")
			(effects
				(font
					(size 0.7874 0.5842)
					(thickness 0.1524)
				)
				(justify left)
			)
		)
		(property "Value" ""
			(at 0 0 180)
			(layer "F.Fab")
			(effects
				(font
					(size 1.27 1.27)
				)
			)
		)
		(duplicate_pad_numbers_are_jumpers no)
		(fp_line
			(start 0 -4.2672)
			(end 0 4.2672)
			(stroke
				(width 0.1524)
				(type default)
			)
			(layer "F.SilkS")
		)
		(fp_circle
			(center 0 0)
			(end -4.2672 0)
			(stroke
				(width 0.1524)
				(type default)
			)
			(fill no)
			(layer "F.SilkS")
		)
		(fp_poly
			(pts
				(arc
					(start 0 -4.2672)
					(mid 4.2672 0)
					(end 0 4.2672)
				)
			)
			(stroke
				(width 0)
				(type default)
			)
			(fill yes)
			(layer "F.SilkS")
		)
		(fp_poly
			(pts
				(xy -2.5146 -0.762) (xy -0.9906 -0.762) (xy -0.9906 0.762) (xy -2.5146 0.762)
			)
			(stroke
				(width 0)
				(type default)
			)
			(fill no)
			(layer "B.CrtYd")
		)
		(fp_poly
			(pts
				(arc
					(start 1.7526 0.762)
					(mid 2.291415 -0.538815)
					(end 0.9906 0)
				)
				(arc
					(start 0.9906 0.0254)
					(mid 1.206345 0.546255)
					(end 1.7272 0.762)
				)
			)
			(stroke
				(width 0)
				(type default)
			)
			(fill no)
			(layer "B.CrtYd")
		)
		(fp_poly
			(pts
				(arc
					(start -4.2672 0)
					(mid 4.2672 0)
					(end -4.2672 0)
				)
			)
			(stroke
				(width 0)
				(type default)
			)
			(fill no)
			(layer "F.CrtYd")
		)
		(fp_circle
			(center 0 0)
			(end -4.2672 0)
			(stroke
				(width 0.1)
				(type default)
			)
			(fill no)
			(layer "F.Fab")
		)
		(fp_text user "+"
			(at -6.029198 -1.261618 180)
			(unlocked yes)
			(layer "F.SilkS")
			(effects
				(font
					(size 1.905 1.4224)
					(thickness 0.1524)
				)
				(justify left)
			)
		)
		(fp_text user "+"
			(at -5.6642 -0.34925 180)
			(unlocked yes)
			(layer "F.Fab")
			(effects
				(font
					(size 1.905 1.4224)
					(thickness 0.000001)
				)
				(justify left)
			)
		)
		(pad "1" thru_hole rect
			(at -1.75006 0 180)
			(size 1.397 1.397)
			(drill 0.9144)
			(layers "*.Cu" "*.Mask")
			(remove_unused_layers no)
			(net "P12V")
			(clearance 0.0127)
			(thermal_gap 0.0127)
			(padstack
				(mode front_inner_back)
				(layer "Inner"
					(shape circle)
					(size 1.397 1.397)
					(clearance 0.0127)
				)
				(layer "B.Cu"
					(shape rect)
					(size 1.397 1.397)
					(clearance 0.0127)
				)
			)
		)
		(pad "2" thru_hole circle
			(at 1.75006 0 180)
			(size 1.397 1.397)
			(drill 0.9144)
			(layers "*.Cu" "*.Mask")
			(remove_unused_layers no)
			(net "GND")
			(clearance 0.0127)
			(thermal_gap 0.0127)
		)
	)
	(footprint ""
		(layer "F.Cu")
		(at 21.453602 -179.957984)
		(property "Reference" "C92"
			(at -1.182116 -1.317752 0)
			(unlocked yes)
			(layer "F.SilkS")
			(effects
				(font
					(size 0.7874 0.5842)
					(thickness 0.1524)
				)
			)
		)
		(property "Value" ""
			(at 0 0 0)
			(layer "F.Fab")
			(effects
				(font
					(size 1.27 1.27)
				)
			)
		)
		(duplicate_pad_numbers_are_jumpers no)
		(fp_line
			(start -1.2954 -0.5842)
			(end 1.2954 -0.5842)
			(stroke
				(width 0.1524)
				(type default)
			)
			(layer "F.SilkS")
		)
		(fp_line
			(start -1.2954 0.5842)
			(end -1.2954 -0.5842)
			(stroke
				(width 0.1524)
				(type default)
			)
			(layer "F.SilkS")
		)
		(fp_line
			(start 0 -0.5842)
			(end 0 0.5842)
			(stroke
				(width 0.1524)
				(type default)
			)
			(layer "F.SilkS")
		)
		(fp_line
			(start 1.2954 -0.5842)
			(end 1.2954 0.5842)
			(stroke
				(width 0.1524)
				(type default)
			)
			(layer "F.SilkS")
		)
		(fp_line
			(start 1.2954 0.5842)
			(end -1.2954 0.5842)
			(stroke
				(width 0.1524)
				(type default)
			)
			(layer "F.SilkS")
		)
		(fp_poly
			(pts
				(xy 0.8636 -0.4572) (xy 0.8636 -0.3556) (xy 1.143 -0.3556) (xy 1.143 0.3556) (xy 0.8636 0.3556)
				(xy 0.8636 0.4572) (xy -0.8636 0.4572) (xy -0.8636 0.3556) (xy -1.143 0.3556) (xy -1.143 -0.3556)
				(xy -0.8636 -0.3556) (xy -0.8636 -0.4572)
			)
			(stroke
				(width 0)
				(type default)
			)
			(fill no)
			(layer "F.CrtYd")
		)
		(fp_line
			(start -0.884936 -0.504952)
			(end 0.884936 -0.504952)
			(stroke
				(width 0.1)
				(type default)
			)
			(layer "F.Fab")
		)
		(fp_line
			(start -0.884936 0.504952)
			(end -0.884936 -0.504952)
			(stroke
				(width 0.1)
				(type default)
			)
			(layer "F.Fab")
		)
		(fp_line
			(start 0.884936 -0.504952)
			(end 0.884936 0.504952)
			(stroke
				(width 0.1)
				(type default)
			)
			(layer "F.Fab")
		)
		(fp_line
			(start 0.884936 0.504952)
			(end -0.884936 0.504952)
			(stroke
				(width 0.1)
				(type default)
			)
			(layer "F.Fab")
		)
		(pad "1" smd rect
			(at 0.7366 0 90)
			(size 0.7112 0.8128)
			(layers "F.Cu" "F.Mask" "F.Paste")
			(net "N42263600")
		)
		(pad "2" smd rect
			(at -0.7366 0 90)
			(size 0.7112 0.8128)
			(layers "F.Cu" "F.Mask" "F.Paste")
			(net "GND")
		)
	)
	(footprint ""
		(layer "F.Cu")
		(at 72.559164 -259.450078 90)
		(property "Reference" "C48"
			(at -4.374134 -0.046482 90)
			(unlocked yes)
			(layer "F.SilkS")
			(effects
				(font
					(size 0.7874 0.5842)
					(thickness 0.1524)
				)
				(justify left)
			)
		)
		(property "Value" ""
			(at 0 0 90)
			(layer "F.Fab")
			(effects
				(font
					(size 1.27 1.27)
				)
			)
		)
		(duplicate_pad_numbers_are_jumpers no)
		(fp_line
			(start 0.7874 -0.4064)
			(end 0.7874 0.4064)
			(stroke
				(width 0.1524)
				(type default)
			)
			(layer "F.SilkS")
		)
		(fp_line
			(start -0.7874 -0.4064)
			(end 0.7874 -0.4064)
			(stroke
				(width 0.1524)
				(type default)
			)
			(layer "F.SilkS")
		)
		(fp_line
			(start 0 0.381)
			(end 0 -0.381)
			(stroke
				(width 0.1524)
				(type default)
			)
			(layer "F.SilkS")
		)
		(fp_line
			(start 0.7874 0.4064)
			(end -0.7874 0.4064)
			(stroke
				(width 0.1524)
				(type default)
			)
			(layer "F.SilkS")
		)
		(fp_line
			(start -0.7874 0.4064)
			(end -0.7874 -0.4064)
			(stroke
				(width 0.1524)
				(type default)
			)
			(layer "F.SilkS")
		)
		(fp_poly
			(pts
				(xy -0.5334 0.254) (xy -0.635 0.254) (xy -0.635 0.2286) (xy -0.635 -0.254) (xy -0.5334 -0.254) (xy -0.5334 -0.2794)
				(xy 0.5334 -0.2794) (xy 0.5334 -0.254) (xy 0.635 -0.254) (xy 0.635 0.254) (xy 0.5334 0.254) (xy 0.5334 0.2794)
				(xy -0.508 0.2794) (xy -0.5334 0.2794)
			)
			(stroke
				(width 0)
				(type default)
			)
			(fill no)
			(layer "F.CrtYd")
		)
		(pad "1" smd rect
			(at 0.40005 0 90)
			(size 0.4572 0.508)
			(layers "F.Cu" "F.Mask" "F.Paste")
			(net "P12V")
		)
		(pad "2" smd rect
			(at -0.40005 0 90)
			(size 0.4572 0.508)
			(layers "F.Cu" "F.Mask" "F.Paste")
			(net "GND")
		)
	)
	(footprint ""
		(layer "F.Cu")
		(at 75.10145 -393.452604 90)
		(property "Reference" "C69"
			(at 1.084834 0.084582 90)
			(unlocked yes)
			(layer "F.SilkS")
			(effects
				(font
					(size 0.7874 0.5842)
					(thickness 0.1524)
				)
				(justify left)
			)
		)
		(property "Value" ""
			(at 0 0 90)
			(layer "F.Fab")
			(effects
				(font
					(size 1.27 1.27)
				)
			)
		)
		(duplicate_pad_numbers_are_jumpers no)
		(fp_line
			(start 0.7874 -0.4064)
			(end 0.7874 0.4064)
			(stroke
				(width 0.1524)
				(type default)
			)
			(layer "F.SilkS")
		)
		(fp_line
			(start -0.7874 -0.4064)
			(end 0.7874 -0.4064)
			(stroke
				(width 0.1524)
				(type default)
			)
			(layer "F.SilkS")
		)
		(fp_line
			(start 0 0.381)
			(end 0 -0.381)
			(stroke
				(width 0.1524)
				(type default)
			)
			(layer "F.SilkS")
		)
		(fp_line
			(start 0.7874 0.4064)
			(end -0.7874 0.4064)
			(stroke
				(width 0.1524)
				(type default)
			)
			(layer "F.SilkS")
		)
		(fp_line
			(start -0.7874 0.4064)
			(end -0.7874 -0.4064)
			(stroke
				(width 0.1524)
				(type default)
			)
			(layer "F.SilkS")
		)
		(fp_poly
			(pts
				(xy -0.5334 0.254) (xy -0.635 0.254) (xy -0.635 0.2286) (xy -0.635 -0.254) (xy -0.5334 -0.254) (xy -0.5334 -0.2794)
				(xy 0.5334 -0.2794) (xy 0.5334 -0.254) (xy 0.635 -0.254) (xy 0.635 0.254) (xy 0.5334 0.254) (xy 0.5334 0.2794)
				(xy -0.508 0.2794) (xy -0.5334 0.2794)
			)
			(stroke
				(width 0)
				(type default)
			)
			(fill no)
			(layer "F.CrtYd")
		)
		(pad "1" smd rect
			(at 0.40005 0 90)
			(size 0.4572 0.508)
			(layers "F.Cu" "F.Mask" "F.Paste")
			(net "P12V")
		)
		(pad "2" smd rect
			(at -0.40005 0 90)
			(size 0.4572 0.508)
			(layers "F.Cu" "F.Mask" "F.Paste")
			(net "GND")
		)
	)
	(footprint ""
		(layer "F.Cu")
		(at 21.162518 -448.10426 180)
		(property "Reference" "C89"
			(at -0.406146 -6.902958 0)
			(unlocked yes)
			(layer "F.SilkS")
			(effects
				(font
					(size 0.7874 0.5842)
					(thickness 0.1524)
				)
				(justify left)
			)
		)
		(property "Value" ""
			(at 0 0 180)
			(layer "F.Fab")
			(effects
				(font
					(size 1.27 1.27)
				)
			)
		)
		(duplicate_pad_numbers_are_jumpers no)
		(fp_line
			(start 1.905 0.8636)
			(end -1.905 0.8636)
			(stroke
				(width 0.1524)
				(type default)
			)
			(layer "F.SilkS")
		)
		(fp_line
			(start 1.905 -0.8636)
			(end 1.905 0.8636)
			(stroke
				(width 0.1524)
				(type default)
			)
			(layer "F.SilkS")
		)
		(fp_line
			(start 0 0.8382)
			(end 0 -0.8382)
			(stroke
				(width 0.1524)
				(type default)
			)
			(layer "F.SilkS")
		)
		(fp_line
			(start -1.905 0.8636)
			(end -1.905 -0.8636)
			(stroke
				(width 0.1524)
				(type default)
			)
			(layer "F.SilkS")
		)
		(fp_line
			(start -1.905 -0.8636)
			(end 1.905 -0.8636)
			(stroke
				(width 0.1524)
				(type default)
			)
			(layer "F.SilkS")
		)
		(fp_rect
			(start -1.524 0.7366)
			(end 1.524 -0.7366)
			(stroke
				(width 0)
				(type default)
			)
			(fill no)
			(layer "F.CrtYd")
		)
		(pad "1" smd rect
			(at 0.94996 0 180)
			(size 1.1176 1.3716)
			(layers "F.Cu" "F.Mask" "F.Paste")
			(net "P3V3_BUF")
		)
		(pad "2" smd rect
			(at -0.94996 0 180)
			(size 1.1176 1.3716)
			(layers "F.Cu" "F.Mask" "F.Paste")
			(net "GND")
		)
	)
	(footprint ""
		(layer "F.Cu")
		(at 16.348964 -336.728562)
		(property "Reference" "U1"
			(at -2.1082 -3.165348 0)
			(unlocked yes)
			(layer "F.SilkS")
			(effects
				(font
					(size 0.7874 0.5842)
					(thickness 0.1524)
				)
				(justify left)
			)
		)
		(property "Value" ""
			(at 0 0 0)
			(layer "F.Fab")
			(effects
				(font
					(size 1.27 1.27)
				)
			)
		)
		(duplicate_pad_numbers_are_jumpers no)
		(fp_line
			(start -1.8288 -2.500122)
			(end -1.8288 2.500122)
			(stroke
				(width 0.1524)
				(type default)
			)
			(layer "F.SilkS")
		)
		(fp_line
			(start -1.8288 2.500122)
			(end 1.8288 2.500122)
			(stroke
				(width 0.1524)
				(type default)
			)
			(layer "F.SilkS")
		)
		(fp_line
			(start -1.077722 -2.500122)
			(end -1.8288 -2.500122)
			(stroke
				(width 0.1524)
				(type default)
			)
			(layer "F.SilkS")
		)
		(fp_line
			(start 0 -1.4224)
			(end -1.077722 -2.500122)
			(stroke
				(width 0.1524)
				(type default)
			)
			(layer "F.SilkS")
		)
		(fp_line
			(start 1.077722 -2.500122)
			(end 0 -1.4224)
			(stroke
				(width 0.1524)
				(type default)
			)
			(layer "F.SilkS")
		)
		(fp_line
			(start 1.8288 -2.500122)
			(end 1.077722 -2.500122)
			(stroke
				(width 0.1524)
				(type default)
			)
			(layer "F.SilkS")
		)
		(fp_line
			(start 1.8288 2.500122)
			(end 1.8288 -2.500122)
			(stroke
				(width 0.1524)
				(type default)
			)
			(layer "F.SilkS")
		)
		(fp_poly
			(pts
				(xy -4.358386 -2.450592) (xy -4.358386 -1.434592) (xy -3.342386 -1.942592)
			)
			(stroke
				(width 0)
				(type default)
			)
			(fill yes)
			(layer "F.SilkS")
		)
		(fp_poly
			(pts
				(xy -1.999996 -2.500122) (xy -1.999996 -2.413) (xy -3.302 -2.413) (xy -3.302 2.413) (xy -1.999996 2.413)
				(xy -1.999996 2.500122) (xy 1.999996 2.500122) (xy 1.999996 2.413) (xy 3.302 2.413) (xy 3.302 -2.413)
				(xy 1.999996 -2.413) (xy 1.999996 -2.500122)
			)
			(stroke
				(width 0)
				(type default)
			)
			(fill no)
			(layer "F.CrtYd")
		)
		(fp_line
			(start -1.999996 -2.500122)
			(end -1.999996 2.500122)
			(stroke
				(width 0.1)
				(type default)
			)
			(layer "F.Fab")
		)
		(fp_line
			(start -1.999996 2.500122)
			(end 1.999996 2.500122)
			(stroke
				(width 0.1)
				(type default)
			)
			(layer "F.Fab")
		)
		(fp_line
			(start 1.999996 -2.500122)
			(end -1.999996 -2.500122)
			(stroke
				(width 0.1)
				(type default)
			)
			(layer "F.Fab")
		)
		(fp_line
			(start 1.999996 2.500122)
			(end 1.999996 -2.500122)
			(stroke
				(width 0.1)
				(type default)
			)
			(layer "F.Fab")
		)
		(fp_poly
			(pts
				(xy -4.5085 -2.413) (xy -4.5085 -1.397) (xy -3.4925 -1.905)
			)
			(stroke
				(width 0)
				(type default)
			)
			(fill yes)
			(layer "F.Fab")
		)
		(pad "1" smd rect
			(at -2.599944 -1.905 270)
			(size 0.889 1.27)
			(layers "F.Cu" "F.Mask" "F.Paste")
			(net "FRU_A0")
		)
		(pad "2" smd rect
			(at -2.599944 -0.635 270)
			(size 0.889 1.27)
			(layers "F.Cu" "F.Mask" "F.Paste")
			(net "FRU_A1")
		)
		(pad "3" smd rect
			(at -2.599944 0.635 270)
			(size 0.889 1.27)
			(layers "F.Cu" "F.Mask" "F.Paste")
			(net "FRU_A2")
		)
		(pad "4" smd rect
			(at -2.599944 1.905 270)
			(size 0.889 1.27)
			(layers "F.Cu" "F.Mask" "F.Paste")
			(net "GND")
		)
		(pad "5" smd rect
			(at 2.599944 1.905 270)
			(size 0.889 1.27)
			(layers "F.Cu" "F.Mask" "F.Paste")
			(net "I2C_PDB_SDA")
		)
		(pad "6" smd rect
			(at 2.599944 0.635 270)
			(size 0.889 1.27)
			(layers "F.Cu" "F.Mask" "F.Paste")
			(net "I2C_PDB_SCL")
		)
		(pad "7" smd rect
			(at 2.599944 -0.635 270)
			(size 0.889 1.27)
			(layers "F.Cu" "F.Mask" "F.Paste")
			(net "FRU_WP")
		)
		(pad "8" smd rect
			(at 2.599944 -1.905 270)
			(size 0.889 1.27)
			(layers "F.Cu" "F.Mask" "F.Paste")
			(net "P3V3")
		)
	)
	(footprint ""
		(layer "F.Cu")
		(at 27.640026 -284.62986 90)
		(property "Reference" "R125"
			(at -3.83413 -1.65354 90)
			(unlocked yes)
			(layer "F.SilkS")
			(effects
				(font
					(size 0.7874 0.5842)
					(thickness 0.1524)
				)
				(justify left)
			)
		)
		(property "Value" ""
			(at 0 0 90)
			(layer "F.Fab")
			(effects
				(font
					(size 1.27 1.27)
				)
			)
		)
		(duplicate_pad_numbers_are_jumpers no)
		(fp_line
			(start 0.7874 -0.4064)
			(end 0.7874 0.4064)
			(stroke
				(width 0.1524)
				(type default)
			)
			(layer "F.SilkS")
		)
		(fp_line
			(start -0.7874 -0.4064)
			(end 0.7874 -0.4064)
			(stroke
				(width 0.1524)
				(type default)
			)
			(layer "F.SilkS")
		)
		(fp_line
			(start 0.7874 0.4064)
			(end -0.7874 0.4064)
			(stroke
				(width 0.1524)
				(type default)
			)
			(layer "F.SilkS")
		)
		(fp_line
			(start -0.7874 0.4064)
			(end -0.7874 -0.4064)
			(stroke
				(width 0.1524)
				(type default)
			)
			(layer "F.SilkS")
		)
		(fp_poly
			(pts
				(xy -0.508 0.2794) (xy -0.508 0.2286) (xy -0.635 0.2286) (xy -0.635 -0.254) (xy -0.5334 -0.254)
				(xy -0.5334 -0.2794) (xy 0.5334 -0.2794) (xy 0.5334 -0.254) (xy 0.635 -0.254) (xy 0.635 0.254) (xy 0.5334 0.254)
				(xy 0.5334 0.2794)
			)
			(stroke
				(width 0)
				(type default)
			)
			(fill no)
			(layer "F.CrtYd")
		)
		(pad "1" smd rect
			(at 0.40005 0 90)
			(size 0.4572 0.508)
			(layers "F.Cu" "F.Mask" "F.Paste")
			(net "PSU4_REMOTE_N")
		)
		(pad "2" smd rect
			(at -0.40005 0 90)
			(size 0.4572 0.508)
			(layers "F.Cu" "F.Mask" "F.Paste")
			(net "PSU4_REMOTE_R2_N")
		)
	)
	(footprint ""
		(layer "F.Cu")
		(at 71.044562 -439.03646 90)
		(property "Reference" "C76"
			(at 1.345946 0.134112 90)
			(unlocked yes)
			(layer "F.SilkS")
			(effects
				(font
					(size 0.7874 0.5842)
					(thickness 0.1524)
				)
				(justify left)
			)
		)
		(property "Value" ""
			(at 0 0 90)
			(layer "F.Fab")
			(effects
				(font
					(size 1.27 1.27)
				)
			)
		)
		(duplicate_pad_numbers_are_jumpers no)
		(fp_line
			(start 0.7874 -0.4064)
			(end 0.7874 0.4064)
			(stroke
				(width 0.1524)
				(type default)
			)
			(layer "F.SilkS")
		)
		(fp_line
			(start -0.7874 -0.4064)
			(end 0.7874 -0.4064)
			(stroke
				(width 0.1524)
				(type default)
			)
			(layer "F.SilkS")
		)
		(fp_line
			(start 0 0.381)
			(end 0 -0.381)
			(stroke
				(width 0.1524)
				(type default)
			)
			(layer "F.SilkS")
		)
		(fp_line
			(start 0.7874 0.4064)
			(end -0.7874 0.4064)
			(stroke
				(width 0.1524)
				(type default)
			)
			(layer "F.SilkS")
		)
		(fp_line
			(start -0.7874 0.4064)
			(end -0.7874 -0.4064)
			(stroke
				(width 0.1524)
				(type default)
			)
			(layer "F.SilkS")
		)
		(fp_poly
			(pts
				(xy -0.5334 0.254) (xy -0.635 0.254) (xy -0.635 0.2286) (xy -0.635 -0.254) (xy -0.5334 -0.254) (xy -0.5334 -0.2794)
				(xy 0.5334 -0.2794) (xy 0.5334 -0.254) (xy 0.635 -0.254) (xy 0.635 0.254) (xy 0.5334 0.254) (xy 0.5334 0.2794)
				(xy -0.508 0.2794) (xy -0.5334 0.2794)
			)
			(stroke
				(width 0)
				(type default)
			)
			(fill no)
			(layer "F.CrtYd")
		)
		(pad "1" smd rect
			(at 0.40005 0 90)
			(size 0.4572 0.508)
			(layers "F.Cu" "F.Mask" "F.Paste")
			(net "P12V")
		)
		(pad "2" smd rect
			(at -0.40005 0 90)
			(size 0.4572 0.508)
			(layers "F.Cu" "F.Mask" "F.Paste")
			(net "GND")
		)
	)
	(footprint ""
		(layer "F.Cu")
		(at 39.798752 -197.274942)
		(property "Reference" "R42"
			(at 2.029968 0.33401 0)
			(unlocked yes)
			(layer "F.SilkS")
			(effects
				(font
					(size 0.7874 0.5842)
					(thickness 0.1524)
				)
				(justify left)
			)
		)
		(property "Value" ""
			(at 0 0 0)
			(layer "F.Fab")
			(effects
				(font
					(size 1.27 1.27)
				)
			)
		)
		(duplicate_pad_numbers_are_jumpers no)
		(fp_line
			(start -0.7874 -0.4064)
			(end 0.7874 -0.4064)
			(stroke
				(width 0.1524)
				(type default)
			)
			(layer "F.SilkS")
		)
		(fp_line
			(start -0.7874 0.4064)
			(end -0.7874 -0.4064)
			(stroke
				(width 0.1524)
				(type default)
			)
			(layer "F.SilkS")
		)
		(fp_line
			(start 0.7874 -0.4064)
			(end 0.7874 0.4064)
			(stroke
				(width 0.1524)
				(type default)
			)
			(layer "F.SilkS")
		)
		(fp_line
			(start 0.7874 0.4064)
			(end -0.7874 0.4064)
			(stroke
				(width 0.1524)
				(type default)
			)
			(layer "F.SilkS")
		)
		(fp_poly
			(pts
				(xy -0.508 0.2794) (xy -0.508 0.2286) (xy -0.635 0.2286) (xy -0.635 -0.254) (xy -0.5334 -0.254)
				(xy -0.5334 -0.2794) (xy 0.5334 -0.2794) (xy 0.5334 -0.254) (xy 0.635 -0.254) (xy 0.635 0.254) (xy 0.5334 0.254)
				(xy 0.5334 0.2794)
			)
			(stroke
				(width 0)
				(type default)
			)
			(fill no)
			(layer "F.CrtYd")
		)
		(pad "1" smd rect
			(at 0.40005 0)
			(size 0.4572 0.508)
			(layers "F.Cu" "F.Mask" "F.Paste")
			(net "GND")
		)
		(pad "2" smd rect
			(at -0.40005 0)
			(size 0.4572 0.508)
			(layers "F.Cu" "F.Mask" "F.Paste")
			(net "P12V_STBY")
		)
	)
	(footprint ""
		(layer "F.Cu")
		(at 91.399868 -108.909866)
		(property "Reference" "H17"
			(at -5.1308 -5.23113 0)
			(unlocked yes)
			(layer "F.SilkS")
			(effects
				(font
					(size 0.7874 0.5842)
					(thickness 0.1524)
				)
				(justify left)
			)
		)
		(property "Value" ""
			(at 0 0 0)
			(layer "F.Fab")
			(effects
				(font
					(size 1.27 1.27)
				)
			)
		)
		(duplicate_pad_numbers_are_jumpers no)
		(fp_circle
			(center 0 0)
			(end 4.826 0)
			(stroke
				(width 0.1524)
				(type default)
			)
			(fill no)
			(layer "F.SilkS")
		)
		(fp_circle
			(center 0 0)
			(end 4.826 0)
			(stroke
				(width 0.1524)
				(type default)
			)
			(fill no)
			(layer "B.SilkS")
		)
		(fp_poly
			(pts
				(arc
					(start 0 4.0132)
					(mid 0 -4.0132)
					(end 0 4.0132)
				)
			)
			(stroke
				(width 0)
				(type default)
			)
			(fill no)
			(layer "F.CrtYd")
		)
		(pad "" np_thru_hole circle
			(at 0 0)
			(size 8.001 8.001)
			(drill 8.001)
			(layers "*.Cu" "*.Mask")
			(clearance 0.381)
			(thermal_gap 0.381)
		)
		(zone
			(layers "F.Cu" "B.Cu" "In1.Cu" "In2.Cu" "In3.Cu" "In4.Cu" "In5.Cu" "In6.Cu")
			(hatch none 0.5)
			(connect_pads
				(clearance 0)
			)
			(min_thickness 0.25)
			(keepout
				(tracks not_allowed)
				(vias allowed)
				(pads allowed)
				(copperpour not_allowed)
				(footprints allowed)
			)
			(placement
				(enabled no)
				(sheetname "")
			)
			(fill
				(thermal_gap 0.5)
				(thermal_bridge_width 0.5)
				(island_removal_mode 0)
			)
			(polygon
				(pts
					(arc
						(start 91.399868 -104.388666)
						(mid 91.399868 -113.431066)
						(end 91.399868 -104.388666)
					)
				)
			)
		)
	)
	(footprint ""
		(layer "F.Cu")
		(at 26.102056 -272.345404)
		(property "Reference" "R57"
			(at -4.037838 -0.005334 0)
			(unlocked yes)
			(layer "F.SilkS")
			(effects
				(font
					(size 0.7874 0.5842)
					(thickness 0.1524)
				)
				(justify left)
			)
		)
		(property "Value" ""
			(at 0 0 0)
			(layer "F.Fab")
			(effects
				(font
					(size 1.27 1.27)
				)
			)
		)
		(duplicate_pad_numbers_are_jumpers no)
		(fp_line
			(start -0.7874 -0.4064)
			(end 0.7874 -0.4064)
			(stroke
				(width 0.1524)
				(type default)
			)
			(layer "F.SilkS")
		)
		(fp_line
			(start -0.7874 0.4064)
			(end -0.7874 -0.4064)
			(stroke
				(width 0.1524)
				(type default)
			)
			(layer "F.SilkS")
		)
		(fp_line
			(start 0.7874 -0.4064)
			(end 0.7874 0.4064)
			(stroke
				(width 0.1524)
				(type default)
			)
			(layer "F.SilkS")
		)
		(fp_line
			(start 0.7874 0.4064)
			(end -0.7874 0.4064)
			(stroke
				(width 0.1524)
				(type default)
			)
			(layer "F.SilkS")
		)
		(fp_poly
			(pts
				(xy -0.508 0.2794) (xy -0.508 0.2286) (xy -0.635 0.2286) (xy -0.635 -0.254) (xy -0.5334 -0.254)
				(xy -0.5334 -0.2794) (xy 0.5334 -0.2794) (xy 0.5334 -0.254) (xy 0.635 -0.254) (xy 0.635 0.254) (xy 0.5334 0.254)
				(xy 0.5334 0.2794)
			)
			(stroke
				(width 0)
				(type default)
			)
			(fill no)
			(layer "F.CrtYd")
		)
		(pad "1" smd rect
			(at 0.40005 0)
			(size 0.4572 0.508)
			(layers "F.Cu" "F.Mask" "F.Paste")
			(net "PSU4_RESET")
		)
		(pad "2" smd rect
			(at -0.40005 0)
			(size 0.4572 0.508)
			(layers "F.Cu" "F.Mask" "F.Paste")
			(net "GND")
		)
	)
	(footprint ""
		(layer "F.Cu")
		(at 16.599916 -295.89984)
		(property "Reference" "H4"
			(at -1.466596 -9.400032 0)
			(unlocked yes)
			(layer "F.SilkS")
			(effects
				(font
					(size 0.7874 0.5842)
					(thickness 0.1524)
				)
				(justify left)
			)
		)
		(property "Value" ""
			(at 0 0 0)
			(layer "F.Fab")
			(effects
				(font
					(size 1.27 1.27)
				)
			)
		)
		(duplicate_pad_numbers_are_jumpers no)
		(fp_circle
			(center 0 0)
			(end 7.999984 0)
			(stroke
				(width 0.1524)
				(type default)
			)
			(fill no)
			(layer "F.SilkS")
		)
		(fp_circle
			(center 0 0)
			(end 14.7066 0)
			(stroke
				(width 0.1524)
				(type default)
			)
			(fill no)
			(layer "B.SilkS")
		)
		(fp_poly
			(pts
				(arc
					(start 0 5.0038)
					(mid 0 -5.0038)
					(end 0 5.0038)
				)
			)
			(stroke
				(width 0)
				(type default)
			)
			(fill no)
			(layer "F.CrtYd")
		)
		(pad "" np_thru_hole circle
			(at 0 0)
			(size 4.0132 4.0132)
			(drill 4.0132)
			(layers "*.Cu" "*.Mask")
			(clearance 0.381)
			(thermal_gap 0.381)
		)
		(pad "2" thru_hole circle
			(at 0 -3.50012)
			(size 0.762 0.762)
			(drill 0.5588)
			(layers "*.Cu" "*.Mask")
			(remove_unused_layers no)
			(net "GND")
			(clearance 0.1524)
			(thermal_gap 0.1524)
		)
		(pad "3" thru_hole circle
			(at -2.500122 -2.500122)
			(size 0.762 0.762)
			(drill 0.5588)
			(layers "*.Cu" "*.Mask")
			(remove_unused_layers no)
			(net "GND")
			(clearance 0.1524)
			(thermal_gap 0.1524)
		)
		(pad "4" thru_hole circle
			(at -3.50012 0)
			(size 0.762 0.762)
			(drill 0.5588)
			(layers "*.Cu" "*.Mask")
			(remove_unused_layers no)
			(net "GND")
			(clearance 0.1524)
			(thermal_gap 0.1524)
		)
		(pad "5" thru_hole circle
			(at -2.500122 2.500122)
			(size 0.762 0.762)
			(drill 0.5588)
			(layers "*.Cu" "*.Mask")
			(remove_unused_layers no)
			(net "GND")
			(clearance 0.1524)
			(thermal_gap 0.1524)
		)
		(pad "6" thru_hole circle
			(at 0 3.50012)
			(size 0.762 0.762)
			(drill 0.5588)
			(layers "*.Cu" "*.Mask")
			(remove_unused_layers no)
			(net "GND")
			(clearance 0.1524)
			(thermal_gap 0.1524)
		)
		(pad "7" thru_hole circle
			(at 2.500122 2.500122)
			(size 0.762 0.762)
			(drill 0.5588)
			(layers "*.Cu" "*.Mask")
			(remove_unused_layers no)
			(net "GND")
			(clearance 0.1524)
			(thermal_gap 0.1524)
		)
		(pad "8" thru_hole circle
			(at 3.50012 0)
			(size 0.762 0.762)
			(drill 0.5588)
			(layers "*.Cu" "*.Mask")
			(remove_unused_layers no)
			(net "GND")
			(clearance 0.1524)
			(thermal_gap 0.1524)
		)
		(pad "9" thru_hole circle
			(at 2.500122 -2.500122)
			(size 0.762 0.762)
			(drill 0.5588)
			(layers "*.Cu" "*.Mask")
			(remove_unused_layers no)
			(net "GND")
			(clearance 0.1524)
			(thermal_gap 0.1524)
		)
		(zone
			(layer "F.Cu")
			(hatch none 0.5)
			(connect_pads
				(clearance 0)
			)
			(min_thickness 0.25)
			(keepout
				(tracks not_allowed)
				(vias allowed)
				(pads allowed)
				(copperpour not_allowed)
				(footprints allowed)
			)
			(placement
				(enabled no)
				(sheetname "")
			)
			(fill
				(thermal_gap 0.5)
				(thermal_bridge_width 0.5)
				(island_removal_mode 0)
			)
			(polygon
				(pts
					(arc
						(start 16.599916 -303.90084)
						(mid 8.598916 -295.89984)
						(end 16.599916 -287.89884)
					)
					(arc
						(start 16.599916 -287.89884)
						(mid 18.035016 -289.33394)
						(end 16.599916 -290.76904)
					)
					(arc
						(start 16.599916 -290.76904)
						(mid 11.469116 -295.89984)
						(end 16.599916 -301.03064)
					)
					(arc
						(start 16.599916 -301.03064)
						(mid 18.035016 -302.46574)
						(end 16.599916 -303.90084)
					)
				)
			)
		)
		(zone
			(layer "F.Cu")
			(hatch none 0.5)
			(connect_pads
				(clearance 0)
			)
			(min_thickness 0.25)
			(keepout
				(tracks not_allowed)
				(vias allowed)
				(pads allowed)
				(copperpour not_allowed)
				(footprints allowed)
			)
			(placement
				(enabled no)
				(sheetname "")
			)
			(fill
				(thermal_gap 0.5)
				(thermal_bridge_width 0.5)
				(island_removal_mode 0)
			)
			(polygon
				(pts
					(arc
						(start 16.599916 -303.90084)
						(mid 24.600916 -295.89984)
						(end 16.599916 -287.89884)
					)
					(arc
						(start 16.599916 -287.89884)
						(mid 15.164816 -289.33394)
						(end 16.599916 -290.76904)
					)
					(arc
						(start 16.599916 -290.76904)
						(mid 21.730716 -295.89984)
						(end 16.599916 -301.03064)
					)
					(arc
						(start 16.599916 -301.03064)
						(mid 15.164816 -302.46574)
						(end 16.599916 -303.90084)
					)
				)
			)
		)
		(zone
			(layers "F.Cu" "B.Cu" "In1.Cu" "In2.Cu" "In3.Cu" "In4.Cu" "In5.Cu" "In6.Cu")
			(hatch none 0.5)
			(connect_pads
				(clearance 0)
			)
			(min_thickness 0.25)
			(keepout
				(tracks not_allowed)
				(vias allowed)
				(pads allowed)
				(copperpour not_allowed)
				(footprints allowed)
			)
			(placement
				(enabled no)
				(sheetname "")
			)
			(fill
				(thermal_gap 0.5)
				(thermal_bridge_width 0.5)
				(island_removal_mode 0)
			)
			(polygon
				(pts
					(arc
						(start 16.599916 -293.38778)
						(mid 16.599916 -298.4119)
						(end 16.599916 -293.38778)
					)
				)
			)
		)
	)
	(footprint ""
		(layer "F.Cu")
		(at 16.263366 -449.79209)
		(property "Reference" "C87"
			(at -1.023366 5.60705 0)
			(unlocked yes)
			(layer "F.SilkS")
			(effects
				(font
					(size 0.7874 0.5842)
					(thickness 0.1524)
				)
				(justify left)
			)
		)
		(property "Value" ""
			(at 0 0 0)
			(layer "F.Fab")
			(effects
				(font
					(size 1.27 1.27)
				)
			)
		)
		(duplicate_pad_numbers_are_jumpers no)
		(fp_line
			(start -1.905 -0.8636)
			(end 1.905 -0.8636)
			(stroke
				(width 0.1524)
				(type default)
			)
			(layer "F.SilkS")
		)
		(fp_line
			(start -1.905 0.8636)
			(end -1.905 -0.8636)
			(stroke
				(width 0.1524)
				(type default)
			)
			(layer "F.SilkS")
		)
		(fp_line
			(start 0 0.8382)
			(end 0 -0.8382)
			(stroke
				(width 0.1524)
				(type default)
			)
			(layer "F.SilkS")
		)
		(fp_line
			(start 1.905 -0.8636)
			(end 1.905 0.8636)
			(stroke
				(width 0.1524)
				(type default)
			)
			(layer "F.SilkS")
		)
		(fp_line
			(start 1.905 0.8636)
			(end -1.905 0.8636)
			(stroke
				(width 0.1524)
				(type default)
			)
			(layer "F.SilkS")
		)
		(fp_rect
			(start -1.524 0.7366)
			(end 1.524 -0.7366)
			(stroke
				(width 0)
				(type default)
			)
			(fill no)
			(layer "F.CrtYd")
		)
		(pad "1" smd rect
			(at 0.94996 0)
			(size 1.1176 1.3716)
			(layers "F.Cu" "F.Mask" "F.Paste")
			(net "P12V")
		)
		(pad "2" smd rect
			(at -0.94996 0)
			(size 1.1176 1.3716)
			(layers "F.Cu" "F.Mask" "F.Paste")
			(net "GND")
		)
	)
	(footprint ""
		(layer "F.Cu")
		(at 3.414014 -127.08636 -90)
		(property "Reference" "R150"
			(at 2.120392 1.17729 90)
			(unlocked yes)
			(layer "F.SilkS")
			(effects
				(font
					(size 0.7874 0.5842)
					(thickness 0.1524)
				)
				(justify left)
			)
		)
		(property "Value" ""
			(at 0 0 270)
			(layer "F.Fab")
			(effects
				(font
					(size 1.27 1.27)
				)
			)
		)
		(duplicate_pad_numbers_are_jumpers no)
		(fp_line
			(start -0.7874 0.4064)
			(end -0.7874 -0.4064)
			(stroke
				(width 0.1524)
				(type default)
			)
			(layer "F.SilkS")
		)
		(fp_line
			(start 0.7874 0.4064)
			(end -0.7874 0.4064)
			(stroke
				(width 0.1524)
				(type default)
			)
			(layer "F.SilkS")
		)
		(fp_line
			(start -0.7874 -0.4064)
			(end 0.7874 -0.4064)
			(stroke
				(width 0.1524)
				(type default)
			)
			(layer "F.SilkS")
		)
		(fp_line
			(start 0.7874 -0.4064)
			(end 0.7874 0.4064)
			(stroke
				(width 0.1524)
				(type default)
			)
			(layer "F.SilkS")
		)
		(fp_poly
			(pts
				(xy -0.508 0.2794) (xy -0.508 0.2286) (xy -0.635 0.2286) (xy -0.635 -0.254) (xy -0.5334 -0.254)
				(xy -0.5334 -0.2794) (xy 0.5334 -0.2794) (xy 0.5334 -0.254) (xy 0.635 -0.254) (xy 0.635 0.254) (xy 0.5334 0.254)
				(xy 0.5334 0.2794)
			)
			(stroke
				(width 0)
				(type default)
			)
			(fill no)
			(layer "F.CrtYd")
		)
		(pad "1" smd rect
			(at 0.40005 0 270)
			(size 0.4572 0.508)
			(layers "F.Cu" "F.Mask" "F.Paste")
			(net "GND")
		)
		(pad "2" smd rect
			(at -0.40005 0 270)
			(size 0.4572 0.508)
			(layers "F.Cu" "F.Mask" "F.Paste")
			(net "N42130542")
		)
	)
	(footprint ""
		(layer "F.Cu")
		(at 19.780504 -454.899522)
		(property "Reference" "U2"
			(at -4.064 -3.52933 0)
			(unlocked yes)
			(layer "F.SilkS")
			(effects
				(font
					(size 0.7874 0.5842)
					(thickness 0.1524)
				)
				(justify left)
			)
		)
		(property "Value" ""
			(at 0 0 0)
			(layer "F.Fab")
			(effects
				(font
					(size 1.27 1.27)
				)
			)
		)
		(duplicate_pad_numbers_are_jumpers no)
		(fp_line
			(start -2.5146 -1.4224)
			(end 2.5146 -1.4224)
			(stroke
				(width 0.1524)
				(type default)
			)
			(layer "F.SilkS")
		)
		(fp_line
			(start -2.5146 -0.4572)
			(end -2.5146 -1.4224)
			(stroke
				(width 0.1524)
				(type default)
			)
			(layer "F.SilkS")
		)
		(fp_line
			(start -2.5146 0.4572)
			(end -2.0574 0)
			(stroke
				(width 0.1524)
				(type default)
			)
			(layer "F.SilkS")
		)
		(fp_line
			(start -2.5146 1.4224)
			(end -2.5146 0.4572)
			(stroke
				(width 0.1524)
				(type default)
			)
			(layer "F.SilkS")
		)
		(fp_line
			(start -2.0574 0)
			(end -2.5146 -0.4572)
			(stroke
				(width 0.1524)
				(type default)
			)
			(layer "F.SilkS")
		)
		(fp_line
			(start 2.5146 -1.4224)
			(end 2.5146 1.4224)
			(stroke
				(width 0.1524)
				(type default)
			)
			(layer "F.SilkS")
		)
		(fp_line
			(start 2.5146 1.4224)
			(end -2.5146 1.4224)
			(stroke
				(width 0.1524)
				(type default)
			)
			(layer "F.SilkS")
		)
		(fp_circle
			(center -1.905 0.889)
			(end -1.651 0.889)
			(stroke
				(width 0.1524)
				(type default)
			)
			(fill no)
			(layer "F.SilkS")
		)
		(fp_poly
			(pts
				(xy -2.1844 3.5052) (xy -2.1844 2.0066) (xy -2.5146 2.0066) (xy -2.5146 -2.0066) (xy -2.1844 -2.0066)
				(xy -2.1844 -3.5052) (xy 2.1844 -3.5052) (xy 2.1844 -2.0066) (xy 2.5146 -2.0066) (xy 2.5146 2.0066)
				(xy 2.1844 2.0066) (xy 2.1844 3.5052)
			)
			(stroke
				(width 0)
				(type default)
			)
			(fill no)
			(layer "F.CrtYd")
		)
		(pad "1" smd rect
			(at -1.905 2.6416)
			(size 0.5588 1.7272)
			(layers "F.Cu" "F.Mask" "F.Paste")
			(net "N42241895")
		)
		(pad "2" smd rect
			(at -0.635 2.6416)
			(size 0.5588 1.7272)
			(layers "F.Cu" "F.Mask" "F.Paste")
			(net "P12V")
		)
		(pad "3" smd rect
			(at 0.635 2.6416)
			(size 0.5588 1.7272)
			(layers "F.Cu" "F.Mask" "F.Paste")
			(net "P3V3_BUF")
		)
		(pad "4" smd rect
			(at 1.905 2.6416)
			(size 0.5588 1.7272)
			(layers "F.Cu" "F.Mask" "F.Paste")
			(net "N42242090")
		)
		(pad "5" smd rect
			(at 1.905 -2.6416)
			(size 0.5588 1.7272)
			(layers "F.Cu" "F.Mask" "F.Paste")
			(net "GND")
		)
		(pad "6" smd rect
			(at 0.635 -2.6416)
			(size 0.5588 1.7272)
			(layers "F.Cu" "F.Mask" "F.Paste")
			(net "GND")
		)
		(pad "7" smd rect
			(at -0.635 -2.6416)
			(size 0.5588 1.7272)
			(layers "F.Cu" "F.Mask" "F.Paste")
			(net "GND")
		)
		(pad "8" smd rect
			(at -1.905 -2.6416)
			(size 0.5588 1.7272)
			(layers "F.Cu" "F.Mask" "F.Paste")
			(net "GND")
		)
	)
	(footprint ""
		(layer "F.Cu")
		(at 50.083466 -38.6207 180)
		(property "Reference" "CE2"
			(at 1.317244 -5.56133 0)
			(unlocked yes)
			(layer "F.SilkS")
			(effects
				(font
					(size 0.7874 0.5842)
					(thickness 0.1524)
				)
				(justify left)
			)
		)
		(property "Value" ""
			(at 0 0 180)
			(layer "F.Fab")
			(effects
				(font
					(size 1.27 1.27)
				)
			)
		)
		(duplicate_pad_numbers_are_jumpers no)
		(fp_line
			(start 0 -4.2672)
			(end 0 4.2672)
			(stroke
				(width 0.1524)
				(type default)
			)
			(layer "F.SilkS")
		)
		(fp_circle
			(center 0 0)
			(end -4.2672 0)
			(stroke
				(width 0.1524)
				(type default)
			)
			(fill no)
			(layer "F.SilkS")
		)
		(fp_poly
			(pts
				(arc
					(start 0 -4.2672)
					(mid 4.2672 0)
					(end 0 4.2672)
				)
			)
			(stroke
				(width 0)
				(type default)
			)
			(fill yes)
			(layer "F.SilkS")
		)
		(fp_poly
			(pts
				(xy -2.5146 -0.762) (xy -0.9906 -0.762) (xy -0.9906 0.762) (xy -2.5146 0.762)
			)
			(stroke
				(width 0)
				(type default)
			)
			(fill no)
			(layer "B.CrtYd")
		)
		(fp_poly
			(pts
				(arc
					(start 1.7526 0.762)
					(mid 2.291415 -0.538815)
					(end 0.9906 0)
				)
				(arc
					(start 0.9906 0.0254)
					(mid 1.206345 0.546255)
					(end 1.7272 0.762)
				)
			)
			(stroke
				(width 0)
				(type default)
			)
			(fill no)
			(layer "B.CrtYd")
		)
		(fp_poly
			(pts
				(arc
					(start -4.2672 0)
					(mid 4.2672 0)
					(end -4.2672 0)
				)
			)
			(stroke
				(width 0)
				(type default)
			)
			(fill no)
			(layer "F.CrtYd")
		)
		(fp_circle
			(center 0 0)
			(end -4.2672 0)
			(stroke
				(width 0.1)
				(type default)
			)
			(fill no)
			(layer "F.Fab")
		)
		(fp_text user "+"
			(at -4.383532 3.495548 180)
			(unlocked yes)
			(layer "F.SilkS")
			(effects
				(font
					(size 1.905 1.4224)
					(thickness 0.1524)
				)
				(justify left)
			)
		)
		(fp_text user "+"
			(at -5.6642 -0.34925 180)
			(unlocked yes)
			(layer "F.Fab")
			(effects
				(font
					(size 1.905 1.4224)
					(thickness 0.000001)
				)
				(justify left)
			)
		)
		(pad "1" thru_hole rect
			(at -1.75006 0 180)
			(size 1.397 1.397)
			(drill 0.9144)
			(layers "*.Cu" "*.Mask")
			(remove_unused_layers no)
			(net "P12V")
			(clearance 0.0127)
			(thermal_gap 0.0127)
			(padstack
				(mode front_inner_back)
				(layer "Inner"
					(shape circle)
					(size 1.397 1.397)
					(clearance 0.0127)
				)
				(layer "B.Cu"
					(shape rect)
					(size 1.397 1.397)
					(clearance 0.0127)
				)
			)
		)
		(pad "2" thru_hole circle
			(at 1.75006 0 180)
			(size 1.397 1.397)
			(drill 0.9144)
			(layers "*.Cu" "*.Mask")
			(remove_unused_layers no)
			(net "GND")
			(clearance 0.0127)
			(thermal_gap 0.0127)
		)
	)
	(footprint ""
		(layer "F.Cu")
		(at 25.997662 -8.344662)
		(property "Reference" "R43"
			(at -3.764788 0.113792 0)
			(unlocked yes)
			(layer "F.SilkS")
			(effects
				(font
					(size 0.7874 0.5842)
					(thickness 0.1524)
				)
				(justify left)
			)
		)
		(property "Value" ""
			(at 0 0 0)
			(layer "F.Fab")
			(effects
				(font
					(size 1.27 1.27)
				)
			)
		)
		(duplicate_pad_numbers_are_jumpers no)
		(fp_line
			(start -0.7874 -0.4064)
			(end 0.7874 -0.4064)
			(stroke
				(width 0.1524)
				(type default)
			)
			(layer "F.SilkS")
		)
		(fp_line
			(start -0.7874 0.4064)
			(end -0.7874 -0.4064)
			(stroke
				(width 0.1524)
				(type default)
			)
			(layer "F.SilkS")
		)
		(fp_line
			(start 0.7874 -0.4064)
			(end 0.7874 0.4064)
			(stroke
				(width 0.1524)
				(type default)
			)
			(layer "F.SilkS")
		)
		(fp_line
			(start 0.7874 0.4064)
			(end -0.7874 0.4064)
			(stroke
				(width 0.1524)
				(type default)
			)
			(layer "F.SilkS")
		)
		(fp_poly
			(pts
				(xy -0.508 0.2794) (xy -0.508 0.2286) (xy -0.635 0.2286) (xy -0.635 -0.254) (xy -0.5334 -0.254)
				(xy -0.5334 -0.2794) (xy 0.5334 -0.2794) (xy 0.5334 -0.254) (xy 0.635 -0.254) (xy 0.635 0.254) (xy 0.5334 0.254)
				(xy 0.5334 0.2794)
			)
			(stroke
				(width 0)
				(type default)
			)
			(fill no)
			(layer "F.CrtYd")
		)
		(pad "1" smd rect
			(at 0.40005 0)
			(size 0.4572 0.508)
			(layers "F.Cu" "F.Mask" "F.Paste")
			(net "PSU1_PS_KILL")
		)
		(pad "2" smd rect
			(at -0.40005 0)
			(size 0.4572 0.508)
			(layers "F.Cu" "F.Mask" "F.Paste")
			(net "GND")
		)
	)
	(footprint ""
		(layer "F.Cu")
		(at 72.478392 -153.431748 -90)
		(property "Reference" "C22"
			(at -3.210052 -0.035814 90)
			(unlocked yes)
			(layer "F.SilkS")
			(effects
				(font
					(size 0.7874 0.5842)
					(thickness 0.1524)
				)
			)
		)
		(property "Value" ""
			(at 0 0 270)
			(layer "F.Fab")
			(effects
				(font
					(size 1.27 1.27)
				)
			)
		)
		(duplicate_pad_numbers_are_jumpers no)
		(fp_line
			(start -1.2954 0.5842)
			(end -1.2954 -0.5842)
			(stroke
				(width 0.1524)
				(type default)
			)
			(layer "F.SilkS")
		)
		(fp_line
			(start 1.2954 0.5842)
			(end -1.2954 0.5842)
			(stroke
				(width 0.1524)
				(type default)
			)
			(layer "F.SilkS")
		)
		(fp_line
			(start -1.2954 -0.5842)
			(end 1.2954 -0.5842)
			(stroke
				(width 0.1524)
				(type default)
			)
			(layer "F.SilkS")
		)
		(fp_line
			(start 0 -0.5842)
			(end 0 0.5842)
			(stroke
				(width 0.1524)
				(type default)
			)
			(layer "F.SilkS")
		)
		(fp_line
			(start 1.2954 -0.5842)
			(end 1.2954 0.5842)
			(stroke
				(width 0.1524)
				(type default)
			)
			(layer "F.SilkS")
		)
		(fp_poly
			(pts
				(xy 0.8636 -0.4572) (xy 0.8636 -0.3556) (xy 1.143 -0.3556) (xy 1.143 0.3556) (xy 0.8636 0.3556)
				(xy 0.8636 0.4572) (xy -0.8636 0.4572) (xy -0.8636 0.3556) (xy -1.143 0.3556) (xy -1.143 -0.3556)
				(xy -0.8636 -0.3556) (xy -0.8636 -0.4572)
			)
			(stroke
				(width 0)
				(type default)
			)
			(fill no)
			(layer "F.CrtYd")
		)
		(fp_line
			(start -0.884936 0.504952)
			(end -0.884936 -0.504952)
			(stroke
				(width 0.1)
				(type default)
			)
			(layer "F.Fab")
		)
		(fp_line
			(start 0.884936 0.504952)
			(end -0.884936 0.504952)
			(stroke
				(width 0.1)
				(type default)
			)
			(layer "F.Fab")
		)
		(fp_line
			(start -0.884936 -0.504952)
			(end 0.884936 -0.504952)
			(stroke
				(width 0.1)
				(type default)
			)
			(layer "F.Fab")
		)
		(fp_line
			(start 0.884936 -0.504952)
			(end 0.884936 0.504952)
			(stroke
				(width 0.1)
				(type default)
			)
			(layer "F.Fab")
		)
		(pad "1" smd rect
			(at 0.7366 0)
			(size 0.7112 0.8128)
			(layers "F.Cu" "F.Mask" "F.Paste")
			(net "P12V")
		)
		(pad "2" smd rect
			(at -0.7366 0)
			(size 0.7112 0.8128)
			(layers "F.Cu" "F.Mask" "F.Paste")
			(net "GND")
		)
	)
	(footprint ""
		(layer "F.Cu")
		(at 72.520302 -83.335368 90)
		(property "Reference" "C20"
			(at 1.029716 -0.015748 90)
			(unlocked yes)
			(layer "F.SilkS")
			(effects
				(font
					(size 0.7874 0.5842)
					(thickness 0.1524)
				)
				(justify left)
			)
		)
		(property "Value" ""
			(at 0 0 90)
			(layer "F.Fab")
			(effects
				(font
					(size 1.27 1.27)
				)
			)
		)
		(duplicate_pad_numbers_are_jumpers no)
		(fp_line
			(start 0.7874 -0.4064)
			(end 0.7874 0.4064)
			(stroke
				(width 0.1524)
				(type default)
			)
			(layer "F.SilkS")
		)
		(fp_line
			(start -0.7874 -0.4064)
			(end 0.7874 -0.4064)
			(stroke
				(width 0.1524)
				(type default)
			)
			(layer "F.SilkS")
		)
		(fp_line
			(start 0 0.381)
			(end 0 -0.381)
			(stroke
				(width 0.1524)
				(type default)
			)
			(layer "F.SilkS")
		)
		(fp_line
			(start 0.7874 0.4064)
			(end -0.7874 0.4064)
			(stroke
				(width 0.1524)
				(type default)
			)
			(layer "F.SilkS")
		)
		(fp_line
			(start -0.7874 0.4064)
			(end -0.7874 -0.4064)
			(stroke
				(width 0.1524)
				(type default)
			)
			(layer "F.SilkS")
		)
		(fp_poly
			(pts
				(xy -0.5334 0.254) (xy -0.635 0.254) (xy -0.635 0.2286) (xy -0.635 -0.254) (xy -0.5334 -0.254) (xy -0.5334 -0.2794)
				(xy 0.5334 -0.2794) (xy 0.5334 -0.254) (xy 0.635 -0.254) (xy 0.635 0.254) (xy 0.5334 0.254) (xy 0.5334 0.2794)
				(xy -0.508 0.2794) (xy -0.5334 0.2794)
			)
			(stroke
				(width 0)
				(type default)
			)
			(fill no)
			(layer "F.CrtYd")
		)
		(pad "1" smd rect
			(at 0.40005 0 90)
			(size 0.4572 0.508)
			(layers "F.Cu" "F.Mask" "F.Paste")
			(net "P12V")
		)
		(pad "2" smd rect
			(at -0.40005 0 90)
			(size 0.4572 0.508)
			(layers "F.Cu" "F.Mask" "F.Paste")
			(net "GND")
		)
	)
	(footprint ""
		(layer "F.Cu")
		(at 91.399868 -20.01012)
		(property "Reference" "H25"
			(at -5.1308 -5.23113 0)
			(unlocked yes)
			(layer "F.SilkS")
			(effects
				(font
					(size 0.7874 0.5842)
					(thickness 0.1524)
				)
				(justify left)
			)
		)
		(property "Value" ""
			(at 0 0 0)
			(layer "F.Fab")
			(effects
				(font
					(size 1.27 1.27)
				)
			)
		)
		(duplicate_pad_numbers_are_jumpers no)
		(fp_circle
			(center 0 0)
			(end 4.826 0)
			(stroke
				(width 0.1524)
				(type default)
			)
			(fill no)
			(layer "F.SilkS")
		)
		(fp_circle
			(center 0 0)
			(end 4.826 0)
			(stroke
				(width 0.1524)
				(type default)
			)
			(fill no)
			(layer "B.SilkS")
		)
		(fp_poly
			(pts
				(arc
					(start 0 4.0132)
					(mid 0 -4.0132)
					(end 0 4.0132)
				)
			)
			(stroke
				(width 0)
				(type default)
			)
			(fill no)
			(layer "F.CrtYd")
		)
		(pad "" np_thru_hole circle
			(at 0 0)
			(size 8.001 8.001)
			(drill 8.001)
			(layers "*.Cu" "*.Mask")
			(clearance 0.381)
			(thermal_gap 0.381)
		)
		(zone
			(layers "F.Cu" "B.Cu" "In1.Cu" "In2.Cu" "In3.Cu" "In4.Cu" "In5.Cu" "In6.Cu")
			(hatch none 0.5)
			(connect_pads
				(clearance 0)
			)
			(min_thickness 0.25)
			(keepout
				(tracks not_allowed)
				(vias allowed)
				(pads allowed)
				(copperpour not_allowed)
				(footprints allowed)
			)
			(placement
				(enabled no)
				(sheetname "")
			)
			(fill
				(thermal_gap 0.5)
				(thermal_bridge_width 0.5)
				(island_removal_mode 0)
			)
			(polygon
				(pts
					(arc
						(start 91.399868 -15.48892)
						(mid 91.399868 -24.53132)
						(end 91.399868 -15.48892)
					)
				)
			)
		)
	)
	(footprint ""
		(layer "F.Cu")
		(at 13.463778 -325.064882 180)
		(property "Reference" "R142"
			(at -1.647444 -0.037592 0)
			(unlocked yes)
			(layer "F.SilkS")
			(effects
				(font
					(size 0.7874 0.5842)
					(thickness 0.1524)
				)
				(justify left)
			)
		)
		(property "Value" ""
			(at 0 0 180)
			(layer "F.Fab")
			(effects
				(font
					(size 1.27 1.27)
				)
			)
		)
		(duplicate_pad_numbers_are_jumpers no)
		(fp_line
			(start 0.7874 0.4064)
			(end -0.7874 0.4064)
			(stroke
				(width 0.1524)
				(type default)
			)
			(layer "F.SilkS")
		)
		(fp_line
			(start 0.7874 -0.4064)
			(end 0.7874 0.4064)
			(stroke
				(width 0.1524)
				(type default)
			)
			(layer "F.SilkS")
		)
		(fp_line
			(start -0.7874 0.4064)
			(end -0.7874 -0.4064)
			(stroke
				(width 0.1524)
				(type default)
			)
			(layer "F.SilkS")
		)
		(fp_line
			(start -0.7874 -0.4064)
			(end 0.7874 -0.4064)
			(stroke
				(width 0.1524)
				(type default)
			)
			(layer "F.SilkS")
		)
		(fp_poly
			(pts
				(xy -0.508 0.2794) (xy -0.508 0.2286) (xy -0.635 0.2286) (xy -0.635 -0.254) (xy -0.5334 -0.254)
				(xy -0.5334 -0.2794) (xy 0.5334 -0.2794) (xy 0.5334 -0.254) (xy 0.635 -0.254) (xy 0.635 0.254) (xy 0.5334 0.254)
				(xy 0.5334 0.2794)
			)
			(stroke
				(width 0)
				(type default)
			)
			(fill no)
			(layer "F.CrtYd")
		)
		(pad "1" smd rect
			(at 0.40005 0 180)
			(size 0.4572 0.508)
			(layers "F.Cu" "F.Mask" "F.Paste")
			(net "FAN1_TACH")
		)
		(pad "2" smd rect
			(at -0.40005 0 180)
			(size 0.4572 0.508)
			(layers "F.Cu" "F.Mask" "F.Paste")
			(net "P12V")
		)
	)
	(footprint ""
		(layer "F.Cu")
		(at 17.162272 -330.455524 -90)
		(property "Reference" "R37"
			(at 3.685032 -0.234188 90)
			(unlocked yes)
			(layer "F.SilkS")
			(effects
				(font
					(size 0.7874 0.5842)
					(thickness 0.1524)
				)
				(justify left)
			)
		)
		(property "Value" ""
			(at 0 0 270)
			(layer "F.Fab")
			(effects
				(font
					(size 1.27 1.27)
				)
			)
		)
		(duplicate_pad_numbers_are_jumpers no)
		(fp_line
			(start -0.7874 0.4064)
			(end -0.7874 -0.4064)
			(stroke
				(width 0.1524)
				(type default)
			)
			(layer "F.SilkS")
		)
		(fp_line
			(start 0.7874 0.4064)
			(end -0.7874 0.4064)
			(stroke
				(width 0.1524)
				(type default)
			)
			(layer "F.SilkS")
		)
		(fp_line
			(start -0.7874 -0.4064)
			(end 0.7874 -0.4064)
			(stroke
				(width 0.1524)
				(type default)
			)
			(layer "F.SilkS")
		)
		(fp_line
			(start 0.7874 -0.4064)
			(end 0.7874 0.4064)
			(stroke
				(width 0.1524)
				(type default)
			)
			(layer "F.SilkS")
		)
		(fp_poly
			(pts
				(xy -0.508 0.2794) (xy -0.508 0.2286) (xy -0.635 0.2286) (xy -0.635 -0.254) (xy -0.5334 -0.254)
				(xy -0.5334 -0.2794) (xy 0.5334 -0.2794) (xy 0.5334 -0.254) (xy 0.635 -0.254) (xy 0.635 0.254) (xy 0.5334 0.254)
				(xy 0.5334 0.2794)
			)
			(stroke
				(width 0)
				(type default)
			)
			(fill no)
			(layer "F.CrtYd")
		)
		(pad "1" smd rect
			(at 0.40005 0 270)
			(size 0.4572 0.508)
			(layers "F.Cu" "F.Mask" "F.Paste")
			(net "GND")
		)
		(pad "2" smd rect
			(at -0.40005 0 270)
			(size 0.4572 0.508)
			(layers "F.Cu" "F.Mask" "F.Paste")
			(net "FRU_A0")
		)
	)
	(footprint ""
		(layer "F.Cu")
		(at 16.017494 -330.497434 -90)
		(property "Reference" "R38"
			(at 3.685032 -0.234188 90)
			(unlocked yes)
			(layer "F.SilkS")
			(effects
				(font
					(size 0.7874 0.5842)
					(thickness 0.1524)
				)
				(justify left)
			)
		)
		(property "Value" ""
			(at 0 0 270)
			(layer "F.Fab")
			(effects
				(font
					(size 1.27 1.27)
				)
			)
		)
		(duplicate_pad_numbers_are_jumpers no)
		(fp_line
			(start -0.7874 0.4064)
			(end -0.7874 -0.4064)
			(stroke
				(width 0.1524)
				(type default)
			)
			(layer "F.SilkS")
		)
		(fp_line
			(start 0.7874 0.4064)
			(end -0.7874 0.4064)
			(stroke
				(width 0.1524)
				(type default)
			)
			(layer "F.SilkS")
		)
		(fp_line
			(start -0.7874 -0.4064)
			(end 0.7874 -0.4064)
			(stroke
				(width 0.1524)
				(type default)
			)
			(layer "F.SilkS")
		)
		(fp_line
			(start 0.7874 -0.4064)
			(end 0.7874 0.4064)
			(stroke
				(width 0.1524)
				(type default)
			)
			(layer "F.SilkS")
		)
		(fp_poly
			(pts
				(xy -0.508 0.2794) (xy -0.508 0.2286) (xy -0.635 0.2286) (xy -0.635 -0.254) (xy -0.5334 -0.254)
				(xy -0.5334 -0.2794) (xy 0.5334 -0.2794) (xy 0.5334 -0.254) (xy 0.635 -0.254) (xy 0.635 0.254) (xy 0.5334 0.254)
				(xy 0.5334 0.2794)
			)
			(stroke
				(width 0)
				(type default)
			)
			(fill no)
			(layer "F.CrtYd")
		)
		(pad "1" smd rect
			(at 0.40005 0 270)
			(size 0.4572 0.508)
			(layers "F.Cu" "F.Mask" "F.Paste")
			(net "GND")
		)
		(pad "2" smd rect
			(at -0.40005 0 270)
			(size 0.4572 0.508)
			(layers "F.Cu" "F.Mask" "F.Paste")
			(net "FRU_A1")
		)
	)
	(footprint ""
		(layer "F.Cu")
		(at 66.689986 -304.009806 90)
		(property "Reference" "C56"
			(at 1.090422 -0.062738 90)
			(unlocked yes)
			(layer "F.SilkS")
			(effects
				(font
					(size 0.7874 0.5842)
					(thickness 0.1524)
				)
				(justify left)
			)
		)
		(property "Value" ""
			(at 0 0 90)
			(layer "F.Fab")
			(effects
				(font
					(size 1.27 1.27)
				)
			)
		)
		(duplicate_pad_numbers_are_jumpers no)
		(fp_line
			(start 0.7874 -0.4064)
			(end 0.7874 0.4064)
			(stroke
				(width 0.1524)
				(type default)
			)
			(layer "F.SilkS")
		)
		(fp_line
			(start -0.7874 -0.4064)
			(end 0.7874 -0.4064)
			(stroke
				(width 0.1524)
				(type default)
			)
			(layer "F.SilkS")
		)
		(fp_line
			(start 0 0.381)
			(end 0 -0.381)
			(stroke
				(width 0.1524)
				(type default)
			)
			(layer "F.SilkS")
		)
		(fp_line
			(start 0.7874 0.4064)
			(end -0.7874 0.4064)
			(stroke
				(width 0.1524)
				(type default)
			)
			(layer "F.SilkS")
		)
		(fp_line
			(start -0.7874 0.4064)
			(end -0.7874 -0.4064)
			(stroke
				(width 0.1524)
				(type default)
			)
			(layer "F.SilkS")
		)
		(fp_poly
			(pts
				(xy -0.5334 0.254) (xy -0.635 0.254) (xy -0.635 0.2286) (xy -0.635 -0.254) (xy -0.5334 -0.254) (xy -0.5334 -0.2794)
				(xy 0.5334 -0.2794) (xy 0.5334 -0.254) (xy 0.635 -0.254) (xy 0.635 0.254) (xy 0.5334 0.254) (xy 0.5334 0.2794)
				(xy -0.508 0.2794) (xy -0.5334 0.2794)
			)
			(stroke
				(width 0)
				(type default)
			)
			(fill no)
			(layer "F.CrtYd")
		)
		(pad "1" smd rect
			(at 0.40005 0 90)
			(size 0.4572 0.508)
			(layers "F.Cu" "F.Mask" "F.Paste")
			(net "P12V")
		)
		(pad "2" smd rect
			(at -0.40005 0 90)
			(size 0.4572 0.508)
			(layers "F.Cu" "F.Mask" "F.Paste")
			(net "GND")
		)
	)
	(footprint ""
		(layer "F.Cu")
		(at 25.857708 -366.710722)
		(property "Reference" "R58"
			(at -3.917442 -0.225298 0)
			(unlocked yes)
			(layer "F.SilkS")
			(effects
				(font
					(size 0.7874 0.5842)
					(thickness 0.1524)
				)
				(justify left)
			)
		)
		(property "Value" ""
			(at 0 0 0)
			(layer "F.Fab")
			(effects
				(font
					(size 1.27 1.27)
				)
			)
		)
		(duplicate_pad_numbers_are_jumpers no)
		(fp_line
			(start -0.7874 -0.4064)
			(end 0.7874 -0.4064)
			(stroke
				(width 0.1524)
				(type default)
			)
			(layer "F.SilkS")
		)
		(fp_line
			(start -0.7874 0.4064)
			(end -0.7874 -0.4064)
			(stroke
				(width 0.1524)
				(type default)
			)
			(layer "F.SilkS")
		)
		(fp_line
			(start 0.7874 -0.4064)
			(end 0.7874 0.4064)
			(stroke
				(width 0.1524)
				(type default)
			)
			(layer "F.SilkS")
		)
		(fp_line
			(start 0.7874 0.4064)
			(end -0.7874 0.4064)
			(stroke
				(width 0.1524)
				(type default)
			)
			(layer "F.SilkS")
		)
		(fp_poly
			(pts
				(xy -0.508 0.2794) (xy -0.508 0.2286) (xy -0.635 0.2286) (xy -0.635 -0.254) (xy -0.5334 -0.254)
				(xy -0.5334 -0.2794) (xy 0.5334 -0.2794) (xy 0.5334 -0.254) (xy 0.635 -0.254) (xy 0.635 0.254) (xy 0.5334 0.254)
				(xy 0.5334 0.2794)
			)
			(stroke
				(width 0)
				(type default)
			)
			(fill no)
			(layer "F.CrtYd")
		)
		(pad "1" smd rect
			(at 0.40005 0)
			(size 0.4572 0.508)
			(layers "F.Cu" "F.Mask" "F.Paste")
			(net "PSU5_PS_KILL")
		)
		(pad "2" smd rect
			(at -0.40005 0)
			(size 0.4572 0.508)
			(layers "F.Cu" "F.Mask" "F.Paste")
			(net "GND")
		)
	)
	(footprint ""
		(layer "F.Cu")
		(at 91.399868 -375.61012)
		(property "Reference" "H23"
			(at -5.1308 -5.23113 0)
			(unlocked yes)
			(layer "F.SilkS")
			(effects
				(font
					(size 0.7874 0.5842)
					(thickness 0.1524)
				)
				(justify left)
			)
		)
		(property "Value" ""
			(at 0 0 0)
			(layer "F.Fab")
			(effects
				(font
					(size 1.27 1.27)
				)
			)
		)
		(duplicate_pad_numbers_are_jumpers no)
		(fp_circle
			(center 0 0)
			(end 4.826 0)
			(stroke
				(width 0.1524)
				(type default)
			)
			(fill no)
			(layer "F.SilkS")
		)
		(fp_circle
			(center 0 0)
			(end 4.826 0)
			(stroke
				(width 0.1524)
				(type default)
			)
			(fill no)
			(layer "B.SilkS")
		)
		(fp_poly
			(pts
				(arc
					(start 0 4.0132)
					(mid 0 -4.0132)
					(end 0 4.0132)
				)
			)
			(stroke
				(width 0)
				(type default)
			)
			(fill no)
			(layer "F.CrtYd")
		)
		(pad "" np_thru_hole circle
			(at 0 0)
			(size 8.001 8.001)
			(drill 8.001)
			(layers "*.Cu" "*.Mask")
			(clearance 0.381)
			(thermal_gap 0.381)
		)
		(zone
			(layers "F.Cu" "B.Cu" "In1.Cu" "In2.Cu" "In3.Cu" "In4.Cu" "In5.Cu" "In6.Cu")
			(hatch none 0.5)
			(connect_pads
				(clearance 0)
			)
			(min_thickness 0.25)
			(keepout
				(tracks not_allowed)
				(vias allowed)
				(pads allowed)
				(copperpour not_allowed)
				(footprints allowed)
			)
			(placement
				(enabled no)
				(sheetname "")
			)
			(fill
				(thermal_gap 0.5)
				(thermal_bridge_width 0.5)
				(island_removal_mode 0)
			)
			(polygon
				(pts
					(arc
						(start 91.399868 -371.08892)
						(mid 91.399868 -380.13132)
						(end 91.399868 -371.08892)
					)
				)
			)
		)
	)
	(footprint ""
		(layer "F.Cu")
		(at 39.577264 -375.589546 90)
		(property "Reference" "R126"
			(at -0.735076 2.494026 0)
			(unlocked yes)
			(layer "F.SilkS")
			(effects
				(font
					(size 0.7874 0.5842)
					(thickness 0.1524)
				)
				(justify left)
			)
		)
		(property "Value" ""
			(at 0 0 90)
			(layer "F.Fab")
			(effects
				(font
					(size 1.27 1.27)
				)
			)
		)
		(duplicate_pad_numbers_are_jumpers no)
		(fp_line
			(start 0.7874 -0.4064)
			(end 0.7874 0.4064)
			(stroke
				(width 0.1524)
				(type default)
			)
			(layer "F.SilkS")
		)
		(fp_line
			(start -0.7874 -0.4064)
			(end 0.7874 -0.4064)
			(stroke
				(width 0.1524)
				(type default)
			)
			(layer "F.SilkS")
		)
		(fp_line
			(start 0.7874 0.4064)
			(end -0.7874 0.4064)
			(stroke
				(width 0.1524)
				(type default)
			)
			(layer "F.SilkS")
		)
		(fp_line
			(start -0.7874 0.4064)
			(end -0.7874 -0.4064)
			(stroke
				(width 0.1524)
				(type default)
			)
			(layer "F.SilkS")
		)
		(fp_poly
			(pts
				(xy -0.508 0.2794) (xy -0.508 0.2286) (xy -0.635 0.2286) (xy -0.635 -0.254) (xy -0.5334 -0.254)
				(xy -0.5334 -0.2794) (xy 0.5334 -0.2794) (xy 0.5334 -0.254) (xy 0.635 -0.254) (xy 0.635 0.254) (xy 0.5334 0.254)
				(xy 0.5334 0.2794)
			)
			(stroke
				(width 0)
				(type default)
			)
			(fill no)
			(layer "F.CrtYd")
		)
		(pad "1" smd rect
			(at 0.40005 0 90)
			(size 0.4572 0.508)
			(layers "F.Cu" "F.Mask" "F.Paste")
			(net "PSU5_REMOTE_P")
		)
		(pad "2" smd rect
			(at -0.40005 0 90)
			(size 0.4572 0.508)
			(layers "F.Cu" "F.Mask" "F.Paste")
			(net "PSU5_REMOTE_R2_P")
		)
	)
	(footprint ""
		(layer "F.Cu")
		(at 21.441918 -446.145158 90)
		(property "Reference" "R156"
			(at -8.594852 1.446022 90)
			(unlocked yes)
			(layer "F.SilkS")
			(effects
				(font
					(size 0.7874 0.5842)
					(thickness 0.1524)
				)
				(justify left)
			)
		)
		(property "Value" ""
			(at 0 0 90)
			(layer "F.Fab")
			(effects
				(font
					(size 1.27 1.27)
				)
			)
		)
		(duplicate_pad_numbers_are_jumpers no)
		(fp_line
			(start 0.7874 -0.4064)
			(end 0.7874 0.4064)
			(stroke
				(width 0.1524)
				(type default)
			)
			(layer "F.SilkS")
		)
		(fp_line
			(start -0.7874 -0.4064)
			(end 0.7874 -0.4064)
			(stroke
				(width 0.1524)
				(type default)
			)
			(layer "F.SilkS")
		)
		(fp_line
			(start 0.7874 0.4064)
			(end -0.7874 0.4064)
			(stroke
				(width 0.1524)
				(type default)
			)
			(layer "F.SilkS")
		)
		(fp_line
			(start -0.7874 0.4064)
			(end -0.7874 -0.4064)
			(stroke
				(width 0.1524)
				(type default)
			)
			(layer "F.SilkS")
		)
		(fp_poly
			(pts
				(xy -0.508 0.2794) (xy -0.508 0.2286) (xy -0.635 0.2286) (xy -0.635 -0.254) (xy -0.5334 -0.254)
				(xy -0.5334 -0.2794) (xy 0.5334 -0.2794) (xy 0.5334 -0.254) (xy 0.635 -0.254) (xy 0.635 0.254) (xy 0.5334 0.254)
				(xy 0.5334 0.2794)
			)
			(stroke
				(width 0)
				(type default)
			)
			(fill no)
			(layer "F.CrtYd")
		)
		(pad "1" smd rect
			(at 0.40005 0 90)
			(size 0.4572 0.508)
			(layers "F.Cu" "F.Mask" "F.Paste")
			(net "P3V3_BUF")
		)
		(pad "2" smd rect
			(at -0.40005 0 90)
			(size 0.4572 0.508)
			(layers "F.Cu" "F.Mask" "F.Paste")
			(net "N42242090")
		)
	)
	(footprint ""
		(layer "F.Cu")
		(at 73.45934 -330.332588 -90)
		(property "Reference" "C51"
			(at 3.323336 -0.07366 90)
			(unlocked yes)
			(layer "F.SilkS")
			(effects
				(font
					(size 0.7874 0.5842)
					(thickness 0.1524)
				)
				(justify left)
			)
		)
		(property "Value" ""
			(at 0 0 270)
			(layer "F.Fab")
			(effects
				(font
					(size 1.27 1.27)
				)
			)
		)
		(duplicate_pad_numbers_are_jumpers no)
		(fp_line
			(start -0.7874 0.4064)
			(end -0.7874 -0.4064)
			(stroke
				(width 0.1524)
				(type default)
			)
			(layer "F.SilkS")
		)
		(fp_line
			(start 0.7874 0.4064)
			(end -0.7874 0.4064)
			(stroke
				(width 0.1524)
				(type default)
			)
			(layer "F.SilkS")
		)
		(fp_line
			(start 0 0.381)
			(end 0 -0.381)
			(stroke
				(width 0.1524)
				(type default)
			)
			(layer "F.SilkS")
		)
		(fp_line
			(start -0.7874 -0.4064)
			(end 0.7874 -0.4064)
			(stroke
				(width 0.1524)
				(type default)
			)
			(layer "F.SilkS")
		)
		(fp_line
			(start 0.7874 -0.4064)
			(end 0.7874 0.4064)
			(stroke
				(width 0.1524)
				(type default)
			)
			(layer "F.SilkS")
		)
		(fp_poly
			(pts
				(xy -0.5334 0.254) (xy -0.635 0.254) (xy -0.635 0.2286) (xy -0.635 -0.254) (xy -0.5334 -0.254) (xy -0.5334 -0.2794)
				(xy 0.5334 -0.2794) (xy 0.5334 -0.254) (xy 0.635 -0.254) (xy 0.635 0.254) (xy 0.5334 0.254) (xy 0.5334 0.2794)
				(xy -0.508 0.2794) (xy -0.5334 0.2794)
			)
			(stroke
				(width 0)
				(type default)
			)
			(fill no)
			(layer "F.CrtYd")
		)
		(pad "1" smd rect
			(at 0.40005 0 270)
			(size 0.4572 0.508)
			(layers "F.Cu" "F.Mask" "F.Paste")
			(net "P12V")
		)
		(pad "2" smd rect
			(at -0.40005 0 270)
			(size 0.4572 0.508)
			(layers "F.Cu" "F.Mask" "F.Paste")
			(net "GND")
		)
	)
	(footprint ""
		(layer "F.Cu")
		(at 72.928734 -483.48138 90)
		(property "Reference" "C81"
			(at -4.217416 0.323088 90)
			(unlocked yes)
			(layer "F.SilkS")
			(effects
				(font
					(size 0.7874 0.5842)
					(thickness 0.1524)
				)
				(justify left)
			)
		)
		(property "Value" ""
			(at 0 0 90)
			(layer "F.Fab")
			(effects
				(font
					(size 1.27 1.27)
				)
			)
		)
		(duplicate_pad_numbers_are_jumpers no)
		(fp_line
			(start 0.7874 -0.4064)
			(end 0.7874 0.4064)
			(stroke
				(width 0.1524)
				(type default)
			)
			(layer "F.SilkS")
		)
		(fp_line
			(start -0.7874 -0.4064)
			(end 0.7874 -0.4064)
			(stroke
				(width 0.1524)
				(type default)
			)
			(layer "F.SilkS")
		)
		(fp_line
			(start 0 0.381)
			(end 0 -0.381)
			(stroke
				(width 0.1524)
				(type default)
			)
			(layer "F.SilkS")
		)
		(fp_line
			(start 0.7874 0.4064)
			(end -0.7874 0.4064)
			(stroke
				(width 0.1524)
				(type default)
			)
			(layer "F.SilkS")
		)
		(fp_line
			(start -0.7874 0.4064)
			(end -0.7874 -0.4064)
			(stroke
				(width 0.1524)
				(type default)
			)
			(layer "F.SilkS")
		)
		(fp_poly
			(pts
				(xy -0.5334 0.254) (xy -0.635 0.254) (xy -0.635 0.2286) (xy -0.635 -0.254) (xy -0.5334 -0.254) (xy -0.5334 -0.2794)
				(xy 0.5334 -0.2794) (xy 0.5334 -0.254) (xy 0.635 -0.254) (xy 0.635 0.254) (xy 0.5334 0.254) (xy 0.5334 0.2794)
				(xy -0.508 0.2794) (xy -0.5334 0.2794)
			)
			(stroke
				(width 0)
				(type default)
			)
			(fill no)
			(layer "F.CrtYd")
		)
		(pad "1" smd rect
			(at 0.40005 0 90)
			(size 0.4572 0.508)
			(layers "F.Cu" "F.Mask" "F.Paste")
			(net "P12V")
		)
		(pad "2" smd rect
			(at -0.40005 0 90)
			(size 0.4572 0.508)
			(layers "F.Cu" "F.Mask" "F.Paste")
			(net "GND")
		)
	)
	(footprint ""
		(layer "F.Cu")
		(at 71.390764 -464.050634 -90)
		(property "Reference" "C71"
			(at -3.412236 0.548894 90)
			(unlocked yes)
			(layer "F.SilkS")
			(effects
				(font
					(size 0.7874 0.5842)
					(thickness 0.1524)
				)
			)
		)
		(property "Value" ""
			(at 0 0 270)
			(layer "F.Fab")
			(effects
				(font
					(size 1.27 1.27)
				)
			)
		)
		(duplicate_pad_numbers_are_jumpers no)
		(fp_line
			(start -1.2954 0.5842)
			(end -1.2954 -0.5842)
			(stroke
				(width 0.1524)
				(type default)
			)
			(layer "F.SilkS")
		)
		(fp_line
			(start 1.2954 0.5842)
			(end -1.2954 0.5842)
			(stroke
				(width 0.1524)
				(type default)
			)
			(layer "F.SilkS")
		)
		(fp_line
			(start -1.2954 -0.5842)
			(end 1.2954 -0.5842)
			(stroke
				(width 0.1524)
				(type default)
			)
			(layer "F.SilkS")
		)
		(fp_line
			(start 0 -0.5842)
			(end 0 0.5842)
			(stroke
				(width 0.1524)
				(type default)
			)
			(layer "F.SilkS")
		)
		(fp_line
			(start 1.2954 -0.5842)
			(end 1.2954 0.5842)
			(stroke
				(width 0.1524)
				(type default)
			)
			(layer "F.SilkS")
		)
		(fp_poly
			(pts
				(xy 0.8636 -0.4572) (xy 0.8636 -0.3556) (xy 1.143 -0.3556) (xy 1.143 0.3556) (xy 0.8636 0.3556)
				(xy 0.8636 0.4572) (xy -0.8636 0.4572) (xy -0.8636 0.3556) (xy -1.143 0.3556) (xy -1.143 -0.3556)
				(xy -0.8636 -0.3556) (xy -0.8636 -0.4572)
			)
			(stroke
				(width 0)
				(type default)
			)
			(fill no)
			(layer "F.CrtYd")
		)
		(fp_line
			(start -0.884936 0.504952)
			(end -0.884936 -0.504952)
			(stroke
				(width 0.1)
				(type default)
			)
			(layer "F.Fab")
		)
		(fp_line
			(start 0.884936 0.504952)
			(end -0.884936 0.504952)
			(stroke
				(width 0.1)
				(type default)
			)
			(layer "F.Fab")
		)
		(fp_line
			(start -0.884936 -0.504952)
			(end 0.884936 -0.504952)
			(stroke
				(width 0.1)
				(type default)
			)
			(layer "F.Fab")
		)
		(fp_line
			(start 0.884936 -0.504952)
			(end 0.884936 0.504952)
			(stroke
				(width 0.1)
				(type default)
			)
			(layer "F.Fab")
		)
		(pad "1" smd rect
			(at 0.7366 0)
			(size 0.7112 0.8128)
			(layers "F.Cu" "F.Mask" "F.Paste")
			(net "P12V")
		)
		(pad "2" smd rect
			(at -0.7366 0)
			(size 0.7112 0.8128)
			(layers "F.Cu" "F.Mask" "F.Paste")
			(net "GND")
		)
	)
	(footprint ""
		(layer "F.Cu")
		(at 13.319506 -229.665784 180)
		(property "Reference" "R163"
			(at 0.625856 -1.451102 0)
			(unlocked yes)
			(layer "F.SilkS")
			(effects
				(font
					(size 0.7874 0.5842)
					(thickness 0.1524)
				)
				(justify left)
			)
		)
		(property "Value" ""
			(at 0 0 180)
			(layer "F.Fab")
			(effects
				(font
					(size 1.27 1.27)
				)
			)
		)
		(duplicate_pad_numbers_are_jumpers no)
		(fp_line
			(start 0.7874 0.4064)
			(end -0.7874 0.4064)
			(stroke
				(width 0.1524)
				(type default)
			)
			(layer "F.SilkS")
		)
		(fp_line
			(start 0.7874 -0.4064)
			(end 0.7874 0.4064)
			(stroke
				(width 0.1524)
				(type default)
			)
			(layer "F.SilkS")
		)
		(fp_line
			(start -0.7874 0.4064)
			(end -0.7874 -0.4064)
			(stroke
				(width 0.1524)
				(type default)
			)
			(layer "F.SilkS")
		)
		(fp_line
			(start -0.7874 -0.4064)
			(end 0.7874 -0.4064)
			(stroke
				(width 0.1524)
				(type default)
			)
			(layer "F.SilkS")
		)
		(fp_poly
			(pts
				(xy -0.508 0.2794) (xy -0.508 0.2286) (xy -0.635 0.2286) (xy -0.635 -0.254) (xy -0.5334 -0.254)
				(xy -0.5334 -0.2794) (xy 0.5334 -0.2794) (xy 0.5334 -0.254) (xy 0.635 -0.254) (xy 0.635 0.254) (xy 0.5334 0.254)
				(xy 0.5334 0.2794)
			)
			(stroke
				(width 0)
				(type default)
			)
			(fill no)
			(layer "F.CrtYd")
		)
		(pad "1" smd rect
			(at 0.40005 0 180)
			(size 0.4572 0.508)
			(layers "F.Cu" "F.Mask" "F.Paste")
			(net "T1_BLAD2_EN")
		)
		(pad "2" smd rect
			(at -0.40005 0 180)
			(size 0.4572 0.508)
			(layers "F.Cu" "F.Mask" "F.Paste")
			(net "PSU_ALERT_N")
		)
	)
	(footprint ""
		(layer "F.Cu")
		(at 70.260718 -63.973456 -90)
		(property "Reference" "C9"
			(at -2.559304 0.19939 90)
			(unlocked yes)
			(layer "F.SilkS")
			(effects
				(font
					(size 0.7874 0.5842)
					(thickness 0.1524)
				)
				(justify left)
			)
		)
		(property "Value" ""
			(at 0 0 270)
			(layer "F.Fab")
			(effects
				(font
					(size 1.27 1.27)
				)
			)
		)
		(duplicate_pad_numbers_are_jumpers no)
		(fp_line
			(start -0.7874 0.4064)
			(end -0.7874 -0.4064)
			(stroke
				(width 0.1524)
				(type default)
			)
			(layer "F.SilkS")
		)
		(fp_line
			(start 0.7874 0.4064)
			(end -0.7874 0.4064)
			(stroke
				(width 0.1524)
				(type default)
			)
			(layer "F.SilkS")
		)
		(fp_line
			(start 0 0.381)
			(end 0 -0.381)
			(stroke
				(width 0.1524)
				(type default)
			)
			(layer "F.SilkS")
		)
		(fp_line
			(start -0.7874 -0.4064)
			(end 0.7874 -0.4064)
			(stroke
				(width 0.1524)
				(type default)
			)
			(layer "F.SilkS")
		)
		(fp_line
			(start 0.7874 -0.4064)
			(end 0.7874 0.4064)
			(stroke
				(width 0.1524)
				(type default)
			)
			(layer "F.SilkS")
		)
		(fp_poly
			(pts
				(xy -0.5334 0.254) (xy -0.635 0.254) (xy -0.635 0.2286) (xy -0.635 -0.254) (xy -0.5334 -0.254) (xy -0.5334 -0.2794)
				(xy 0.5334 -0.2794) (xy 0.5334 -0.254) (xy 0.635 -0.254) (xy 0.635 0.254) (xy 0.5334 0.254) (xy 0.5334 0.2794)
				(xy -0.508 0.2794) (xy -0.5334 0.2794)
			)
			(stroke
				(width 0)
				(type default)
			)
			(fill no)
			(layer "F.CrtYd")
		)
		(pad "1" smd rect
			(at 0.40005 0 270)
			(size 0.4572 0.508)
			(layers "F.Cu" "F.Mask" "F.Paste")
			(net "P12V")
		)
		(pad "2" smd rect
			(at -0.40005 0 270)
			(size 0.4572 0.508)
			(layers "F.Cu" "F.Mask" "F.Paste")
			(net "GND")
		)
	)
	(footprint ""
		(layer "F.Cu")
		(at 77.999844 -210.09991)
		(property "Reference" "H7"
			(at -2.377186 -8.725154 0)
			(unlocked yes)
			(layer "F.SilkS")
			(effects
				(font
					(size 0.7874 0.5842)
					(thickness 0.1524)
				)
				(justify left)
			)
		)
		(property "Value" ""
			(at 0 0 0)
			(layer "F.Fab")
			(effects
				(font
					(size 1.27 1.27)
				)
			)
		)
		(duplicate_pad_numbers_are_jumpers no)
		(fp_circle
			(center 0 0)
			(end 7.999984 0)
			(stroke
				(width 0.1524)
				(type default)
			)
			(fill no)
			(layer "F.SilkS")
		)
		(fp_circle
			(center 0 0)
			(end 14.7066 0)
			(stroke
				(width 0.1524)
				(type default)
			)
			(fill no)
			(layer "B.SilkS")
		)
		(fp_poly
			(pts
				(arc
					(start 5.0038 0)
					(mid -5.0038 0)
					(end 5.0038 0)
				)
			)
			(stroke
				(width 0)
				(type default)
			)
			(fill no)
			(layer "F.CrtYd")
		)
		(pad "" np_thru_hole circle
			(at 0 0)
			(size 4.0132 4.0132)
			(drill 4.0132)
			(layers "*.Cu" "*.Mask")
			(clearance 0.381)
			(thermal_gap 0.381)
		)
		(pad "2" thru_hole circle
			(at 0 -3.50012)
			(size 0.762 0.762)
			(drill 0.5588)
			(layers "*.Cu" "*.Mask")
			(remove_unused_layers no)
			(net "GND")
			(clearance 0.1524)
			(thermal_gap 0.1524)
		)
		(pad "3" thru_hole circle
			(at -2.500122 -2.500122)
			(size 0.762 0.762)
			(drill 0.5588)
			(layers "*.Cu" "*.Mask")
			(remove_unused_layers no)
			(net "GND")
			(clearance 0.1524)
			(thermal_gap 0.1524)
		)
		(pad "4" thru_hole circle
			(at -3.50012 0)
			(size 0.762 0.762)
			(drill 0.5588)
			(layers "*.Cu" "*.Mask")
			(remove_unused_layers no)
			(net "GND")
			(clearance 0.1524)
			(thermal_gap 0.1524)
		)
		(pad "5" thru_hole circle
			(at -2.500122 2.500122)
			(size 0.762 0.762)
			(drill 0.5588)
			(layers "*.Cu" "*.Mask")
			(remove_unused_layers no)
			(net "GND")
			(clearance 0.1524)
			(thermal_gap 0.1524)
		)
		(pad "6" thru_hole circle
			(at 0 3.50012)
			(size 0.762 0.762)
			(drill 0.5588)
			(layers "*.Cu" "*.Mask")
			(remove_unused_layers no)
			(net "GND")
			(clearance 0.1524)
			(thermal_gap 0.1524)
		)
		(pad "7" thru_hole circle
			(at 2.500122 2.500122)
			(size 0.762 0.762)
			(drill 0.5588)
			(layers "*.Cu" "*.Mask")
			(remove_unused_layers no)
			(net "GND")
			(clearance 0.1524)
			(thermal_gap 0.1524)
		)
		(pad "8" thru_hole circle
			(at 3.50012 0)
			(size 0.762 0.762)
			(drill 0.5588)
			(layers "*.Cu" "*.Mask")
			(remove_unused_layers no)
			(net "GND")
			(clearance 0.1524)
			(thermal_gap 0.1524)
		)
		(pad "9" thru_hole circle
			(at 2.500122 -2.500122)
			(size 0.762 0.762)
			(drill 0.5588)
			(layers "*.Cu" "*.Mask")
			(remove_unused_layers no)
			(net "GND")
			(clearance 0.1524)
			(thermal_gap 0.1524)
		)
		(zone
			(layer "F.Cu")
			(hatch none 0.5)
			(connect_pads
				(clearance 0)
			)
			(min_thickness 0.25)
			(keepout
				(tracks not_allowed)
				(vias allowed)
				(pads allowed)
				(copperpour not_allowed)
				(footprints allowed)
			)
			(placement
				(enabled no)
				(sheetname "")
			)
			(fill
				(thermal_gap 0.5)
				(thermal_bridge_width 0.5)
				(island_removal_mode 0)
			)
			(polygon
				(pts
					(arc
						(start 77.999844 -218.10091)
						(mid 69.998844 -210.09991)
						(end 77.999844 -202.09891)
					)
					(arc
						(start 77.999844 -202.09891)
						(mid 79.434944 -203.53401)
						(end 77.999844 -204.96911)
					)
					(arc
						(start 77.999844 -204.96911)
						(mid 72.869044 -210.09991)
						(end 77.999844 -215.23071)
					)
					(arc
						(start 77.999844 -215.23071)
						(mid 79.434944 -216.66581)
						(end 77.999844 -218.10091)
					)
				)
			)
		)
		(zone
			(layer "F.Cu")
			(hatch none 0.5)
			(connect_pads
				(clearance 0)
			)
			(min_thickness 0.25)
			(keepout
				(tracks not_allowed)
				(vias allowed)
				(pads allowed)
				(copperpour not_allowed)
				(footprints allowed)
			)
			(placement
				(enabled no)
				(sheetname "")
			)
			(fill
				(thermal_gap 0.5)
				(thermal_bridge_width 0.5)
				(island_removal_mode 0)
			)
			(polygon
				(pts
					(arc
						(start 77.999844 -218.10091)
						(mid 86.000844 -210.09991)
						(end 77.999844 -202.09891)
					)
					(arc
						(start 77.999844 -202.09891)
						(mid 76.564744 -203.53401)
						(end 77.999844 -204.96911)
					)
					(arc
						(start 77.999844 -204.96911)
						(mid 83.130644 -210.09991)
						(end 77.999844 -215.23071)
					)
					(arc
						(start 77.999844 -215.23071)
						(mid 76.564744 -216.66581)
						(end 77.999844 -218.10091)
					)
				)
			)
		)
		(zone
			(layers "F.Cu" "B.Cu" "In1.Cu" "In2.Cu" "In3.Cu" "In4.Cu" "In5.Cu" "In6.Cu")
			(hatch none 0.5)
			(connect_pads
				(clearance 0)
			)
			(min_thickness 0.25)
			(keepout
				(tracks not_allowed)
				(vias allowed)
				(pads allowed)
				(copperpour not_allowed)
				(footprints allowed)
			)
			(placement
				(enabled no)
				(sheetname "")
			)
			(fill
				(thermal_gap 0.5)
				(thermal_bridge_width 0.5)
				(island_removal_mode 0)
			)
			(polygon
				(pts
					(arc
						(start 80.511904 -210.09991)
						(mid 75.487784 -210.09991)
						(end 80.511904 -210.09991)
					)
				)
			)
		)
	)
	(footprint ""
		(layer "F.Cu")
		(at 91.399868 -420.06012)
		(property "Reference" "H15"
			(at -5.1308 -5.23113 0)
			(unlocked yes)
			(layer "F.SilkS")
			(effects
				(font
					(size 0.7874 0.5842)
					(thickness 0.1524)
				)
				(justify left)
			)
		)
		(property "Value" ""
			(at 0 0 0)
			(layer "F.Fab")
			(effects
				(font
					(size 1.27 1.27)
				)
			)
		)
		(duplicate_pad_numbers_are_jumpers no)
		(fp_circle
			(center 0 0)
			(end 4.826 0)
			(stroke
				(width 0.1524)
				(type default)
			)
			(fill no)
			(layer "F.SilkS")
		)
		(fp_circle
			(center 0 0)
			(end 4.826 0)
			(stroke
				(width 0.1524)
				(type default)
			)
			(fill no)
			(layer "B.SilkS")
		)
		(fp_poly
			(pts
				(arc
					(start 0 4.0132)
					(mid 0 -4.0132)
					(end 0 4.0132)
				)
			)
			(stroke
				(width 0)
				(type default)
			)
			(fill no)
			(layer "F.CrtYd")
		)
		(pad "" np_thru_hole circle
			(at 0 0)
			(size 8.001 8.001)
			(drill 8.001)
			(layers "*.Cu" "*.Mask")
			(clearance 0.381)
			(thermal_gap 0.381)
		)
		(zone
			(layers "F.Cu" "B.Cu" "In1.Cu" "In2.Cu" "In3.Cu" "In4.Cu" "In5.Cu" "In6.Cu")
			(hatch none 0.5)
			(connect_pads
				(clearance 0)
			)
			(min_thickness 0.25)
			(keepout
				(tracks not_allowed)
				(vias allowed)
				(pads allowed)
				(copperpour not_allowed)
				(footprints allowed)
			)
			(placement
				(enabled no)
				(sheetname "")
			)
			(fill
				(thermal_gap 0.5)
				(thermal_bridge_width 0.5)
				(island_removal_mode 0)
			)
			(polygon
				(pts
					(arc
						(start 91.399868 -415.53892)
						(mid 91.399868 -424.58132)
						(end 91.399868 -415.53892)
					)
				)
			)
		)
	)
	(footprint ""
		(layer "F.Cu")
		(at 71.96836 -172.135546 90)
		(property "Reference" "C32"
			(at -4.154678 0.383032 90)
			(unlocked yes)
			(layer "F.SilkS")
			(effects
				(font
					(size 0.7874 0.5842)
					(thickness 0.1524)
				)
				(justify left)
			)
		)
		(property "Value" ""
			(at 0 0 90)
			(layer "F.Fab")
			(effects
				(font
					(size 1.27 1.27)
				)
			)
		)
		(duplicate_pad_numbers_are_jumpers no)
		(fp_line
			(start 0.7874 -0.4064)
			(end 0.7874 0.4064)
			(stroke
				(width 0.1524)
				(type default)
			)
			(layer "F.SilkS")
		)
		(fp_line
			(start -0.7874 -0.4064)
			(end 0.7874 -0.4064)
			(stroke
				(width 0.1524)
				(type default)
			)
			(layer "F.SilkS")
		)
		(fp_line
			(start 0 0.381)
			(end 0 -0.381)
			(stroke
				(width 0.1524)
				(type default)
			)
			(layer "F.SilkS")
		)
		(fp_line
			(start 0.7874 0.4064)
			(end -0.7874 0.4064)
			(stroke
				(width 0.1524)
				(type default)
			)
			(layer "F.SilkS")
		)
		(fp_line
			(start -0.7874 0.4064)
			(end -0.7874 -0.4064)
			(stroke
				(width 0.1524)
				(type default)
			)
			(layer "F.SilkS")
		)
		(fp_poly
			(pts
				(xy -0.5334 0.254) (xy -0.635 0.254) (xy -0.635 0.2286) (xy -0.635 -0.254) (xy -0.5334 -0.254) (xy -0.5334 -0.2794)
				(xy 0.5334 -0.2794) (xy 0.5334 -0.254) (xy 0.635 -0.254) (xy 0.635 0.254) (xy 0.5334 0.254) (xy 0.5334 0.2794)
				(xy -0.508 0.2794) (xy -0.5334 0.2794)
			)
			(stroke
				(width 0)
				(type default)
			)
			(fill no)
			(layer "F.CrtYd")
		)
		(pad "1" smd rect
			(at 0.40005 0 90)
			(size 0.4572 0.508)
			(layers "F.Cu" "F.Mask" "F.Paste")
			(net "P12V")
		)
		(pad "2" smd rect
			(at -0.40005 0 90)
			(size 0.4572 0.508)
			(layers "F.Cu" "F.Mask" "F.Paste")
			(net "GND")
		)
	)
	(footprint ""
		(layer "F.Cu")
		(at 49.873662 -374.437148 180)
		(property "Reference" "CE17"
			(at -5.288534 -1.081024 0)
			(unlocked yes)
			(layer "F.SilkS")
			(effects
				(font
					(size 0.7874 0.5842)
					(thickness 0.1524)
				)
				(justify left)
			)
		)
		(property "Value" ""
			(at 0 0 180)
			(layer "F.Fab")
			(effects
				(font
					(size 1.27 1.27)
				)
			)
		)
		(duplicate_pad_numbers_are_jumpers no)
		(fp_line
			(start 0 -4.2672)
			(end 0 4.2672)
			(stroke
				(width 0.1524)
				(type default)
			)
			(layer "F.SilkS")
		)
		(fp_circle
			(center 0 0)
			(end -4.2672 0)
			(stroke
				(width 0.1524)
				(type default)
			)
			(fill no)
			(layer "F.SilkS")
		)
		(fp_poly
			(pts
				(arc
					(start 0 -4.2672)
					(mid 4.2672 0)
					(end 0 4.2672)
				)
			)
			(stroke
				(width 0)
				(type default)
			)
			(fill yes)
			(layer "F.SilkS")
		)
		(fp_poly
			(pts
				(xy -2.5146 -0.762) (xy -0.9906 -0.762) (xy -0.9906 0.762) (xy -2.5146 0.762)
			)
			(stroke
				(width 0)
				(type default)
			)
			(fill no)
			(layer "B.CrtYd")
		)
		(fp_poly
			(pts
				(arc
					(start 1.7526 0.762)
					(mid 2.291415 -0.538815)
					(end 0.9906 0)
				)
				(arc
					(start 0.9906 0.0254)
					(mid 1.206345 0.546255)
					(end 1.7272 0.762)
				)
			)
			(stroke
				(width 0)
				(type default)
			)
			(fill no)
			(layer "B.CrtYd")
		)
		(fp_poly
			(pts
				(arc
					(start -4.2672 0)
					(mid 4.2672 0)
					(end -4.2672 0)
				)
			)
			(stroke
				(width 0)
				(type default)
			)
			(fill no)
			(layer "F.CrtYd")
		)
		(fp_circle
			(center 0 0)
			(end -4.2672 0)
			(stroke
				(width 0.1)
				(type default)
			)
			(fill no)
			(layer "F.Fab")
		)
		(fp_text user "+"
			(at -5.468874 1.015492 180)
			(unlocked yes)
			(layer "F.SilkS")
			(effects
				(font
					(size 1.905 1.4224)
					(thickness 0.1524)
				)
				(justify left)
			)
		)
		(fp_text user "+"
			(at -5.6642 -0.34925 180)
			(unlocked yes)
			(layer "F.Fab")
			(effects
				(font
					(size 1.905 1.4224)
					(thickness 0.000001)
				)
				(justify left)
			)
		)
		(pad "1" thru_hole rect
			(at -1.75006 0 180)
			(size 1.397 1.397)
			(drill 0.9144)
			(layers "*.Cu" "*.Mask")
			(remove_unused_layers no)
			(net "P12V")
			(clearance 0.0127)
			(thermal_gap 0.0127)
			(padstack
				(mode front_inner_back)
				(layer "Inner"
					(shape circle)
					(size 1.397 1.397)
					(clearance 0.0127)
				)
				(layer "B.Cu"
					(shape rect)
					(size 1.397 1.397)
					(clearance 0.0127)
				)
			)
		)
		(pad "2" thru_hole circle
			(at 1.75006 0 180)
			(size 1.397 1.397)
			(drill 0.9144)
			(layers "*.Cu" "*.Mask")
			(remove_unused_layers no)
			(net "GND")
			(clearance 0.0127)
			(thermal_gap 0.0127)
		)
	)
	(footprint ""
		(layer "F.Cu")
		(at 66.7004 -209.195416 180)
		(property "Reference" "R119"
			(at 0.958596 0.97282 0)
			(unlocked yes)
			(layer "F.SilkS")
			(effects
				(font
					(size 0.7874 0.5842)
					(thickness 0.1524)
				)
				(justify left)
			)
		)
		(property "Value" ""
			(at 0 0 180)
			(layer "F.Fab")
			(effects
				(font
					(size 1.27 1.27)
				)
			)
		)
		(duplicate_pad_numbers_are_jumpers no)
		(fp_line
			(start 0.7874 0.4064)
			(end -0.7874 0.4064)
			(stroke
				(width 0.1524)
				(type default)
			)
			(layer "F.SilkS")
		)
		(fp_line
			(start 0.7874 -0.4064)
			(end 0.7874 0.4064)
			(stroke
				(width 0.1524)
				(type default)
			)
			(layer "F.SilkS")
		)
		(fp_line
			(start -0.7874 0.4064)
			(end -0.7874 -0.4064)
			(stroke
				(width 0.1524)
				(type default)
			)
			(layer "F.SilkS")
		)
		(fp_line
			(start -0.7874 -0.4064)
			(end 0.7874 -0.4064)
			(stroke
				(width 0.1524)
				(type default)
			)
			(layer "F.SilkS")
		)
		(fp_poly
			(pts
				(xy -0.508 0.2794) (xy -0.508 0.2286) (xy -0.635 0.2286) (xy -0.635 -0.254) (xy -0.5334 -0.254)
				(xy -0.5334 -0.2794) (xy 0.5334 -0.2794) (xy 0.5334 -0.254) (xy 0.635 -0.254) (xy 0.635 0.254) (xy 0.5334 0.254)
				(xy 0.5334 0.2794)
			)
			(stroke
				(width 0)
				(type default)
			)
			(fill no)
			(layer "F.CrtYd")
		)
		(pad "1" smd rect
			(at 0.40005 0 180)
			(size 0.4572 0.508)
			(layers "F.Cu" "F.Mask" "F.Paste")
			(net "PSU3_REMOTE_R2_P")
		)
		(pad "2" smd rect
			(at -0.40005 0 180)
			(size 0.4572 0.508)
			(layers "F.Cu" "F.Mask" "F.Paste")
			(net "P12V")
		)
	)
	(footprint ""
		(layer "F.Cu")
		(at 71.11746 -374.411748 -90)
		(property "Reference" "C59"
			(at -2.675128 -0.117856 90)
			(unlocked yes)
			(layer "F.SilkS")
			(effects
				(font
					(size 0.7874 0.5842)
					(thickness 0.1524)
				)
				(justify left)
			)
		)
		(property "Value" ""
			(at 0 0 270)
			(layer "F.Fab")
			(effects
				(font
					(size 1.27 1.27)
				)
			)
		)
		(duplicate_pad_numbers_are_jumpers no)
		(fp_line
			(start -0.7874 0.4064)
			(end -0.7874 -0.4064)
			(stroke
				(width 0.1524)
				(type default)
			)
			(layer "F.SilkS")
		)
		(fp_line
			(start 0.7874 0.4064)
			(end -0.7874 0.4064)
			(stroke
				(width 0.1524)
				(type default)
			)
			(layer "F.SilkS")
		)
		(fp_line
			(start 0 0.381)
			(end 0 -0.381)
			(stroke
				(width 0.1524)
				(type default)
			)
			(layer "F.SilkS")
		)
		(fp_line
			(start -0.7874 -0.4064)
			(end 0.7874 -0.4064)
			(stroke
				(width 0.1524)
				(type default)
			)
			(layer "F.SilkS")
		)
		(fp_line
			(start 0.7874 -0.4064)
			(end 0.7874 0.4064)
			(stroke
				(width 0.1524)
				(type default)
			)
			(layer "F.SilkS")
		)
		(fp_poly
			(pts
				(xy -0.5334 0.254) (xy -0.635 0.254) (xy -0.635 0.2286) (xy -0.635 -0.254) (xy -0.5334 -0.254) (xy -0.5334 -0.2794)
				(xy 0.5334 -0.2794) (xy 0.5334 -0.254) (xy 0.635 -0.254) (xy 0.635 0.254) (xy 0.5334 0.254) (xy 0.5334 0.2794)
				(xy -0.508 0.2794) (xy -0.5334 0.2794)
			)
			(stroke
				(width 0)
				(type default)
			)
			(fill no)
			(layer "F.CrtYd")
		)
		(pad "1" smd rect
			(at 0.40005 0 270)
			(size 0.4572 0.508)
			(layers "F.Cu" "F.Mask" "F.Paste")
			(net "P12V")
		)
		(pad "2" smd rect
			(at -0.40005 0 270)
			(size 0.4572 0.508)
			(layers "F.Cu" "F.Mask" "F.Paste")
			(net "GND")
		)
	)
	(footprint ""
		(layer "F.Cu")
		(at 69.549518 -483.48138 90)
		(property "Reference" "C84"
			(at -4.090162 -0.14605 90)
			(unlocked yes)
			(layer "F.SilkS")
			(effects
				(font
					(size 0.7874 0.5842)
					(thickness 0.1524)
				)
				(justify left)
			)
		)
		(property "Value" ""
			(at 0 0 90)
			(layer "F.Fab")
			(effects
				(font
					(size 1.27 1.27)
				)
			)
		)
		(duplicate_pad_numbers_are_jumpers no)
		(fp_line
			(start 0.7874 -0.4064)
			(end 0.7874 0.4064)
			(stroke
				(width 0.1524)
				(type default)
			)
			(layer "F.SilkS")
		)
		(fp_line
			(start -0.7874 -0.4064)
			(end 0.7874 -0.4064)
			(stroke
				(width 0.1524)
				(type default)
			)
			(layer "F.SilkS")
		)
		(fp_line
			(start 0 0.381)
			(end 0 -0.381)
			(stroke
				(width 0.1524)
				(type default)
			)
			(layer "F.SilkS")
		)
		(fp_line
			(start 0.7874 0.4064)
			(end -0.7874 0.4064)
			(stroke
				(width 0.1524)
				(type default)
			)
			(layer "F.SilkS")
		)
		(fp_line
			(start -0.7874 0.4064)
			(end -0.7874 -0.4064)
			(stroke
				(width 0.1524)
				(type default)
			)
			(layer "F.SilkS")
		)
		(fp_poly
			(pts
				(xy -0.5334 0.254) (xy -0.635 0.254) (xy -0.635 0.2286) (xy -0.635 -0.254) (xy -0.5334 -0.254) (xy -0.5334 -0.2794)
				(xy 0.5334 -0.2794) (xy 0.5334 -0.254) (xy 0.635 -0.254) (xy 0.635 0.254) (xy 0.5334 0.254) (xy 0.5334 0.2794)
				(xy -0.508 0.2794) (xy -0.5334 0.2794)
			)
			(stroke
				(width 0)
				(type default)
			)
			(fill no)
			(layer "F.CrtYd")
		)
		(pad "1" smd rect
			(at 0.40005 0 90)
			(size 0.4572 0.508)
			(layers "F.Cu" "F.Mask" "F.Paste")
			(net "P12V")
		)
		(pad "2" smd rect
			(at -0.40005 0 90)
			(size 0.4572 0.508)
			(layers "F.Cu" "F.Mask" "F.Paste")
			(net "GND")
		)
	)
	(footprint ""
		(layer "F.Cu")
		(at 46.365922 -257.889502 180)
		(property "Reference" "R107"
			(at -1.032002 -0.406908 0)
			(unlocked yes)
			(layer "F.SilkS")
			(effects
				(font
					(size 0.7874 0.5842)
					(thickness 0.1524)
				)
				(justify left)
			)
		)
		(property "Value" ""
			(at 0 0 180)
			(layer "F.Fab")
			(effects
				(font
					(size 1.27 1.27)
				)
			)
		)
		(duplicate_pad_numbers_are_jumpers no)
		(fp_line
			(start 0.7874 0.4064)
			(end -0.7874 0.4064)
			(stroke
				(width 0.1524)
				(type default)
			)
			(layer "F.SilkS")
		)
		(fp_line
			(start 0.7874 -0.4064)
			(end 0.7874 0.4064)
			(stroke
				(width 0.1524)
				(type default)
			)
			(layer "F.SilkS")
		)
		(fp_line
			(start -0.7874 0.4064)
			(end -0.7874 -0.4064)
			(stroke
				(width 0.1524)
				(type default)
			)
			(layer "F.SilkS")
		)
		(fp_line
			(start -0.7874 -0.4064)
			(end 0.7874 -0.4064)
			(stroke
				(width 0.1524)
				(type default)
			)
			(layer "F.SilkS")
		)
		(fp_poly
			(pts
				(xy -0.508 0.2794) (xy -0.508 0.2286) (xy -0.635 0.2286) (xy -0.635 -0.254) (xy -0.5334 -0.254)
				(xy -0.5334 -0.2794) (xy 0.5334 -0.2794) (xy 0.5334 -0.254) (xy 0.635 -0.254) (xy 0.635 0.254) (xy 0.5334 0.254)
				(xy 0.5334 0.2794)
			)
			(stroke
				(width 0)
				(type default)
			)
			(fill no)
			(layer "F.CrtYd")
		)
		(pad "1" smd rect
			(at 0.40005 0 180)
			(size 0.4572 0.508)
			(layers "F.Cu" "F.Mask" "F.Paste")
			(net "PSU4_REMOTE_R_N")
		)
		(pad "2" smd rect
			(at -0.40005 0 180)
			(size 0.4572 0.508)
			(layers "F.Cu" "F.Mask" "F.Paste")
			(net "GND")
		)
	)
	(footprint ""
		(layer "F.Cu")
		(at 78.000098 -519.049762)
		(property "Reference" "H1"
			(at -5.872734 -7.468108 0)
			(unlocked yes)
			(layer "F.SilkS")
			(effects
				(font
					(size 0.7874 0.5842)
					(thickness 0.1524)
				)
				(justify left)
			)
		)
		(property "Value" ""
			(at 0 0 0)
			(layer "F.Fab")
			(effects
				(font
					(size 1.27 1.27)
				)
			)
		)
		(duplicate_pad_numbers_are_jumpers no)
		(fp_circle
			(center 0 0)
			(end 7.999984 0)
			(stroke
				(width 0.1524)
				(type default)
			)
			(fill no)
			(layer "F.SilkS")
		)
		(fp_circle
			(center 0 0)
			(end 14.7066 0)
			(stroke
				(width 0.1524)
				(type default)
			)
			(fill no)
			(layer "B.SilkS")
		)
		(fp_poly
			(pts
				(arc
					(start 5.0038 0)
					(mid -5.0038 0)
					(end 5.0038 0)
				)
			)
			(stroke
				(width 0)
				(type default)
			)
			(fill no)
			(layer "F.CrtYd")
		)
		(pad "" np_thru_hole circle
			(at 0 0)
			(size 4.0132 4.0132)
			(drill 4.0132)
			(layers "*.Cu" "*.Mask")
			(clearance 0.381)
			(thermal_gap 0.381)
		)
		(pad "2" thru_hole circle
			(at 0 -3.50012)
			(size 0.762 0.762)
			(drill 0.5588)
			(layers "*.Cu" "*.Mask")
			(remove_unused_layers no)
			(net "GND")
			(clearance 0.1524)
			(thermal_gap 0.1524)
		)
		(pad "3" thru_hole circle
			(at -2.500122 -2.500122)
			(size 0.762 0.762)
			(drill 0.5588)
			(layers "*.Cu" "*.Mask")
			(remove_unused_layers no)
			(net "GND")
			(clearance 0.1524)
			(thermal_gap 0.1524)
		)
		(pad "4" thru_hole circle
			(at -3.50012 0)
			(size 0.762 0.762)
			(drill 0.5588)
			(layers "*.Cu" "*.Mask")
			(remove_unused_layers no)
			(net "GND")
			(clearance 0.1524)
			(thermal_gap 0.1524)
		)
		(pad "5" thru_hole circle
			(at -2.500122 2.500122)
			(size 0.762 0.762)
			(drill 0.5588)
			(layers "*.Cu" "*.Mask")
			(remove_unused_layers no)
			(net "GND")
			(clearance 0.1524)
			(thermal_gap 0.1524)
		)
		(pad "6" thru_hole circle
			(at 0 3.50012)
			(size 0.762 0.762)
			(drill 0.5588)
			(layers "*.Cu" "*.Mask")
			(remove_unused_layers no)
			(net "GND")
			(clearance 0.1524)
			(thermal_gap 0.1524)
		)
		(pad "7" thru_hole circle
			(at 2.500122 2.500122)
			(size 0.762 0.762)
			(drill 0.5588)
			(layers "*.Cu" "*.Mask")
			(remove_unused_layers no)
			(net "GND")
			(clearance 0.1524)
			(thermal_gap 0.1524)
		)
		(pad "8" thru_hole circle
			(at 3.50012 0)
			(size 0.762 0.762)
			(drill 0.5588)
			(layers "*.Cu" "*.Mask")
			(remove_unused_layers no)
			(net "GND")
			(clearance 0.1524)
			(thermal_gap 0.1524)
		)
		(pad "9" thru_hole circle
			(at 2.500122 -2.500122)
			(size 0.762 0.762)
			(drill 0.5588)
			(layers "*.Cu" "*.Mask")
			(remove_unused_layers no)
			(net "GND")
			(clearance 0.1524)
			(thermal_gap 0.1524)
		)
		(zone
			(layer "F.Cu")
			(hatch none 0.5)
			(connect_pads
				(clearance 0)
			)
			(min_thickness 0.25)
			(keepout
				(tracks not_allowed)
				(vias allowed)
				(pads allowed)
				(copperpour not_allowed)
				(footprints allowed)
			)
			(placement
				(enabled no)
				(sheetname "")
			)
			(fill
				(thermal_gap 0.5)
				(thermal_bridge_width 0.5)
				(island_removal_mode 0)
			)
			(polygon
				(pts
					(arc
						(start 78.000098 -527.050762)
						(mid 69.999098 -519.049762)
						(end 78.000098 -511.048762)
					)
					(arc
						(start 78.000098 -511.048762)
						(mid 79.435198 -512.483862)
						(end 78.000098 -513.918962)
					)
					(arc
						(start 78.000098 -513.918962)
						(mid 72.869298 -519.049762)
						(end 78.000098 -524.180562)
					)
					(arc
						(start 78.000098 -524.180562)
						(mid 79.435198 -525.615662)
						(end 78.000098 -527.050762)
					)
				)
			)
		)
		(zone
			(layer "F.Cu")
			(hatch none 0.5)
			(connect_pads
				(clearance 0)
			)
			(min_thickness 0.25)
			(keepout
				(tracks not_allowed)
				(vias allowed)
				(pads allowed)
				(copperpour not_allowed)
				(footprints allowed)
			)
			(placement
				(enabled no)
				(sheetname "")
			)
			(fill
				(thermal_gap 0.5)
				(thermal_bridge_width 0.5)
				(island_removal_mode 0)
			)
			(polygon
				(pts
					(arc
						(start 78.000098 -527.050762)
						(mid 86.001098 -519.049762)
						(end 78.000098 -511.048762)
					)
					(arc
						(start 78.000098 -511.048762)
						(mid 76.564998 -512.483862)
						(end 78.000098 -513.918962)
					)
					(arc
						(start 78.000098 -513.918962)
						(mid 83.130898 -519.049762)
						(end 78.000098 -524.180562)
					)
					(arc
						(start 78.000098 -524.180562)
						(mid 76.564998 -525.615662)
						(end 78.000098 -527.050762)
					)
				)
			)
		)
		(zone
			(layers "F.Cu" "B.Cu" "In1.Cu" "In2.Cu" "In3.Cu" "In4.Cu" "In5.Cu" "In6.Cu")
			(hatch none 0.5)
			(connect_pads
				(clearance 0)
			)
			(min_thickness 0.25)
			(keepout
				(tracks not_allowed)
				(vias allowed)
				(pads allowed)
				(copperpour not_allowed)
				(footprints allowed)
			)
			(placement
				(enabled no)
				(sheetname "")
			)
			(fill
				(thermal_gap 0.5)
				(thermal_bridge_width 0.5)
				(island_removal_mode 0)
			)
			(polygon
				(pts
					(arc
						(start 80.512158 -519.049762)
						(mid 75.488038 -519.049762)
						(end 80.512158 -519.049762)
					)
				)
			)
		)
	)
	(footprint ""
		(layer "F.Cu")
		(at 13.964666 -17.907 -90)
		(property "Reference" "J19"
			(at -4.500372 7.138416 0)
			(unlocked yes)
			(layer "F.SilkS")
			(effects
				(font
					(size 0.7874 0.5842)
					(thickness 0.1524)
				)
				(justify left)
			)
		)
		(property "Value" ""
			(at 0 0 270)
			(layer "F.Fab")
			(effects
				(font
					(size 1.27 1.27)
				)
			)
		)
		(duplicate_pad_numbers_are_jumpers no)
		(fp_line
			(start -3.370072 12.830048)
			(end -3.370072 -3.81)
			(stroke
				(width 0.1524)
				(type default)
			)
			(layer "F.SilkS")
		)
		(fp_line
			(start 12.260072 12.830048)
			(end -3.370072 12.830048)
			(stroke
				(width 0.1524)
				(type default)
			)
			(layer "F.SilkS")
		)
		(fp_line
			(start -3.370072 -3.81)
			(end 12.260072 -3.81)
			(stroke
				(width 0.1524)
				(type default)
			)
			(layer "F.SilkS")
		)
		(fp_line
			(start 12.260072 -3.81)
			(end 12.260072 12.830048)
			(stroke
				(width 0.1524)
				(type default)
			)
			(layer "F.SilkS")
		)
		(fp_poly
			(pts
				(xy -3.631946 2.173224) (xy -3.856736 3.752596) (xy -5.03047 2.940812)
			)
			(stroke
				(width 0)
				(type default)
			)
			(fill yes)
			(layer "F.SilkS")
		)
		(fp_poly
			(pts
				(xy -0.762 0.762) (xy 8.382 0.762) (xy 8.382 -1.8034) (xy 9.652 -1.8034) (xy 9.652 -3.302) (xy 0.508 -3.302)
				(xy 0.508 -0.762) (xy -0.762 -0.762)
			)
			(stroke
				(width 0)
				(type default)
			)
			(fill no)
			(layer "B.CrtYd")
		)
		(fp_poly
			(pts
				(arc
					(start -1.27 4.4196)
					(mid -1.27 8.2804)
					(end -1.27 4.4196)
				)
			)
			(stroke
				(width 0)
				(type default)
			)
			(fill no)
			(layer "B.CrtYd")
		)
		(fp_poly
			(pts
				(arc
					(start 10.16 4.4196)
					(mid 10.16 8.2804)
					(end 10.16 4.4196)
				)
			)
			(stroke
				(width 0)
				(type default)
			)
			(fill no)
			(layer "B.CrtYd")
		)
		(fp_poly
			(pts
				(xy -3.370072 12.830048) (xy 12.260072 12.830048) (xy 12.260072 -3.81) (xy -3.370072 -3.81)
			)
			(stroke
				(width 0)
				(type default)
			)
			(fill no)
			(layer "F.CrtYd")
		)
		(fp_line
			(start -3.370072 12.830048)
			(end -3.370072 -3.81)
			(stroke
				(width 0.1)
				(type default)
			)
			(layer "F.Fab")
		)
		(fp_line
			(start 12.260072 12.830048)
			(end -3.370072 12.830048)
			(stroke
				(width 0.1)
				(type default)
			)
			(layer "F.Fab")
		)
		(fp_line
			(start -3.370072 -3.81)
			(end 12.260072 -3.81)
			(stroke
				(width 0.1)
				(type default)
			)
			(layer "F.Fab")
		)
		(fp_line
			(start 12.260072 -3.81)
			(end 12.260072 12.830048)
			(stroke
				(width 0.1)
				(type default)
			)
			(layer "F.Fab")
		)
		(fp_poly
			(pts
				(xy -3.576828 0) (xy -5.0038 0.713486) (xy -5.0038 -0.713486)
			)
			(stroke
				(width 0)
				(type default)
			)
			(fill yes)
			(layer "F.Fab")
		)
		(fp_text user "1"
			(at -3.98399 1.897126 0)
			(unlocked yes)
			(layer "F.SilkS")
			(effects
				(font
					(size 0.7874 0.5842)
					(thickness 0.1524)
				)
			)
		)
		(fp_text user "7"
			(at 12.980924 0.338836 0)
			(unlocked yes)
			(layer "F.SilkS")
			(effects
				(font
					(size 0.7874 0.5842)
					(thickness 0.1524)
				)
			)
		)
		(fp_text user "8"
			(at 12.95019 -2.418334 0)
			(unlocked yes)
			(layer "F.SilkS")
			(effects
				(font
					(size 0.7874 0.5842)
					(thickness 0.1524)
				)
			)
		)
		(fp_text user "2"
			(at -2.72923 -4.624832 0)
			(unlocked yes)
			(layer "F.SilkS")
			(effects
				(font
					(size 0.7874 0.5842)
					(thickness 0.1524)
				)
			)
		)
		(fp_text user "7"
			(at 9.215628 0.267208 0)
			(unlocked yes)
			(layer "B.SilkS")
			(effects
				(font
					(size 0.7874 0.5842)
					(thickness 0.1524)
				)
				(justify mirror)
			)
		)
		(fp_text user "1"
			(at -1.522476 0.234442 0)
			(unlocked yes)
			(layer "B.SilkS")
			(effects
				(font
					(size 0.7874 0.5842)
					(thickness 0.1524)
				)
				(justify mirror)
			)
		)
		(fp_text user "8"
			(at 10.566146 -2.883662 0)
			(unlocked yes)
			(layer "B.SilkS")
			(effects
				(font
					(size 0.7874 0.5842)
					(thickness 0.1524)
				)
				(justify mirror)
			)
		)
		(fp_text user "2"
			(at -0.42418 -2.948178 0)
			(unlocked yes)
			(layer "B.SilkS")
			(effects
				(font
					(size 0.7874 0.5842)
					(thickness 0.1524)
				)
				(justify mirror)
			)
		)
		(fp_text user "7"
			(at 8.8138 0.238252 270)
			(unlocked yes)
			(layer "B.Fab")
			(effects
				(font
					(size 0.7874 0.5842)
					(thickness 0.000001)
				)
				(justify mirror)
			)
		)
		(fp_text user "1"
			(at -1.2954 0.085852 270)
			(unlocked yes)
			(layer "B.Fab")
			(effects
				(font
					(size 0.7874 0.5842)
					(thickness 0.000001)
				)
				(justify mirror)
			)
		)
		(fp_text user "8"
			(at 10.0838 -2.403348 270)
			(unlocked yes)
			(layer "B.Fab")
			(effects
				(font
					(size 0.7874 0.5842)
					(thickness 0.000001)
				)
				(justify mirror)
			)
		)
		(fp_text user "2"
			(at 0 -2.581148 270)
			(unlocked yes)
			(layer "B.Fab")
			(effects
				(font
					(size 0.7874 0.5842)
					(thickness 0.000001)
				)
				(justify mirror)
			)
		)
		(fp_text user "7"
			(at 12.7762 -0.091948 270)
			(unlocked yes)
			(layer "F.Fab")
			(effects
				(font
					(size 0.7874 0.5842)
					(thickness 0.000001)
				)
			)
		)
		(fp_text user "1"
			(at -3.9116 -0.930148 270)
			(unlocked yes)
			(layer "F.Fab")
			(effects
				(font
					(size 0.7874 0.5842)
					(thickness 0.000001)
				)
			)
		)
		(fp_text user "2"
			(at -3.9624 -2.428748 270)
			(unlocked yes)
			(layer "F.Fab")
			(effects
				(font
					(size 0.7874 0.5842)
					(thickness 0.000001)
				)
			)
		)
		(fp_text user "8"
			(at 12.7762 -2.555748 270)
			(unlocked yes)
			(layer "F.Fab")
			(effects
				(font
					(size 0.7874 0.5842)
					(thickness 0.000001)
				)
			)
		)
		(pad "" np_thru_hole circle
			(at -1.27 6.35 270)
			(size 3.3528 3.3528)
			(drill 3.3528)
			(layers "*.Cu" "*.Mask")
			(clearance 0.381)
			(thermal_gap 0.381)
		)
		(pad "" np_thru_hole circle
			(at 10.16 6.35 270)
			(size 3.3528 3.3528)
			(drill 3.3528)
			(layers "*.Cu" "*.Mask")
			(clearance 0.381)
			(thermal_gap 0.381)
		)
		(pad "1" thru_hole rect
			(at 0 0 270)
			(size 1.397 1.397)
			(drill 0.9906)
			(layers "*.Cu" "*.Mask")
			(remove_unused_layers no)
			(net "UART_RTS_P1_L_N")
			(clearance 0.0508)
			(thermal_gap 0.0508)
			(padstack
				(mode front_inner_back)
				(layer "Inner"
					(shape circle)
					(size 1.397 1.397)
					(clearance 0.0508)
				)
				(layer "B.Cu"
					(shape rect)
					(size 1.397 1.397)
					(clearance 0.0508)
				)
			)
		)
		(pad "2" thru_hole circle
			(at 1.27 -2.54 270)
			(size 1.397 1.397)
			(drill 0.9906)
			(layers "*.Cu" "*.Mask")
			(remove_unused_layers no)
			(net "UART_DSR_P1_L_N")
			(clearance 0.0508)
			(thermal_gap 0.0508)
		)
		(pad "3" thru_hole circle
			(at 2.54 0 270)
			(size 1.397 1.397)
			(drill 0.9906)
			(layers "*.Cu" "*.Mask")
			(remove_unused_layers no)
			(net "UART_RX_P1_L")
			(clearance 0.0508)
			(thermal_gap 0.0508)
		)
		(pad "4" thru_hole circle
			(at 3.81 -2.54 270)
			(size 1.397 1.397)
			(drill 0.9906)
			(layers "*.Cu" "*.Mask")
			(remove_unused_layers no)
			(net "GND")
			(clearance 0.0508)
			(thermal_gap 0.0508)
		)
		(pad "5" thru_hole circle
			(at 5.08 0 270)
			(size 1.397 1.397)
			(drill 0.9906)
			(layers "*.Cu" "*.Mask")
			(remove_unused_layers no)
			(net "GND")
			(clearance 0.0508)
			(thermal_gap 0.0508)
		)
		(pad "6" thru_hole circle
			(at 6.35 -2.54 270)
			(size 1.397 1.397)
			(drill 0.9906)
			(layers "*.Cu" "*.Mask")
			(remove_unused_layers no)
			(net "UART_TX_P1_L")
			(clearance 0.0508)
			(thermal_gap 0.0508)
		)
		(pad "7" thru_hole circle
			(at 7.62 0 270)
			(size 1.397 1.397)
			(drill 0.9906)
			(layers "*.Cu" "*.Mask")
			(remove_unused_layers no)
			(net "UART_DTR_P1_L_N")
			(clearance 0.0508)
			(thermal_gap 0.0508)
		)
		(pad "8" thru_hole circle
			(at 8.89 -2.54 270)
			(size 1.397 1.397)
			(drill 0.9906)
			(layers "*.Cu" "*.Mask")
			(remove_unused_layers no)
			(net "UART_CTS_P1_L_N")
			(clearance 0.0508)
			(thermal_gap 0.0508)
		)
		(zone
			(layers "F.Cu" "B.Cu" "In1.Cu" "In2.Cu" "In3.Cu" "In4.Cu" "In5.Cu" "In6.Cu")
			(hatch none 0.5)
			(connect_pads
				(clearance 0)
			)
			(min_thickness 0.25)
			(keepout
				(tracks not_allowed)
				(vias allowed)
				(pads allowed)
				(copperpour not_allowed)
				(footprints allowed)
			)
			(placement
				(enabled no)
				(sheetname "")
			)
			(fill
				(thermal_gap 0.5)
				(thermal_bridge_width 0.5)
				(island_removal_mode 0)
			)
			(polygon
				(pts
					(arc
						(start 9.697466 -19.177)
						(mid 5.531866 -19.177)
						(end 9.697466 -19.177)
					)
				)
			)
		)
		(zone
			(layers "F.Cu" "B.Cu" "In1.Cu" "In2.Cu" "In3.Cu" "In4.Cu" "In5.Cu" "In6.Cu")
			(hatch none 0.5)
			(connect_pads
				(clearance 0)
			)
			(min_thickness 0.25)
			(keepout
				(tracks not_allowed)
				(vias allowed)
				(pads allowed)
				(copperpour not_allowed)
				(footprints allowed)
			)
			(placement
				(enabled no)
				(sheetname "")
			)
			(fill
				(thermal_gap 0.5)
				(thermal_bridge_width 0.5)
				(island_removal_mode 0)
			)
			(polygon
				(pts
					(arc
						(start 9.697466 -7.747)
						(mid 5.531866 -7.747)
						(end 9.697466 -7.747)
					)
				)
			)
		)
	)
	(footprint ""
		(layer "F.Cu")
		(at 78.062074 -387.197854 180)
		(property "Reference" "R127"
			(at 0.888492 1.176274 0)
			(unlocked yes)
			(layer "F.SilkS")
			(effects
				(font
					(size 0.7874 0.5842)
					(thickness 0.1524)
				)
				(justify left)
			)
		)
		(property "Value" ""
			(at 0 0 180)
			(layer "F.Fab")
			(effects
				(font
					(size 1.27 1.27)
				)
			)
		)
		(duplicate_pad_numbers_are_jumpers no)
		(fp_line
			(start 0.7874 0.4064)
			(end -0.7874 0.4064)
			(stroke
				(width 0.1524)
				(type default)
			)
			(layer "F.SilkS")
		)
		(fp_line
			(start 0.7874 -0.4064)
			(end 0.7874 0.4064)
			(stroke
				(width 0.1524)
				(type default)
			)
			(layer "F.SilkS")
		)
		(fp_line
			(start -0.7874 0.4064)
			(end -0.7874 -0.4064)
			(stroke
				(width 0.1524)
				(type default)
			)
			(layer "F.SilkS")
		)
		(fp_line
			(start -0.7874 -0.4064)
			(end 0.7874 -0.4064)
			(stroke
				(width 0.1524)
				(type default)
			)
			(layer "F.SilkS")
		)
		(fp_poly
			(pts
				(xy -0.508 0.2794) (xy -0.508 0.2286) (xy -0.635 0.2286) (xy -0.635 -0.254) (xy -0.5334 -0.254)
				(xy -0.5334 -0.2794) (xy 0.5334 -0.2794) (xy 0.5334 -0.254) (xy 0.635 -0.254) (xy 0.635 0.254) (xy 0.5334 0.254)
				(xy 0.5334 0.2794)
			)
			(stroke
				(width 0)
				(type default)
			)
			(fill no)
			(layer "F.CrtYd")
		)
		(pad "1" smd rect
			(at 0.40005 0 180)
			(size 0.4572 0.508)
			(layers "F.Cu" "F.Mask" "F.Paste")
			(net "PSU5_REMOTE_R2_P")
		)
		(pad "2" smd rect
			(at -0.40005 0 180)
			(size 0.4572 0.508)
			(layers "F.Cu" "F.Mask" "F.Paste")
			(net "P12V")
		)
	)
	(footprint ""
		(layer "F.Cu")
		(at 13.36929 -320.828162 180)
		(property "Reference" "R144"
			(at -1.74244 -0.214122 0)
			(unlocked yes)
			(layer "F.SilkS")
			(effects
				(font
					(size 0.7874 0.5842)
					(thickness 0.1524)
				)
				(justify left)
			)
		)
		(property "Value" ""
			(at 0 0 180)
			(layer "F.Fab")
			(effects
				(font
					(size 1.27 1.27)
				)
			)
		)
		(duplicate_pad_numbers_are_jumpers no)
		(fp_line
			(start 0.7874 0.4064)
			(end -0.7874 0.4064)
			(stroke
				(width 0.1524)
				(type default)
			)
			(layer "F.SilkS")
		)
		(fp_line
			(start 0.7874 -0.4064)
			(end 0.7874 0.4064)
			(stroke
				(width 0.1524)
				(type default)
			)
			(layer "F.SilkS")
		)
		(fp_line
			(start -0.7874 0.4064)
			(end -0.7874 -0.4064)
			(stroke
				(width 0.1524)
				(type default)
			)
			(layer "F.SilkS")
		)
		(fp_line
			(start -0.7874 -0.4064)
			(end 0.7874 -0.4064)
			(stroke
				(width 0.1524)
				(type default)
			)
			(layer "F.SilkS")
		)
		(fp_poly
			(pts
				(xy -0.508 0.2794) (xy -0.508 0.2286) (xy -0.635 0.2286) (xy -0.635 -0.254) (xy -0.5334 -0.254)
				(xy -0.5334 -0.2794) (xy 0.5334 -0.2794) (xy 0.5334 -0.254) (xy 0.635 -0.254) (xy 0.635 0.254) (xy 0.5334 0.254)
				(xy 0.5334 0.2794)
			)
			(stroke
				(width 0)
				(type default)
			)
			(fill no)
			(layer "F.CrtYd")
		)
		(pad "1" smd rect
			(at 0.40005 0 180)
			(size 0.4572 0.508)
			(layers "F.Cu" "F.Mask" "F.Paste")
			(net "FAN3_TACH")
		)
		(pad "2" smd rect
			(at -0.40005 0 180)
			(size 0.4572 0.508)
			(layers "F.Cu" "F.Mask" "F.Paste")
			(net "P12V")
		)
	)
	(footprint ""
		(layer "F.Cu")
		(at 26.125678 -278.486362 180)
		(property "Reference" "R52"
			(at 3.845306 0.107188 0)
			(unlocked yes)
			(layer "F.SilkS")
			(effects
				(font
					(size 0.7874 0.5842)
					(thickness 0.1524)
				)
				(justify left)
			)
		)
		(property "Value" ""
			(at 0 0 180)
			(layer "F.Fab")
			(effects
				(font
					(size 1.27 1.27)
				)
			)
		)
		(duplicate_pad_numbers_are_jumpers no)
		(fp_line
			(start 0.7874 0.4064)
			(end -0.7874 0.4064)
			(stroke
				(width 0.1524)
				(type default)
			)
			(layer "F.SilkS")
		)
		(fp_line
			(start 0.7874 -0.4064)
			(end 0.7874 0.4064)
			(stroke
				(width 0.1524)
				(type default)
			)
			(layer "F.SilkS")
		)
		(fp_line
			(start -0.7874 0.4064)
			(end -0.7874 -0.4064)
			(stroke
				(width 0.1524)
				(type default)
			)
			(layer "F.SilkS")
		)
		(fp_line
			(start -0.7874 -0.4064)
			(end 0.7874 -0.4064)
			(stroke
				(width 0.1524)
				(type default)
			)
			(layer "F.SilkS")
		)
		(fp_poly
			(pts
				(xy -0.508 0.2794) (xy -0.508 0.2286) (xy -0.635 0.2286) (xy -0.635 -0.254) (xy -0.5334 -0.254)
				(xy -0.5334 -0.2794) (xy 0.5334 -0.2794) (xy 0.5334 -0.254) (xy 0.635 -0.254) (xy 0.635 0.254) (xy 0.5334 0.254)
				(xy 0.5334 0.2794)
			)
			(stroke
				(width 0)
				(type default)
			)
			(fill no)
			(layer "F.CrtYd")
		)
		(pad "1" smd rect
			(at 0.40005 0 180)
			(size 0.4572 0.508)
			(layers "F.Cu" "F.Mask" "F.Paste")
			(net "GND")
		)
		(pad "2" smd rect
			(at -0.40005 0 180)
			(size 0.4572 0.508)
			(layers "F.Cu" "F.Mask" "F.Paste")
			(net "PSU4_PS_ON_N")
		)
	)
	(footprint ""
		(layer "F.Cu")
		(at 26.102056 -277.377144)
		(property "Reference" "R56"
			(at -4.060444 0.200152 0)
			(unlocked yes)
			(layer "F.SilkS")
			(effects
				(font
					(size 0.7874 0.5842)
					(thickness 0.1524)
				)
				(justify left)
			)
		)
		(property "Value" ""
			(at 0 0 0)
			(layer "F.Fab")
			(effects
				(font
					(size 1.27 1.27)
				)
			)
		)
		(duplicate_pad_numbers_are_jumpers no)
		(fp_line
			(start -0.7874 -0.4064)
			(end 0.7874 -0.4064)
			(stroke
				(width 0.1524)
				(type default)
			)
			(layer "F.SilkS")
		)
		(fp_line
			(start -0.7874 0.4064)
			(end -0.7874 -0.4064)
			(stroke
				(width 0.1524)
				(type default)
			)
			(layer "F.SilkS")
		)
		(fp_line
			(start 0.7874 -0.4064)
			(end 0.7874 0.4064)
			(stroke
				(width 0.1524)
				(type default)
			)
			(layer "F.SilkS")
		)
		(fp_line
			(start 0.7874 0.4064)
			(end -0.7874 0.4064)
			(stroke
				(width 0.1524)
				(type default)
			)
			(layer "F.SilkS")
		)
		(fp_poly
			(pts
				(xy -0.508 0.2794) (xy -0.508 0.2286) (xy -0.635 0.2286) (xy -0.635 -0.254) (xy -0.5334 -0.254)
				(xy -0.5334 -0.2794) (xy 0.5334 -0.2794) (xy 0.5334 -0.254) (xy 0.635 -0.254) (xy 0.635 0.254) (xy 0.5334 0.254)
				(xy 0.5334 0.2794)
			)
			(stroke
				(width 0)
				(type default)
			)
			(fill no)
			(layer "F.CrtYd")
		)
		(pad "1" smd rect
			(at 0.40005 0)
			(size 0.4572 0.508)
			(layers "F.Cu" "F.Mask" "F.Paste")
			(net "PSU4_PS_KILL")
		)
		(pad "2" smd rect
			(at -0.40005 0)
			(size 0.4572 0.508)
			(layers "F.Cu" "F.Mask" "F.Paste")
			(net "GND")
		)
	)
	(footprint ""
		(layer "F.Cu")
		(at 27.239976 -461.829912)
		(property "Reference" "R22"
			(at -2.45364 -1.05029 0)
			(unlocked yes)
			(layer "F.SilkS")
			(effects
				(font
					(size 0.7874 0.5842)
					(thickness 0.1524)
				)
				(justify left)
			)
		)
		(property "Value" ""
			(at 0 0 0)
			(layer "F.Fab")
			(effects
				(font
					(size 1.27 1.27)
				)
			)
		)
		(duplicate_pad_numbers_are_jumpers no)
		(fp_line
			(start -0.7874 -0.4064)
			(end 0.7874 -0.4064)
			(stroke
				(width 0.1524)
				(type default)
			)
			(layer "F.SilkS")
		)
		(fp_line
			(start -0.7874 0.4064)
			(end -0.7874 -0.4064)
			(stroke
				(width 0.1524)
				(type default)
			)
			(layer "F.SilkS")
		)
		(fp_line
			(start 0.7874 -0.4064)
			(end 0.7874 0.4064)
			(stroke
				(width 0.1524)
				(type default)
			)
			(layer "F.SilkS")
		)
		(fp_line
			(start 0.7874 0.4064)
			(end -0.7874 0.4064)
			(stroke
				(width 0.1524)
				(type default)
			)
			(layer "F.SilkS")
		)
		(fp_poly
			(pts
				(xy -0.508 0.2794) (xy -0.508 0.2286) (xy -0.635 0.2286) (xy -0.635 -0.254) (xy -0.5334 -0.254)
				(xy -0.5334 -0.2794) (xy 0.5334 -0.2794) (xy 0.5334 -0.254) (xy 0.635 -0.254) (xy 0.635 0.254) (xy 0.5334 0.254)
				(xy 0.5334 0.2794)
			)
			(stroke
				(width 0)
				(type default)
			)
			(fill no)
			(layer "F.CrtYd")
		)
		(pad "1" smd rect
			(at 0.40005 0)
			(size 0.4572 0.508)
			(layers "F.Cu" "F.Mask" "F.Paste")
			(net "PSU6_REMOTE_N")
		)
		(pad "2" smd rect
			(at -0.40005 0)
			(size 0.4572 0.508)
			(layers "F.Cu" "F.Mask" "F.Paste")
			(net "GND")
		)
	)
	(footprint ""
		(layer "F.Cu")
		(at 25.931622 -98.10369)
		(property "Reference" "R66"
			(at -4.080256 -0.075692 0)
			(unlocked yes)
			(layer "F.SilkS")
			(effects
				(font
					(size 0.7874 0.5842)
					(thickness 0.1524)
				)
				(justify left)
			)
		)
		(property "Value" ""
			(at 0 0 0)
			(layer "F.Fab")
			(effects
				(font
					(size 1.27 1.27)
				)
			)
		)
		(duplicate_pad_numbers_are_jumpers no)
		(fp_line
			(start -0.7874 -0.4064)
			(end 0.7874 -0.4064)
			(stroke
				(width 0.1524)
				(type default)
			)
			(layer "F.SilkS")
		)
		(fp_line
			(start -0.7874 0.4064)
			(end -0.7874 -0.4064)
			(stroke
				(width 0.1524)
				(type default)
			)
			(layer "F.SilkS")
		)
		(fp_line
			(start 0.7874 -0.4064)
			(end 0.7874 0.4064)
			(stroke
				(width 0.1524)
				(type default)
			)
			(layer "F.SilkS")
		)
		(fp_line
			(start 0.7874 0.4064)
			(end -0.7874 0.4064)
			(stroke
				(width 0.1524)
				(type default)
			)
			(layer "F.SilkS")
		)
		(fp_poly
			(pts
				(xy -0.508 0.2794) (xy -0.508 0.2286) (xy -0.635 0.2286) (xy -0.635 -0.254) (xy -0.5334 -0.254)
				(xy -0.5334 -0.2794) (xy 0.5334 -0.2794) (xy 0.5334 -0.254) (xy 0.635 -0.254) (xy 0.635 0.254) (xy 0.5334 0.254)
				(xy 0.5334 0.2794)
			)
			(stroke
				(width 0)
				(type default)
			)
			(fill no)
			(layer "F.CrtYd")
		)
		(pad "1" smd rect
			(at 0.40005 0)
			(size 0.4572 0.508)
			(layers "F.Cu" "F.Mask" "F.Paste")
			(net "PSU2_PS_KILL")
		)
		(pad "2" smd rect
			(at -0.40005 0)
			(size 0.4572 0.508)
			(layers "F.Cu" "F.Mask" "F.Paste")
			(net "P12V_STBY")
		)
	)
	(footprint ""
		(layer "F.Cu")
		(at 3.331464 -396.058136 180)
		(property "Reference" "R153"
			(at -1.305814 -0.218694 0)
			(unlocked yes)
			(layer "F.SilkS")
			(effects
				(font
					(size 0.7874 0.5842)
					(thickness 0.1524)
				)
				(justify left)
			)
		)
		(property "Value" ""
			(at 0 0 180)
			(layer "F.Fab")
			(effects
				(font
					(size 1.27 1.27)
				)
			)
		)
		(duplicate_pad_numbers_are_jumpers no)
		(fp_line
			(start 0.7874 0.4064)
			(end -0.7874 0.4064)
			(stroke
				(width 0.1524)
				(type default)
			)
			(layer "F.SilkS")
		)
		(fp_line
			(start 0.7874 -0.4064)
			(end 0.7874 0.4064)
			(stroke
				(width 0.1524)
				(type default)
			)
			(layer "F.SilkS")
		)
		(fp_line
			(start -0.7874 0.4064)
			(end -0.7874 -0.4064)
			(stroke
				(width 0.1524)
				(type default)
			)
			(layer "F.SilkS")
		)
		(fp_line
			(start -0.7874 -0.4064)
			(end 0.7874 -0.4064)
			(stroke
				(width 0.1524)
				(type default)
			)
			(layer "F.SilkS")
		)
		(fp_poly
			(pts
				(xy -0.508 0.2794) (xy -0.508 0.2286) (xy -0.635 0.2286) (xy -0.635 -0.254) (xy -0.5334 -0.254)
				(xy -0.5334 -0.2794) (xy 0.5334 -0.2794) (xy 0.5334 -0.254) (xy 0.635 -0.254) (xy 0.635 0.254) (xy 0.5334 0.254)
				(xy 0.5334 0.2794)
			)
			(stroke
				(width 0)
				(type default)
			)
			(fill no)
			(layer "F.CrtYd")
		)
		(pad "1" smd rect
			(at 0.40005 0 180)
			(size 0.4572 0.508)
			(layers "F.Cu" "F.Mask" "F.Paste")
			(net "GND")
		)
		(pad "2" smd rect
			(at -0.40005 0 180)
			(size 0.4572 0.508)
			(layers "F.Cu" "F.Mask" "F.Paste")
			(net "N42132358")
		)
	)
	(footprint ""
		(layer "F.Cu")
		(at 16.263366 -447.797428)
		(property "Reference" "C86"
			(at -1.061212 4.70662 0)
			(unlocked yes)
			(layer "F.SilkS")
			(effects
				(font
					(size 0.7874 0.5842)
					(thickness 0.1524)
				)
				(justify left)
			)
		)
		(property "Value" ""
			(at 0 0 0)
			(layer "F.Fab")
			(effects
				(font
					(size 1.27 1.27)
				)
			)
		)
		(duplicate_pad_numbers_are_jumpers no)
		(fp_line
			(start -1.905 -0.8636)
			(end 1.905 -0.8636)
			(stroke
				(width 0.1524)
				(type default)
			)
			(layer "F.SilkS")
		)
		(fp_line
			(start -1.905 0.8636)
			(end -1.905 -0.8636)
			(stroke
				(width 0.1524)
				(type default)
			)
			(layer "F.SilkS")
		)
		(fp_line
			(start 0 0.8382)
			(end 0 -0.8382)
			(stroke
				(width 0.1524)
				(type default)
			)
			(layer "F.SilkS")
		)
		(fp_line
			(start 1.905 -0.8636)
			(end 1.905 0.8636)
			(stroke
				(width 0.1524)
				(type default)
			)
			(layer "F.SilkS")
		)
		(fp_line
			(start 1.905 0.8636)
			(end -1.905 0.8636)
			(stroke
				(width 0.1524)
				(type default)
			)
			(layer "F.SilkS")
		)
		(fp_rect
			(start -1.524 0.7366)
			(end 1.524 -0.7366)
			(stroke
				(width 0)
				(type default)
			)
			(fill no)
			(layer "F.CrtYd")
		)
		(pad "1" smd rect
			(at 0.94996 0)
			(size 1.1176 1.3716)
			(layers "F.Cu" "F.Mask" "F.Paste")
			(net "P12V")
		)
		(pad "2" smd rect
			(at -0.94996 0)
			(size 1.1176 1.3716)
			(layers "F.Cu" "F.Mask" "F.Paste")
			(net "GND")
		)
	)
	(footprint ""
		(layer "F.Cu")
		(at 74.798682 -19.257772 -90)
		(property "Reference" "C1"
			(at -2.757424 -0.074422 90)
			(unlocked yes)
			(layer "F.SilkS")
			(effects
				(font
					(size 0.7874 0.5842)
					(thickness 0.1524)
				)
			)
		)
		(property "Value" ""
			(at 0 0 270)
			(layer "F.Fab")
			(effects
				(font
					(size 1.27 1.27)
				)
			)
		)
		(duplicate_pad_numbers_are_jumpers no)
		(fp_line
			(start -1.2954 0.5842)
			(end -1.2954 -0.5842)
			(stroke
				(width 0.1524)
				(type default)
			)
			(layer "F.SilkS")
		)
		(fp_line
			(start 1.2954 0.5842)
			(end -1.2954 0.5842)
			(stroke
				(width 0.1524)
				(type default)
			)
			(layer "F.SilkS")
		)
		(fp_line
			(start -1.2954 -0.5842)
			(end 1.2954 -0.5842)
			(stroke
				(width 0.1524)
				(type default)
			)
			(layer "F.SilkS")
		)
		(fp_line
			(start 0 -0.5842)
			(end 0 0.5842)
			(stroke
				(width 0.1524)
				(type default)
			)
			(layer "F.SilkS")
		)
		(fp_line
			(start 1.2954 -0.5842)
			(end 1.2954 0.5842)
			(stroke
				(width 0.1524)
				(type default)
			)
			(layer "F.SilkS")
		)
		(fp_poly
			(pts
				(xy 0.8636 -0.4572) (xy 0.8636 -0.3556) (xy 1.143 -0.3556) (xy 1.143 0.3556) (xy 0.8636 0.3556)
				(xy 0.8636 0.4572) (xy -0.8636 0.4572) (xy -0.8636 0.3556) (xy -1.143 0.3556) (xy -1.143 -0.3556)
				(xy -0.8636 -0.3556) (xy -0.8636 -0.4572)
			)
			(stroke
				(width 0)
				(type default)
			)
			(fill no)
			(layer "F.CrtYd")
		)
		(fp_line
			(start -0.884936 0.504952)
			(end -0.884936 -0.504952)
			(stroke
				(width 0.1)
				(type default)
			)
			(layer "F.Fab")
		)
		(fp_line
			(start 0.884936 0.504952)
			(end -0.884936 0.504952)
			(stroke
				(width 0.1)
				(type default)
			)
			(layer "F.Fab")
		)
		(fp_line
			(start -0.884936 -0.504952)
			(end 0.884936 -0.504952)
			(stroke
				(width 0.1)
				(type default)
			)
			(layer "F.Fab")
		)
		(fp_line
			(start 0.884936 -0.504952)
			(end 0.884936 0.504952)
			(stroke
				(width 0.1)
				(type default)
			)
			(layer "F.Fab")
		)
		(pad "1" smd rect
			(at 0.7366 0)
			(size 0.7112 0.8128)
			(layers "F.Cu" "F.Mask" "F.Paste")
			(net "P12V")
		)
		(pad "2" smd rect
			(at -0.7366 0)
			(size 0.7112 0.8128)
			(layers "F.Cu" "F.Mask" "F.Paste")
			(net "GND")
		)
	)
	(footprint ""
		(layer "F.Cu")
		(at 39.934642 -374.14708)
		(property "Reference" "R44"
			(at 2.011172 0.405638 0)
			(unlocked yes)
			(layer "F.SilkS")
			(effects
				(font
					(size 0.7874 0.5842)
					(thickness 0.1524)
				)
				(justify left)
			)
		)
		(property "Value" ""
			(at 0 0 0)
			(layer "F.Fab")
			(effects
				(font
					(size 1.27 1.27)
				)
			)
		)
		(duplicate_pad_numbers_are_jumpers no)
		(fp_line
			(start -0.7874 -0.4064)
			(end 0.7874 -0.4064)
			(stroke
				(width 0.1524)
				(type default)
			)
			(layer "F.SilkS")
		)
		(fp_line
			(start -0.7874 0.4064)
			(end -0.7874 -0.4064)
			(stroke
				(width 0.1524)
				(type default)
			)
			(layer "F.SilkS")
		)
		(fp_line
			(start 0.7874 -0.4064)
			(end 0.7874 0.4064)
			(stroke
				(width 0.1524)
				(type default)
			)
			(layer "F.SilkS")
		)
		(fp_line
			(start 0.7874 0.4064)
			(end -0.7874 0.4064)
			(stroke
				(width 0.1524)
				(type default)
			)
			(layer "F.SilkS")
		)
		(fp_poly
			(pts
				(xy -0.508 0.2794) (xy -0.508 0.2286) (xy -0.635 0.2286) (xy -0.635 -0.254) (xy -0.5334 -0.254)
				(xy -0.5334 -0.2794) (xy 0.5334 -0.2794) (xy 0.5334 -0.254) (xy 0.635 -0.254) (xy 0.635 0.254) (xy 0.5334 0.254)
				(xy 0.5334 0.2794)
			)
			(stroke
				(width 0)
				(type default)
			)
			(fill no)
			(layer "F.CrtYd")
		)
		(pad "1" smd rect
			(at 0.40005 0)
			(size 0.4572 0.508)
			(layers "F.Cu" "F.Mask" "F.Paste")
			(net "GND")
		)
		(pad "2" smd rect
			(at -0.40005 0)
			(size 0.4572 0.508)
			(layers "F.Cu" "F.Mask" "F.Paste")
			(net "P12V_STBY")
		)
	)
	(footprint ""
		(layer "F.Cu")
		(at 50.418238 -439.763154 180)
		(property "Reference" "CE20"
			(at -4.84124 2.782824 0)
			(unlocked yes)
			(layer "F.SilkS")
			(effects
				(font
					(size 0.7874 0.5842)
					(thickness 0.1524)
				)
				(justify left)
			)
		)
		(property "Value" ""
			(at 0 0 180)
			(layer "F.Fab")
			(effects
				(font
					(size 1.27 1.27)
				)
			)
		)
		(duplicate_pad_numbers_are_jumpers no)
		(fp_line
			(start 0 -4.2672)
			(end 0 4.2672)
			(stroke
				(width 0.1524)
				(type default)
			)
			(layer "F.SilkS")
		)
		(fp_circle
			(center 0 0)
			(end -4.2672 0)
			(stroke
				(width 0.1524)
				(type default)
			)
			(fill no)
			(layer "F.SilkS")
		)
		(fp_poly
			(pts
				(arc
					(start 0 -4.2672)
					(mid 4.2672 0)
					(end 0 4.2672)
				)
			)
			(stroke
				(width 0)
				(type default)
			)
			(fill yes)
			(layer "F.SilkS")
		)
		(fp_poly
			(pts
				(xy -2.5146 -0.762) (xy -0.9906 -0.762) (xy -0.9906 0.762) (xy -2.5146 0.762)
			)
			(stroke
				(width 0)
				(type default)
			)
			(fill no)
			(layer "B.CrtYd")
		)
		(fp_poly
			(pts
				(arc
					(start 1.7526 0.762)
					(mid 2.291415 -0.538815)
					(end 0.9906 0)
				)
				(arc
					(start 0.9906 0.0254)
					(mid 1.206345 0.546255)
					(end 1.7272 0.762)
				)
			)
			(stroke
				(width 0)
				(type default)
			)
			(fill no)
			(layer "B.CrtYd")
		)
		(fp_poly
			(pts
				(arc
					(start -4.2672 0)
					(mid 4.2672 0)
					(end -4.2672 0)
				)
			)
			(stroke
				(width 0)
				(type default)
			)
			(fill no)
			(layer "F.CrtYd")
		)
		(fp_circle
			(center 0 0)
			(end -4.2672 0)
			(stroke
				(width 0.1)
				(type default)
			)
			(fill no)
			(layer "F.Fab")
		)
		(fp_text user "+"
			(at -5.6642 -0.34925 180)
			(unlocked yes)
			(layer "F.SilkS")
			(effects
				(font
					(size 1.905 1.4224)
					(thickness 0.1524)
				)
				(justify left)
			)
		)
		(fp_text user "+"
			(at -5.6642 -0.34925 180)
			(unlocked yes)
			(layer "F.Fab")
			(effects
				(font
					(size 1.905 1.4224)
					(thickness 0.000001)
				)
				(justify left)
			)
		)
		(pad "1" thru_hole rect
			(at -1.75006 0 180)
			(size 1.397 1.397)
			(drill 0.9144)
			(layers "*.Cu" "*.Mask")
			(remove_unused_layers no)
			(net "P12V")
			(clearance 0.0127)
			(thermal_gap 0.0127)
			(padstack
				(mode front_inner_back)
				(layer "Inner"
					(shape circle)
					(size 1.397 1.397)
					(clearance 0.0127)
				)
				(layer "B.Cu"
					(shape rect)
					(size 1.397 1.397)
					(clearance 0.0127)
				)
			)
		)
		(pad "2" thru_hole circle
			(at 1.75006 0 180)
			(size 1.397 1.397)
			(drill 0.9144)
			(layers "*.Cu" "*.Mask")
			(remove_unused_layers no)
			(net "GND")
			(clearance 0.0127)
			(thermal_gap 0.0127)
		)
	)
	(footprint ""
		(layer "F.Cu")
		(at 71.405496 -259.450078 90)
		(property "Reference" "C49"
			(at -4.355846 -0.127762 90)
			(unlocked yes)
			(layer "F.SilkS")
			(effects
				(font
					(size 0.7874 0.5842)
					(thickness 0.1524)
				)
				(justify left)
			)
		)
		(property "Value" ""
			(at 0 0 90)
			(layer "F.Fab")
			(effects
				(font
					(size 1.27 1.27)
				)
			)
		)
		(duplicate_pad_numbers_are_jumpers no)
		(fp_line
			(start 0.7874 -0.4064)
			(end 0.7874 0.4064)
			(stroke
				(width 0.1524)
				(type default)
			)
			(layer "F.SilkS")
		)
		(fp_line
			(start -0.7874 -0.4064)
			(end 0.7874 -0.4064)
			(stroke
				(width 0.1524)
				(type default)
			)
			(layer "F.SilkS")
		)
		(fp_line
			(start 0 0.381)
			(end 0 -0.381)
			(stroke
				(width 0.1524)
				(type default)
			)
			(layer "F.SilkS")
		)
		(fp_line
			(start 0.7874 0.4064)
			(end -0.7874 0.4064)
			(stroke
				(width 0.1524)
				(type default)
			)
			(layer "F.SilkS")
		)
		(fp_line
			(start -0.7874 0.4064)
			(end -0.7874 -0.4064)
			(stroke
				(width 0.1524)
				(type default)
			)
			(layer "F.SilkS")
		)
		(fp_poly
			(pts
				(xy -0.5334 0.254) (xy -0.635 0.254) (xy -0.635 0.2286) (xy -0.635 -0.254) (xy -0.5334 -0.254) (xy -0.5334 -0.2794)
				(xy 0.5334 -0.2794) (xy 0.5334 -0.254) (xy 0.635 -0.254) (xy 0.635 0.254) (xy 0.5334 0.254) (xy 0.5334 0.2794)
				(xy -0.508 0.2794) (xy -0.5334 0.2794)
			)
			(stroke
				(width 0)
				(type default)
			)
			(fill no)
			(layer "F.CrtYd")
		)
		(pad "1" smd rect
			(at 0.40005 0 90)
			(size 0.4572 0.508)
			(layers "F.Cu" "F.Mask" "F.Paste")
			(net "P12V")
		)
		(pad "2" smd rect
			(at -0.40005 0 90)
			(size 0.4572 0.508)
			(layers "F.Cu" "F.Mask" "F.Paste")
			(net "GND")
		)
	)
	(footprint ""
		(layer "F.Cu")
		(at 39.462964 -21.994368 90)
		(property "Reference" "R110"
			(at -0.675132 1.446022 0)
			(unlocked yes)
			(layer "F.SilkS")
			(effects
				(font
					(size 0.7874 0.5842)
					(thickness 0.1524)
				)
				(justify left)
			)
		)
		(property "Value" ""
			(at 0 0 90)
			(layer "F.Fab")
			(effects
				(font
					(size 1.27 1.27)
				)
			)
		)
		(duplicate_pad_numbers_are_jumpers no)
		(fp_line
			(start 0.7874 -0.4064)
			(end 0.7874 0.4064)
			(stroke
				(width 0.1524)
				(type default)
			)
			(layer "F.SilkS")
		)
		(fp_line
			(start -0.7874 -0.4064)
			(end 0.7874 -0.4064)
			(stroke
				(width 0.1524)
				(type default)
			)
			(layer "F.SilkS")
		)
		(fp_line
			(start 0.7874 0.4064)
			(end -0.7874 0.4064)
			(stroke
				(width 0.1524)
				(type default)
			)
			(layer "F.SilkS")
		)
		(fp_line
			(start -0.7874 0.4064)
			(end -0.7874 -0.4064)
			(stroke
				(width 0.1524)
				(type default)
			)
			(layer "F.SilkS")
		)
		(fp_poly
			(pts
				(xy -0.508 0.2794) (xy -0.508 0.2286) (xy -0.635 0.2286) (xy -0.635 -0.254) (xy -0.5334 -0.254)
				(xy -0.5334 -0.2794) (xy 0.5334 -0.2794) (xy 0.5334 -0.254) (xy 0.635 -0.254) (xy 0.635 0.254) (xy 0.5334 0.254)
				(xy 0.5334 0.2794)
			)
			(stroke
				(width 0)
				(type default)
			)
			(fill no)
			(layer "F.CrtYd")
		)
		(pad "1" smd rect
			(at 0.40005 0 90)
			(size 0.4572 0.508)
			(layers "F.Cu" "F.Mask" "F.Paste")
			(net "PSU1_REMOTE_P")
		)
		(pad "2" smd rect
			(at -0.40005 0 90)
			(size 0.4572 0.508)
			(layers "F.Cu" "F.Mask" "F.Paste")
			(net "PSU1_REMOTE_R2_P")
		)
	)
	(footprint ""
		(layer "F.Cu")
		(at 15.540736 -451.706234)
		(property "Reference" "C90"
			(at -1.292098 -3.46837 0)
			(unlocked yes)
			(layer "F.SilkS")
			(effects
				(font
					(size 0.7874 0.5842)
					(thickness 0.1524)
				)
				(justify left)
			)
		)
		(property "Value" ""
			(at 0 0 0)
			(layer "F.Fab")
			(effects
				(font
					(size 1.27 1.27)
				)
			)
		)
		(duplicate_pad_numbers_are_jumpers no)
		(fp_line
			(start -0.7874 -0.4064)
			(end 0.7874 -0.4064)
			(stroke
				(width 0.1524)
				(type default)
			)
			(layer "F.SilkS")
		)
		(fp_line
			(start -0.7874 0.4064)
			(end -0.7874 -0.4064)
			(stroke
				(width 0.1524)
				(type default)
			)
			(layer "F.SilkS")
		)
		(fp_line
			(start 0 0.381)
			(end 0 -0.381)
			(stroke
				(width 0.1524)
				(type default)
			)
			(layer "F.SilkS")
		)
		(fp_line
			(start 0.7874 -0.4064)
			(end 0.7874 0.4064)
			(stroke
				(width 0.1524)
				(type default)
			)
			(layer "F.SilkS")
		)
		(fp_line
			(start 0.7874 0.4064)
			(end -0.7874 0.4064)
			(stroke
				(width 0.1524)
				(type default)
			)
			(layer "F.SilkS")
		)
		(fp_poly
			(pts
				(xy -0.5334 0.254) (xy -0.635 0.254) (xy -0.635 0.2286) (xy -0.635 -0.254) (xy -0.5334 -0.254) (xy -0.5334 -0.2794)
				(xy 0.5334 -0.2794) (xy 0.5334 -0.254) (xy 0.635 -0.254) (xy 0.635 0.254) (xy 0.5334 0.254) (xy 0.5334 0.2794)
				(xy -0.508 0.2794) (xy -0.5334 0.2794)
			)
			(stroke
				(width 0)
				(type default)
			)
			(fill no)
			(layer "F.CrtYd")
		)
		(pad "1" smd rect
			(at 0.40005 0)
			(size 0.4572 0.508)
			(layers "F.Cu" "F.Mask" "F.Paste")
			(net "P12V")
		)
		(pad "2" smd rect
			(at -0.40005 0)
			(size 0.4572 0.508)
			(layers "F.Cu" "F.Mask" "F.Paste")
			(net "GND")
		)
	)
	(footprint ""
		(layer "F.Cu")
		(at 67.92468 -38.821106 90)
		(property "Reference" "C13"
			(at 1.149604 -0.056134 90)
			(unlocked yes)
			(layer "F.SilkS")
			(effects
				(font
					(size 0.7874 0.5842)
					(thickness 0.1524)
				)
				(justify left)
			)
		)
		(property "Value" ""
			(at 0 0 90)
			(layer "F.Fab")
			(effects
				(font
					(size 1.27 1.27)
				)
			)
		)
		(duplicate_pad_numbers_are_jumpers no)
		(fp_line
			(start 0.7874 -0.4064)
			(end 0.7874 0.4064)
			(stroke
				(width 0.1524)
				(type default)
			)
			(layer "F.SilkS")
		)
		(fp_line
			(start -0.7874 -0.4064)
			(end 0.7874 -0.4064)
			(stroke
				(width 0.1524)
				(type default)
			)
			(layer "F.SilkS")
		)
		(fp_line
			(start 0 0.381)
			(end 0 -0.381)
			(stroke
				(width 0.1524)
				(type default)
			)
			(layer "F.SilkS")
		)
		(fp_line
			(start 0.7874 0.4064)
			(end -0.7874 0.4064)
			(stroke
				(width 0.1524)
				(type default)
			)
			(layer "F.SilkS")
		)
		(fp_line
			(start -0.7874 0.4064)
			(end -0.7874 -0.4064)
			(stroke
				(width 0.1524)
				(type default)
			)
			(layer "F.SilkS")
		)
		(fp_poly
			(pts
				(xy -0.5334 0.254) (xy -0.635 0.254) (xy -0.635 0.2286) (xy -0.635 -0.254) (xy -0.5334 -0.254) (xy -0.5334 -0.2794)
				(xy 0.5334 -0.2794) (xy 0.5334 -0.254) (xy 0.635 -0.254) (xy 0.635 0.254) (xy 0.5334 0.254) (xy 0.5334 0.2794)
				(xy -0.508 0.2794) (xy -0.5334 0.2794)
			)
			(stroke
				(width 0)
				(type default)
			)
			(fill no)
			(layer "F.CrtYd")
		)
		(pad "1" smd rect
			(at 0.40005 0 90)
			(size 0.4572 0.508)
			(layers "F.Cu" "F.Mask" "F.Paste")
			(net "P12V")
		)
		(pad "2" smd rect
			(at -0.40005 0 90)
			(size 0.4572 0.508)
			(layers "F.Cu" "F.Mask" "F.Paste")
			(net "GND")
		)
	)
	(footprint ""
		(layer "F.Cu")
		(at 30.45968 -171.729908)
		(property "Reference" "J2"
			(at 7.63778 3.119628 0)
			(unlocked yes)
			(layer "F.SilkS")
			(effects
				(font
					(size 0.7874 0.5842)
					(thickness 0.1524)
				)
				(justify left)
			)
		)
		(property "Value" ""
			(at 0 0 0)
			(layer "F.Fab")
			(effects
				(font
					(size 1.27 1.27)
				)
			)
		)
		(duplicate_pad_numbers_are_jumpers no)
		(fp_line
			(start -2.135124 -4.560062)
			(end -2.135124 83.300062)
			(stroke
				(width 0.1524)
				(type default)
			)
			(layer "F.SilkS")
		)
		(fp_line
			(start -2.135124 83.300062)
			(end 7.215124 83.300062)
			(stroke
				(width 0.1524)
				(type default)
			)
			(layer "F.SilkS")
		)
		(fp_line
			(start 7.215124 -4.560062)
			(end -2.135124 -4.560062)
			(stroke
				(width 0.1524)
				(type default)
			)
			(layer "F.SilkS")
		)
		(fp_line
			(start 7.215124 83.300062)
			(end 7.215124 -4.560062)
			(stroke
				(width 0.1524)
				(type default)
			)
			(layer "F.SilkS")
		)
		(fp_poly
			(pts
				(xy -2.557272 -0.130556) (xy -5.257292 -0.83058) (xy -5.257292 0.569468)
			)
			(stroke
				(width 0)
				(type default)
			)
			(fill yes)
			(layer "F.SilkS")
		)
		(fp_poly
			(pts
				(xy -2.28219 -0.127) (xy -4.98221 -0.827024) (xy -4.98221 0.573024)
			)
			(stroke
				(width 0)
				(type default)
			)
			(fill yes)
			(layer "B.SilkS")
		)
		(fp_poly
			(pts
				(xy -0.8636 -0.8636) (xy -0.8636 79.6036) (xy -0.8636 79.629) (xy 5.9436 79.629) (xy 5.9436 79.6036)
				(xy 5.9436 -0.8636) (xy 5.9436 -0.889) (xy -0.8636 -0.889)
			)
			(stroke
				(width 0)
				(type default)
			)
			(fill no)
			(layer "B.CrtYd")
		)
		(fp_rect
			(start -2.135124 -4.560062)
			(end 7.21487 83.300062)
			(stroke
				(width 0)
				(type default)
			)
			(fill no)
			(layer "F.CrtYd")
		)
		(fp_line
			(start -2.135124 -4.560062)
			(end 7.215124 -4.560062)
			(stroke
				(width 0.1)
				(type default)
			)
			(layer "F.Fab")
		)
		(fp_line
			(start -2.135124 83.300062)
			(end -2.135124 -4.560062)
			(stroke
				(width 0.1)
				(type default)
			)
			(layer "F.Fab")
		)
		(fp_line
			(start 7.215124 -4.560062)
			(end 7.215124 83.300062)
			(stroke
				(width 0.1)
				(type default)
			)
			(layer "F.Fab")
		)
		(fp_line
			(start 7.215124 83.300062)
			(end -2.135124 83.300062)
			(stroke
				(width 0.1)
				(type default)
			)
			(layer "F.Fab")
		)
		(fp_text user "32"
			(at -3.674872 78.298802 0)
			(unlocked yes)
			(layer "F.SilkS")
			(effects
				(font
					(size 0.7874 0.5842)
					(thickness 0.1524)
				)
				(justify left)
			)
		)
		(fp_text user "1"
			(at -3.253994 -1.297178 0)
			(unlocked yes)
			(layer "F.SilkS")
			(effects
				(font
					(size 0.7874 0.5842)
					(thickness 0.1524)
				)
				(justify left)
			)
		)
		(fp_text user "64"
			(at 7.640066 -0.704342 0)
			(unlocked yes)
			(layer "F.SilkS")
			(effects
				(font
					(size 0.7874 0.5842)
					(thickness 0.1524)
				)
				(justify left)
			)
		)
		(fp_text user "33"
			(at 7.654544 83.258914 0)
			(unlocked yes)
			(layer "F.SilkS")
			(effects
				(font
					(size 0.7874 0.5842)
					(thickness 0.1524)
				)
				(justify left)
			)
		)
		(fp_text user "1"
			(at -1.619758 -0.610362 0)
			(unlocked yes)
			(layer "B.SilkS")
			(effects
				(font
					(size 0.7874 0.5842)
					(thickness 0.1524)
				)
				(justify left mirror)
			)
		)
		(fp_text user "32"
			(at -1.102868 78.932024 0)
			(unlocked yes)
			(layer "B.SilkS")
			(effects
				(font
					(size 0.7874 0.5842)
					(thickness 0.1524)
				)
				(justify left mirror)
			)
		)
		(fp_text user "64"
			(at 5.791454 -1.569466 0)
			(unlocked yes)
			(layer "B.SilkS")
			(effects
				(font
					(size 0.7874 0.5842)
					(thickness 0.1524)
				)
				(justify left mirror)
			)
		)
		(fp_text user "33"
			(at 6.84784 83.378294 0)
			(unlocked yes)
			(layer "B.SilkS")
			(effects
				(font
					(size 0.7874 0.5842)
					(thickness 0.1524)
				)
				(justify left mirror)
			)
		)
		(pad "1" thru_hole rect
			(at 0 0 270)
			(size 1.6256 1.6256)
			(drill 1.1176)
			(layers "*.Cu" "*.Mask")
			(remove_unused_layers no)
			(net "P12V")
			(clearance 0)
			(padstack
				(mode front_inner_back)
				(layer "Inner"
					(shape circle)
					(size 1.6256 1.6256)
					(clearance 0)
				)
				(layer "B.Cu"
					(shape rect)
					(size 1.6256 1.6256)
					(clearance 0)
				)
			)
		)
		(pad "2" thru_hole circle
			(at 0 2.54 270)
			(size 1.6256 1.6256)
			(drill 1.1176)
			(layers "*.Cu" "*.Mask")
			(remove_unused_layers no)
			(net "P12V")
			(clearance 0)
		)
		(pad "3" thru_hole circle
			(at 0 5.08 270)
			(size 1.6256 1.6256)
			(drill 1.1176)
			(layers "*.Cu" "*.Mask")
			(remove_unused_layers no)
			(net "P12V")
			(clearance 0)
		)
		(pad "4" thru_hole circle
			(at 0 7.62 270)
			(size 1.6256 1.6256)
			(drill 1.1176)
			(layers "*.Cu" "*.Mask")
			(remove_unused_layers no)
			(net "P12V")
			(clearance 0)
		)
		(pad "5" thru_hole circle
			(at 0 10.16 270)
			(size 1.6256 1.6256)
			(drill 1.1176)
			(layers "*.Cu" "*.Mask")
			(remove_unused_layers no)
			(net "P12V")
			(clearance 0)
		)
		(pad "6" thru_hole circle
			(at 0 12.7 270)
			(size 1.6256 1.6256)
			(drill 1.1176)
			(layers "*.Cu" "*.Mask")
			(remove_unused_layers no)
			(net "P12V")
			(clearance 0)
		)
		(pad "7" thru_hole circle
			(at 0 15.24 270)
			(size 1.6256 1.6256)
			(drill 1.1176)
			(layers "*.Cu" "*.Mask")
			(remove_unused_layers no)
			(net "P12V")
			(clearance 0)
		)
		(pad "8" thru_hole circle
			(at 0 17.78 270)
			(size 1.6256 1.6256)
			(drill 1.1176)
			(layers "*.Cu" "*.Mask")
			(remove_unused_layers no)
			(net "P12V")
			(clearance 0)
		)
		(pad "9" thru_hole circle
			(at 0 20.32 270)
			(size 1.6256 1.6256)
			(drill 1.1176)
			(layers "*.Cu" "*.Mask")
			(remove_unused_layers no)
			(net "P12V")
			(clearance 0)
		)
		(pad "10" thru_hole circle
			(at 0 22.86 270)
			(size 1.6256 1.6256)
			(drill 1.1176)
			(layers "*.Cu" "*.Mask")
			(remove_unused_layers no)
			(net "P12V")
			(clearance 0)
		)
		(pad "11" thru_hole circle
			(at 0 25.4 270)
			(size 1.6256 1.6256)
			(drill 1.1176)
			(layers "*.Cu" "*.Mask")
			(remove_unused_layers no)
			(net "P12V")
			(clearance 0)
		)
		(pad "12" thru_hole circle
			(at 0 27.94 270)
			(size 1.6256 1.6256)
			(drill 1.1176)
			(layers "*.Cu" "*.Mask")
			(remove_unused_layers no)
			(net "P12V")
			(clearance 0)
		)
		(pad "13" thru_hole circle
			(at 0 30.48 270)
			(size 1.6256 1.6256)
			(drill 1.1176)
			(layers "*.Cu" "*.Mask")
			(remove_unused_layers no)
			(net "GND")
			(clearance 0)
		)
		(pad "14" thru_hole circle
			(at 0 33.02 270)
			(size 1.6256 1.6256)
			(drill 1.1176)
			(layers "*.Cu" "*.Mask")
			(remove_unused_layers no)
			(net "GND")
			(clearance 0)
		)
		(pad "15" thru_hole circle
			(at 0 35.56 270)
			(size 1.6256 1.6256)
			(drill 1.1176)
			(layers "*.Cu" "*.Mask")
			(remove_unused_layers no)
			(net "GND")
			(clearance 0)
		)
		(pad "16" thru_hole circle
			(at 0 38.1 270)
			(size 1.6256 1.6256)
			(drill 1.1176)
			(layers "*.Cu" "*.Mask")
			(remove_unused_layers no)
			(net "GND")
			(clearance 0)
		)
		(pad "17" thru_hole circle
			(at 0 40.64 270)
			(size 1.6256 1.6256)
			(drill 1.1176)
			(layers "*.Cu" "*.Mask")
			(remove_unused_layers no)
			(net "GND")
			(clearance 0)
		)
		(pad "18" thru_hole circle
			(at 0 43.18 270)
			(size 1.6256 1.6256)
			(drill 1.1176)
			(layers "*.Cu" "*.Mask")
			(remove_unused_layers no)
			(net "GND")
			(clearance 0)
		)
		(pad "19" thru_hole circle
			(at 0 45.72 270)
			(size 1.6256 1.6256)
			(drill 1.1176)
			(layers "*.Cu" "*.Mask")
			(remove_unused_layers no)
			(net "GND")
			(clearance 0)
		)
		(pad "20" thru_hole circle
			(at 0 48.26 270)
			(size 1.6256 1.6256)
			(drill 1.1176)
			(layers "*.Cu" "*.Mask")
			(remove_unused_layers no)
			(net "GND")
			(clearance 0)
		)
		(pad "21" thru_hole circle
			(at 0 50.8 270)
			(size 1.6256 1.6256)
			(drill 1.1176)
			(layers "*.Cu" "*.Mask")
			(remove_unused_layers no)
			(net "GND")
			(clearance 0)
		)
		(pad "22" thru_hole circle
			(at 0 53.34 270)
			(size 1.6256 1.6256)
			(drill 1.1176)
			(layers "*.Cu" "*.Mask")
			(remove_unused_layers no)
			(net "GND")
			(clearance 0)
		)
		(pad "23" thru_hole circle
			(at 0 55.88 270)
			(size 1.6256 1.6256)
			(drill 1.1176)
			(layers "*.Cu" "*.Mask")
			(remove_unused_layers no)
			(net "GND")
			(clearance 0)
		)
		(pad "24" thru_hole circle
			(at 0 58.42 270)
			(size 1.6256 1.6256)
			(drill 1.1176)
			(layers "*.Cu" "*.Mask")
			(remove_unused_layers no)
			(net "GND")
			(clearance 0)
		)
		(pad "25" thru_hole circle
			(at 0 60.96 270)
			(size 1.6256 1.6256)
			(drill 1.1176)
			(layers "*.Cu" "*.Mask")
			(remove_unused_layers no)
			(net "PHLOSS")
			(clearance 0)
		)
		(pad "26" thru_hole circle
			(at 0 63.5 270)
			(size 1.6256 1.6256)
			(drill 1.1176)
			(layers "*.Cu" "*.Mask")
			(remove_unused_layers no)
			(net "PSU2_REMOTE_N")
			(clearance 0)
		)
		(pad "27" thru_hole circle
			(at 0 66.04 270)
			(size 1.6256 1.6256)
			(drill 1.1176)
			(layers "*.Cu" "*.Mask")
			(remove_unused_layers no)
			(net "PSU2_AC_OK")
			(clearance 0)
		)
		(pad "28" thru_hole circle
			(at 0 68.58 270)
			(size 1.6256 1.6256)
			(drill 1.1176)
			(layers "*.Cu" "*.Mask")
			(remove_unused_layers no)
			(net "PSU2_CSAHRE")
			(clearance 0)
		)
		(pad "29" thru_hole circle
			(at 0 71.12 270)
			(size 1.6256 1.6256)
			(drill 1.1176)
			(layers "*.Cu" "*.Mask")
			(remove_unused_layers no)
			(net "PSU2_PS_ON_N")
			(clearance 0)
		)
		(pad "30" thru_hole circle
			(at 0 73.66 270)
			(size 1.6256 1.6256)
			(drill 1.1176)
			(layers "*.Cu" "*.Mask")
			(remove_unused_layers no)
			(net "PSU2_PS_KILL")
			(clearance 0)
		)
		(pad "31" thru_hole circle
			(at 0 76.2 270)
			(size 1.6256 1.6256)
			(drill 1.1176)
			(layers "*.Cu" "*.Mask")
			(remove_unused_layers no)
			(net "PSU2_RESET")
			(clearance 0)
		)
		(pad "32" thru_hole circle
			(at 0 78.74 270)
			(size 1.6256 1.6256)
			(drill 1.1176)
			(layers "*.Cu" "*.Mask")
			(remove_unused_layers no)
			(net "PSU_ALERT_N")
			(clearance 0)
		)
		(pad "33" thru_hole circle
			(at 5.08 78.74 270)
			(size 1.6256 1.6256)
			(drill 1.1176)
			(layers "*.Cu" "*.Mask")
			(remove_unused_layers no)
			(net "I2C_PSU1_SDA")
			(clearance 0)
		)
		(pad "34" thru_hole circle
			(at 5.08 76.2 270)
			(size 1.6256 1.6256)
			(drill 1.1176)
			(layers "*.Cu" "*.Mask")
			(remove_unused_layers no)
			(net "Net_429")
			(clearance 0)
		)
		(pad "35" thru_hole circle
			(at 5.08 73.66 270)
			(size 1.6256 1.6256)
			(drill 1.1176)
			(layers "*.Cu" "*.Mask")
			(remove_unused_layers no)
			(net "I2C_PSU1_SCL")
			(clearance 0)
		)
		(pad "36" thru_hole circle
			(at 5.08 71.12 270)
			(size 1.6256 1.6256)
			(drill 1.1176)
			(layers "*.Cu" "*.Mask")
			(remove_unused_layers no)
			(net "PSU2_RETURN")
			(clearance 0)
		)
		(pad "37" thru_hole circle
			(at 5.08 68.58 270)
			(size 1.6256 1.6256)
			(drill 1.1176)
			(layers "*.Cu" "*.Mask")
			(remove_unused_layers no)
			(net "PSU2_DC_OK")
			(clearance 0)
		)
		(pad "38" thru_hole circle
			(at 5.08 66.04 270)
			(size 1.6256 1.6256)
			(drill 1.1176)
			(layers "*.Cu" "*.Mask")
			(remove_unused_layers no)
			(net "PSU2_AD0")
			(clearance 0)
		)
		(pad "39" thru_hole circle
			(at 5.08 63.5 270)
			(size 1.6256 1.6256)
			(drill 1.1176)
			(layers "*.Cu" "*.Mask")
			(remove_unused_layers no)
			(net "P12V_STBY")
			(clearance 0)
		)
		(pad "40" thru_hole circle
			(at 5.08 60.96 270)
			(size 1.6256 1.6256)
			(drill 1.1176)
			(layers "*.Cu" "*.Mask")
			(remove_unused_layers no)
			(net "PSU2_REMOTE_P")
			(clearance 0)
		)
		(pad "41" thru_hole circle
			(at 5.08 58.42 270)
			(size 1.6256 1.6256)
			(drill 1.1176)
			(layers "*.Cu" "*.Mask")
			(remove_unused_layers no)
			(net "GND")
			(clearance 0)
		)
		(pad "42" thru_hole circle
			(at 5.08 55.88 270)
			(size 1.6256 1.6256)
			(drill 1.1176)
			(layers "*.Cu" "*.Mask")
			(remove_unused_layers no)
			(net "GND")
			(clearance 0)
		)
		(pad "43" thru_hole circle
			(at 5.08 53.34 270)
			(size 1.6256 1.6256)
			(drill 1.1176)
			(layers "*.Cu" "*.Mask")
			(remove_unused_layers no)
			(net "GND")
			(clearance 0)
		)
		(pad "44" thru_hole circle
			(at 5.08 50.8 270)
			(size 1.6256 1.6256)
			(drill 1.1176)
			(layers "*.Cu" "*.Mask")
			(remove_unused_layers no)
			(net "GND")
			(clearance 0)
		)
		(pad "45" thru_hole circle
			(at 5.08 48.26 270)
			(size 1.6256 1.6256)
			(drill 1.1176)
			(layers "*.Cu" "*.Mask")
			(remove_unused_layers no)
			(net "GND")
			(clearance 0)
		)
		(pad "46" thru_hole circle
			(at 5.08 45.72 270)
			(size 1.6256 1.6256)
			(drill 1.1176)
			(layers "*.Cu" "*.Mask")
			(remove_unused_layers no)
			(net "GND")
			(clearance 0)
		)
		(pad "47" thru_hole circle
			(at 5.08 43.18 270)
			(size 1.6256 1.6256)
			(drill 1.1176)
			(layers "*.Cu" "*.Mask")
			(remove_unused_layers no)
			(net "GND")
			(clearance 0)
		)
		(pad "48" thru_hole circle
			(at 5.08 40.64 270)
			(size 1.6256 1.6256)
			(drill 1.1176)
			(layers "*.Cu" "*.Mask")
			(remove_unused_layers no)
			(net "GND")
			(clearance 0)
		)
		(pad "49" thru_hole circle
			(at 5.08 38.1 270)
			(size 1.6256 1.6256)
			(drill 1.1176)
			(layers "*.Cu" "*.Mask")
			(remove_unused_layers no)
			(net "GND")
			(clearance 0)
		)
		(pad "50" thru_hole circle
			(at 5.08 35.56 270)
			(size 1.6256 1.6256)
			(drill 1.1176)
			(layers "*.Cu" "*.Mask")
			(remove_unused_layers no)
			(net "GND")
			(clearance 0)
		)
		(pad "51" thru_hole circle
			(at 5.08 33.02 270)
			(size 1.6256 1.6256)
			(drill 1.1176)
			(layers "*.Cu" "*.Mask")
			(remove_unused_layers no)
			(net "GND")
			(clearance 0)
		)
		(pad "52" thru_hole circle
			(at 5.08 30.48 270)
			(size 1.6256 1.6256)
			(drill 1.1176)
			(layers "*.Cu" "*.Mask")
			(remove_unused_layers no)
			(net "GND")
			(clearance 0)
		)
		(pad "53" thru_hole circle
			(at 5.08 27.94 270)
			(size 1.6256 1.6256)
			(drill 1.1176)
			(layers "*.Cu" "*.Mask")
			(remove_unused_layers no)
			(net "P12V")
			(clearance 0)
		)
		(pad "54" thru_hole circle
			(at 5.08 25.4 270)
			(size 1.6256 1.6256)
			(drill 1.1176)
			(layers "*.Cu" "*.Mask")
			(remove_unused_layers no)
			(net "P12V")
			(clearance 0)
		)
		(pad "55" thru_hole circle
			(at 5.08 22.86 270)
			(size 1.6256 1.6256)
			(drill 1.1176)
			(layers "*.Cu" "*.Mask")
			(remove_unused_layers no)
			(net "P12V")
			(clearance 0)
		)
		(pad "56" thru_hole circle
			(at 5.08 20.32 270)
			(size 1.6256 1.6256)
			(drill 1.1176)
			(layers "*.Cu" "*.Mask")
			(remove_unused_layers no)
			(net "P12V")
			(clearance 0)
		)
		(pad "57" thru_hole circle
			(at 5.08 17.78 270)
			(size 1.6256 1.6256)
			(drill 1.1176)
			(layers "*.Cu" "*.Mask")
			(remove_unused_layers no)
			(net "P12V")
			(clearance 0)
		)
		(pad "58" thru_hole circle
			(at 5.08 15.24 270)
			(size 1.6256 1.6256)
			(drill 1.1176)
			(layers "*.Cu" "*.Mask")
			(remove_unused_layers no)
			(net "P12V")
			(clearance 0)
		)
		(pad "59" thru_hole circle
			(at 5.08 12.7 270)
			(size 1.6256 1.6256)
			(drill 1.1176)
			(layers "*.Cu" "*.Mask")
			(remove_unused_layers no)
			(net "P12V")
			(clearance 0)
		)
		(pad "60" thru_hole circle
			(at 5.08 10.16 270)
			(size 1.6256 1.6256)
			(drill 1.1176)
			(layers "*.Cu" "*.Mask")
			(remove_unused_layers no)
			(net "P12V")
			(clearance 0)
		)
		(pad "61" thru_hole circle
			(at 5.08 7.62 270)
			(size 1.6256 1.6256)
			(drill 1.1176)
			(layers "*.Cu" "*.Mask")
			(remove_unused_layers no)
			(net "P12V")
			(clearance 0)
		)
		(pad "62" thru_hole circle
			(at 5.08 5.08 270)
			(size 1.6256 1.6256)
			(drill 1.1176)
			(layers "*.Cu" "*.Mask")
			(remove_unused_layers no)
			(net "P12V")
			(clearance 0)
		)
		(pad "63" thru_hole circle
			(at 5.08 2.54 270)
			(size 1.6256 1.6256)
			(drill 1.1176)
			(layers "*.Cu" "*.Mask")
			(remove_unused_layers no)
			(net "P12V")
			(clearance 0)
		)
		(pad "64" thru_hole circle
			(at 5.08 0 270)
			(size 1.6256 1.6256)
			(drill 1.1176)
			(layers "*.Cu" "*.Mask")
			(remove_unused_layers no)
			(net "P12V")
			(clearance 0)
		)
	)
	(footprint ""
		(layer "F.Cu")
		(at 22.524974 -177.804572 -90)
		(property "Reference" "R160"
			(at 1.072896 4.462526 90)
			(unlocked yes)
			(layer "F.SilkS")
			(effects
				(font
					(size 0.7874 0.5842)
					(thickness 0.1524)
				)
				(justify left)
			)
		)
		(property "Value" ""
			(at 0 0 270)
			(layer "F.Fab")
			(effects
				(font
					(size 1.27 1.27)
				)
			)
		)
		(duplicate_pad_numbers_are_jumpers no)
		(fp_line
			(start -0.7874 0.4064)
			(end -0.7874 -0.4064)
			(stroke
				(width 0.1524)
				(type default)
			)
			(layer "F.SilkS")
		)
		(fp_line
			(start 0.7874 0.4064)
			(end -0.7874 0.4064)
			(stroke
				(width 0.1524)
				(type default)
			)
			(layer "F.SilkS")
		)
		(fp_line
			(start -0.7874 -0.4064)
			(end 0.7874 -0.4064)
			(stroke
				(width 0.1524)
				(type default)
			)
			(layer "F.SilkS")
		)
		(fp_line
			(start 0.7874 -0.4064)
			(end 0.7874 0.4064)
			(stroke
				(width 0.1524)
				(type default)
			)
			(layer "F.SilkS")
		)
		(fp_poly
			(pts
				(xy -0.508 0.2794) (xy -0.508 0.2286) (xy -0.635 0.2286) (xy -0.635 -0.254) (xy -0.5334 -0.254)
				(xy -0.5334 -0.2794) (xy 0.5334 -0.2794) (xy 0.5334 -0.254) (xy 0.635 -0.254) (xy 0.635 0.254) (xy 0.5334 0.254)
				(xy 0.5334 0.2794)
			)
			(stroke
				(width 0)
				(type default)
			)
			(fill no)
			(layer "F.CrtYd")
		)
		(pad "1" smd rect
			(at 0.40005 0 270)
			(size 0.4572 0.508)
			(layers "F.Cu" "F.Mask" "F.Paste")
			(net "N42264085")
		)
		(pad "2" smd rect
			(at -0.40005 0 270)
			(size 0.4572 0.508)
			(layers "F.Cu" "F.Mask" "F.Paste")
			(net "GND")
		)
	)
	(footprint ""
		(layer "F.Cu")
		(at 73.909936 -152.923748 -90)
		(property "Reference" "C23"
			(at -2.638552 0.124206 90)
			(unlocked yes)
			(layer "F.SilkS")
			(effects
				(font
					(size 0.7874 0.5842)
					(thickness 0.1524)
				)
				(justify left)
			)
		)
		(property "Value" ""
			(at 0 0 270)
			(layer "F.Fab")
			(effects
				(font
					(size 1.27 1.27)
				)
			)
		)
		(duplicate_pad_numbers_are_jumpers no)
		(fp_line
			(start -0.7874 0.4064)
			(end -0.7874 -0.4064)
			(stroke
				(width 0.1524)
				(type default)
			)
			(layer "F.SilkS")
		)
		(fp_line
			(start 0.7874 0.4064)
			(end -0.7874 0.4064)
			(stroke
				(width 0.1524)
				(type default)
			)
			(layer "F.SilkS")
		)
		(fp_line
			(start 0 0.381)
			(end 0 -0.381)
			(stroke
				(width 0.1524)
				(type default)
			)
			(layer "F.SilkS")
		)
		(fp_line
			(start -0.7874 -0.4064)
			(end 0.7874 -0.4064)
			(stroke
				(width 0.1524)
				(type default)
			)
			(layer "F.SilkS")
		)
		(fp_line
			(start 0.7874 -0.4064)
			(end 0.7874 0.4064)
			(stroke
				(width 0.1524)
				(type default)
			)
			(layer "F.SilkS")
		)
		(fp_poly
			(pts
				(xy -0.5334 0.254) (xy -0.635 0.254) (xy -0.635 0.2286) (xy -0.635 -0.254) (xy -0.5334 -0.254) (xy -0.5334 -0.2794)
				(xy 0.5334 -0.2794) (xy 0.5334 -0.254) (xy 0.635 -0.254) (xy 0.635 0.254) (xy 0.5334 0.254) (xy 0.5334 0.2794)
				(xy -0.508 0.2794) (xy -0.5334 0.2794)
			)
			(stroke
				(width 0)
				(type default)
			)
			(fill no)
			(layer "F.CrtYd")
		)
		(pad "1" smd rect
			(at 0.40005 0 270)
			(size 0.4572 0.508)
			(layers "F.Cu" "F.Mask" "F.Paste")
			(net "P12V")
		)
		(pad "2" smd rect
			(at -0.40005 0 270)
			(size 0.4572 0.508)
			(layers "F.Cu" "F.Mask" "F.Paste")
			(net "GND")
		)
	)
	(footprint ""
		(layer "F.Cu")
		(at 46.472856 -247.282716 180)
		(property "Reference" "R96"
			(at -0.980186 -0.54483 0)
			(unlocked yes)
			(layer "F.SilkS")
			(effects
				(font
					(size 0.7874 0.5842)
					(thickness 0.1524)
				)
				(justify left)
			)
		)
		(property "Value" ""
			(at 0 0 180)
			(layer "F.Fab")
			(effects
				(font
					(size 1.27 1.27)
				)
			)
		)
		(duplicate_pad_numbers_are_jumpers no)
		(fp_line
			(start 0.7874 0.4064)
			(end -0.7874 0.4064)
			(stroke
				(width 0.1524)
				(type default)
			)
			(layer "F.SilkS")
		)
		(fp_line
			(start 0.7874 -0.4064)
			(end 0.7874 0.4064)
			(stroke
				(width 0.1524)
				(type default)
			)
			(layer "F.SilkS")
		)
		(fp_line
			(start -0.7874 0.4064)
			(end -0.7874 -0.4064)
			(stroke
				(width 0.1524)
				(type default)
			)
			(layer "F.SilkS")
		)
		(fp_line
			(start -0.7874 -0.4064)
			(end 0.7874 -0.4064)
			(stroke
				(width 0.1524)
				(type default)
			)
			(layer "F.SilkS")
		)
		(fp_poly
			(pts
				(xy -0.508 0.2794) (xy -0.508 0.2286) (xy -0.635 0.2286) (xy -0.635 -0.254) (xy -0.5334 -0.254)
				(xy -0.5334 -0.2794) (xy 0.5334 -0.2794) (xy 0.5334 -0.254) (xy 0.635 -0.254) (xy 0.635 0.254) (xy 0.5334 0.254)
				(xy 0.5334 0.2794)
			)
			(stroke
				(width 0)
				(type default)
			)
			(fill no)
			(layer "F.CrtYd")
		)
		(pad "1" smd rect
			(at 0.40005 0 180)
			(size 0.4572 0.508)
			(layers "F.Cu" "F.Mask" "F.Paste")
			(net "PSU3_REMOTE_R_P")
		)
		(pad "2" smd rect
			(at -0.40005 0 180)
			(size 0.4572 0.508)
			(layers "F.Cu" "F.Mask" "F.Paste")
			(net "P12V")
		)
	)
	(footprint ""
		(layer "F.Cu")
		(at 70.236842 -38.821106 90)
		(property "Reference" "C11"
			(at 1.198626 -0.235712 90)
			(unlocked yes)
			(layer "F.SilkS")
			(effects
				(font
					(size 0.7874 0.5842)
					(thickness 0.1524)
				)
				(justify left)
			)
		)
		(property "Value" ""
			(at 0 0 90)
			(layer "F.Fab")
			(effects
				(font
					(size 1.27 1.27)
				)
			)
		)
		(duplicate_pad_numbers_are_jumpers no)
		(fp_line
			(start 0.7874 -0.4064)
			(end 0.7874 0.4064)
			(stroke
				(width 0.1524)
				(type default)
			)
			(layer "F.SilkS")
		)
		(fp_line
			(start -0.7874 -0.4064)
			(end 0.7874 -0.4064)
			(stroke
				(width 0.1524)
				(type default)
			)
			(layer "F.SilkS")
		)
		(fp_line
			(start 0 0.381)
			(end 0 -0.381)
			(stroke
				(width 0.1524)
				(type default)
			)
			(layer "F.SilkS")
		)
		(fp_line
			(start 0.7874 0.4064)
			(end -0.7874 0.4064)
			(stroke
				(width 0.1524)
				(type default)
			)
			(layer "F.SilkS")
		)
		(fp_line
			(start -0.7874 0.4064)
			(end -0.7874 -0.4064)
			(stroke
				(width 0.1524)
				(type default)
			)
			(layer "F.SilkS")
		)
		(fp_poly
			(pts
				(xy -0.5334 0.254) (xy -0.635 0.254) (xy -0.635 0.2286) (xy -0.635 -0.254) (xy -0.5334 -0.254) (xy -0.5334 -0.2794)
				(xy 0.5334 -0.2794) (xy 0.5334 -0.254) (xy 0.635 -0.254) (xy 0.635 0.254) (xy 0.5334 0.254) (xy 0.5334 0.2794)
				(xy -0.508 0.2794) (xy -0.5334 0.2794)
			)
			(stroke
				(width 0)
				(type default)
			)
			(fill no)
			(layer "F.CrtYd")
		)
		(pad "1" smd rect
			(at 0.40005 0 90)
			(size 0.4572 0.508)
			(layers "F.Cu" "F.Mask" "F.Paste")
			(net "P12V")
		)
		(pad "2" smd rect
			(at -0.40005 0 90)
			(size 0.4572 0.508)
			(layers "F.Cu" "F.Mask" "F.Paste")
			(net "GND")
		)
	)
	(footprint ""
		(layer "F.Cu")
		(at 73.512934 -419.288722 -90)
		(property "Reference" "C65"
			(at 3.469894 -0.070358 90)
			(unlocked yes)
			(layer "F.SilkS")
			(effects
				(font
					(size 0.7874 0.5842)
					(thickness 0.1524)
				)
				(justify left)
			)
		)
		(property "Value" ""
			(at 0 0 270)
			(layer "F.Fab")
			(effects
				(font
					(size 1.27 1.27)
				)
			)
		)
		(duplicate_pad_numbers_are_jumpers no)
		(fp_line
			(start -0.7874 0.4064)
			(end -0.7874 -0.4064)
			(stroke
				(width 0.1524)
				(type default)
			)
			(layer "F.SilkS")
		)
		(fp_line
			(start 0.7874 0.4064)
			(end -0.7874 0.4064)
			(stroke
				(width 0.1524)
				(type default)
			)
			(layer "F.SilkS")
		)
		(fp_line
			(start 0 0.381)
			(end 0 -0.381)
			(stroke
				(width 0.1524)
				(type default)
			)
			(layer "F.SilkS")
		)
		(fp_line
			(start -0.7874 -0.4064)
			(end 0.7874 -0.4064)
			(stroke
				(width 0.1524)
				(type default)
			)
			(layer "F.SilkS")
		)
		(fp_line
			(start 0.7874 -0.4064)
			(end 0.7874 0.4064)
			(stroke
				(width 0.1524)
				(type default)
			)
			(layer "F.SilkS")
		)
		(fp_poly
			(pts
				(xy -0.5334 0.254) (xy -0.635 0.254) (xy -0.635 0.2286) (xy -0.635 -0.254) (xy -0.5334 -0.254) (xy -0.5334 -0.2794)
				(xy 0.5334 -0.2794) (xy 0.5334 -0.254) (xy 0.635 -0.254) (xy 0.635 0.254) (xy 0.5334 0.254) (xy 0.5334 0.2794)
				(xy -0.508 0.2794) (xy -0.5334 0.2794)
			)
			(stroke
				(width 0)
				(type default)
			)
			(fill no)
			(layer "F.CrtYd")
		)
		(pad "1" smd rect
			(at 0.40005 0 270)
			(size 0.4572 0.508)
			(layers "F.Cu" "F.Mask" "F.Paste")
			(net "P12V")
		)
		(pad "2" smd rect
			(at -0.40005 0 270)
			(size 0.4572 0.508)
			(layers "F.Cu" "F.Mask" "F.Paste")
			(net "GND")
		)
	)
	(footprint ""
		(layer "F.Cu")
		(at 39.46398 -22.785324 -90)
		(property "Reference" "R86"
			(at -1.022858 -0.025146 90)
			(unlocked yes)
			(layer "F.SilkS")
			(effects
				(font
					(size 0.7874 0.5842)
					(thickness 0.1524)
				)
				(justify left)
			)
		)
		(property "Value" ""
			(at 0 0 270)
			(layer "F.Fab")
			(effects
				(font
					(size 1.27 1.27)
				)
			)
		)
		(duplicate_pad_numbers_are_jumpers no)
		(fp_line
			(start -0.7874 0.4064)
			(end -0.7874 -0.4064)
			(stroke
				(width 0.1524)
				(type default)
			)
			(layer "F.SilkS")
		)
		(fp_line
			(start 0.7874 0.4064)
			(end -0.7874 0.4064)
			(stroke
				(width 0.1524)
				(type default)
			)
			(layer "F.SilkS")
		)
		(fp_line
			(start -0.7874 -0.4064)
			(end 0.7874 -0.4064)
			(stroke
				(width 0.1524)
				(type default)
			)
			(layer "F.SilkS")
		)
		(fp_line
			(start 0.7874 -0.4064)
			(end 0.7874 0.4064)
			(stroke
				(width 0.1524)
				(type default)
			)
			(layer "F.SilkS")
		)
		(fp_poly
			(pts
				(xy -0.508 0.2794) (xy -0.508 0.2286) (xy -0.635 0.2286) (xy -0.635 -0.254) (xy -0.5334 -0.254)
				(xy -0.5334 -0.2794) (xy 0.5334 -0.2794) (xy 0.5334 -0.254) (xy 0.635 -0.254) (xy 0.635 0.254) (xy 0.5334 0.254)
				(xy 0.5334 0.2794)
			)
			(stroke
				(width 0)
				(type default)
			)
			(fill no)
			(layer "F.CrtYd")
		)
		(pad "1" smd rect
			(at 0.40005 0 270)
			(size 0.4572 0.508)
			(layers "F.Cu" "F.Mask" "F.Paste")
			(net "PSU1_REMOTE_P")
		)
		(pad "2" smd rect
			(at -0.40005 0 270)
			(size 0.4572 0.508)
			(layers "F.Cu" "F.Mask" "F.Paste")
			(net "PSU1_REMOTE_R_P")
		)
	)
	(footprint ""
		(layer "F.Cu")
		(at 27.052778 -10.617962)
		(property "Reference" "R50"
			(at -4.020312 -0.32258 0)
			(unlocked yes)
			(layer "F.SilkS")
			(effects
				(font
					(size 0.7874 0.5842)
					(thickness 0.1524)
				)
				(justify left)
			)
		)
		(property "Value" ""
			(at 0 0 0)
			(layer "F.Fab")
			(effects
				(font
					(size 1.27 1.27)
				)
			)
		)
		(duplicate_pad_numbers_are_jumpers no)
		(fp_line
			(start -0.7874 -0.4064)
			(end 0.7874 -0.4064)
			(stroke
				(width 0.1524)
				(type default)
			)
			(layer "F.SilkS")
		)
		(fp_line
			(start -0.7874 0.4064)
			(end -0.7874 -0.4064)
			(stroke
				(width 0.1524)
				(type default)
			)
			(layer "F.SilkS")
		)
		(fp_line
			(start 0.7874 -0.4064)
			(end 0.7874 0.4064)
			(stroke
				(width 0.1524)
				(type default)
			)
			(layer "F.SilkS")
		)
		(fp_line
			(start 0.7874 0.4064)
			(end -0.7874 0.4064)
			(stroke
				(width 0.1524)
				(type default)
			)
			(layer "F.SilkS")
		)
		(fp_poly
			(pts
				(xy -0.508 0.2794) (xy -0.508 0.2286) (xy -0.635 0.2286) (xy -0.635 -0.254) (xy -0.5334 -0.254)
				(xy -0.5334 -0.2794) (xy 0.5334 -0.2794) (xy 0.5334 -0.254) (xy 0.635 -0.254) (xy 0.635 0.254) (xy 0.5334 0.254)
				(xy 0.5334 0.2794)
			)
			(stroke
				(width 0)
				(type default)
			)
			(fill no)
			(layer "F.CrtYd")
		)
		(pad "1" smd rect
			(at 0.40005 0)
			(size 0.4572 0.508)
			(layers "F.Cu" "F.Mask" "F.Paste")
			(net "GND")
		)
		(pad "2" smd rect
			(at -0.40005 0)
			(size 0.4572 0.508)
			(layers "F.Cu" "F.Mask" "F.Paste")
			(net "PSU2_PS_ON_N")
		)
	)
	(footprint ""
		(layer "F.Cu")
		(at 74.69886 -419.288722 -90)
		(property "Reference" "C66"
			(at 3.469894 -0.070358 90)
			(unlocked yes)
			(layer "F.SilkS")
			(effects
				(font
					(size 0.7874 0.5842)
					(thickness 0.1524)
				)
				(justify left)
			)
		)
		(property "Value" ""
			(at 0 0 270)
			(layer "F.Fab")
			(effects
				(font
					(size 1.27 1.27)
				)
			)
		)
		(duplicate_pad_numbers_are_jumpers no)
		(fp_line
			(start -0.7874 0.4064)
			(end -0.7874 -0.4064)
			(stroke
				(width 0.1524)
				(type default)
			)
			(layer "F.SilkS")
		)
		(fp_line
			(start 0.7874 0.4064)
			(end -0.7874 0.4064)
			(stroke
				(width 0.1524)
				(type default)
			)
			(layer "F.SilkS")
		)
		(fp_line
			(start 0 0.381)
			(end 0 -0.381)
			(stroke
				(width 0.1524)
				(type default)
			)
			(layer "F.SilkS")
		)
		(fp_line
			(start -0.7874 -0.4064)
			(end 0.7874 -0.4064)
			(stroke
				(width 0.1524)
				(type default)
			)
			(layer "F.SilkS")
		)
		(fp_line
			(start 0.7874 -0.4064)
			(end 0.7874 0.4064)
			(stroke
				(width 0.1524)
				(type default)
			)
			(layer "F.SilkS")
		)
		(fp_poly
			(pts
				(xy -0.5334 0.254) (xy -0.635 0.254) (xy -0.635 0.2286) (xy -0.635 -0.254) (xy -0.5334 -0.254) (xy -0.5334 -0.2794)
				(xy 0.5334 -0.2794) (xy 0.5334 -0.254) (xy 0.635 -0.254) (xy 0.635 0.254) (xy 0.5334 0.254) (xy 0.5334 0.2794)
				(xy -0.508 0.2794) (xy -0.5334 0.2794)
			)
			(stroke
				(width 0)
				(type default)
			)
			(fill no)
			(layer "F.CrtYd")
		)
		(pad "1" smd rect
			(at 0.40005 0 270)
			(size 0.4572 0.508)
			(layers "F.Cu" "F.Mask" "F.Paste")
			(net "P12V")
		)
		(pad "2" smd rect
			(at -0.40005 0 270)
			(size 0.4572 0.508)
			(layers "F.Cu" "F.Mask" "F.Paste")
			(net "GND")
		)
	)
	(footprint ""
		(layer "F.Cu")
		(at 26.226008 -447.250058)
		(property "Reference" "R61"
			(at -1.712468 1.059942 0)
			(unlocked yes)
			(layer "F.SilkS")
			(effects
				(font
					(size 0.7874 0.5842)
					(thickness 0.1524)
				)
				(justify left)
			)
		)
		(property "Value" ""
			(at 0 0 0)
			(layer "F.Fab")
			(effects
				(font
					(size 1.27 1.27)
				)
			)
		)
		(duplicate_pad_numbers_are_jumpers no)
		(fp_line
			(start -0.7874 -0.4064)
			(end 0.7874 -0.4064)
			(stroke
				(width 0.1524)
				(type default)
			)
			(layer "F.SilkS")
		)
		(fp_line
			(start -0.7874 0.4064)
			(end -0.7874 -0.4064)
			(stroke
				(width 0.1524)
				(type default)
			)
			(layer "F.SilkS")
		)
		(fp_line
			(start 0.7874 -0.4064)
			(end 0.7874 0.4064)
			(stroke
				(width 0.1524)
				(type default)
			)
			(layer "F.SilkS")
		)
		(fp_line
			(start 0.7874 0.4064)
			(end -0.7874 0.4064)
			(stroke
				(width 0.1524)
				(type default)
			)
			(layer "F.SilkS")
		)
		(fp_poly
			(pts
				(xy -0.508 0.2794) (xy -0.508 0.2286) (xy -0.635 0.2286) (xy -0.635 -0.254) (xy -0.5334 -0.254)
				(xy -0.5334 -0.2794) (xy 0.5334 -0.2794) (xy 0.5334 -0.254) (xy 0.635 -0.254) (xy 0.635 0.254) (xy 0.5334 0.254)
				(xy 0.5334 0.2794)
			)
			(stroke
				(width 0)
				(type default)
			)
			(fill no)
			(layer "F.CrtYd")
		)
		(pad "1" smd rect
			(at 0.40005 0)
			(size 0.4572 0.508)
			(layers "F.Cu" "F.Mask" "F.Paste")
			(net "PSU6_RESET")
		)
		(pad "2" smd rect
			(at -0.40005 0)
			(size 0.4572 0.508)
			(layers "F.Cu" "F.Mask" "F.Paste")
			(net "GND")
		)
	)
	(footprint ""
		(layer "F.Cu")
		(at 50.150522 -128.655318 180)
		(property "Reference" "CE6"
			(at 0.794004 -5.521452 0)
			(unlocked yes)
			(layer "F.SilkS")
			(effects
				(font
					(size 0.7874 0.5842)
					(thickness 0.1524)
				)
				(justify left)
			)
		)
		(property "Value" ""
			(at 0 0 180)
			(layer "F.Fab")
			(effects
				(font
					(size 1.27 1.27)
				)
			)
		)
		(duplicate_pad_numbers_are_jumpers no)
		(fp_line
			(start 0 -4.2672)
			(end 0 4.2672)
			(stroke
				(width 0.1524)
				(type default)
			)
			(layer "F.SilkS")
		)
		(fp_circle
			(center 0 0)
			(end -4.2672 0)
			(stroke
				(width 0.1524)
				(type default)
			)
			(fill no)
			(layer "F.SilkS")
		)
		(fp_poly
			(pts
				(arc
					(start 0 -4.2672)
					(mid 4.2672 0)
					(end 0 4.2672)
				)
			)
			(stroke
				(width 0)
				(type default)
			)
			(fill yes)
			(layer "F.SilkS")
		)
		(fp_poly
			(pts
				(xy -2.5146 -0.762) (xy -0.9906 -0.762) (xy -0.9906 0.762) (xy -2.5146 0.762)
			)
			(stroke
				(width 0)
				(type default)
			)
			(fill no)
			(layer "B.CrtYd")
		)
		(fp_poly
			(pts
				(arc
					(start 1.7526 0.762)
					(mid 2.291415 -0.538815)
					(end 0.9906 0)
				)
				(arc
					(start 0.9906 0.0254)
					(mid 1.206345 0.546255)
					(end 1.7272 0.762)
				)
			)
			(stroke
				(width 0)
				(type default)
			)
			(fill no)
			(layer "B.CrtYd")
		)
		(fp_poly
			(pts
				(arc
					(start -4.2672 0)
					(mid 4.2672 0)
					(end -4.2672 0)
				)
			)
			(stroke
				(width 0)
				(type default)
			)
			(fill no)
			(layer "F.CrtYd")
		)
		(fp_circle
			(center 0 0)
			(end -4.2672 0)
			(stroke
				(width 0.1)
				(type default)
			)
			(fill no)
			(layer "F.Fab")
		)
		(fp_text user "+"
			(at -5.65785 -2.009648 180)
			(unlocked yes)
			(layer "F.SilkS")
			(effects
				(font
					(size 1.905 1.4224)
					(thickness 0.1524)
				)
				(justify left)
			)
		)
		(fp_text user "+"
			(at -5.6642 -0.34925 180)
			(unlocked yes)
			(layer "F.Fab")
			(effects
				(font
					(size 1.905 1.4224)
					(thickness 0.000001)
				)
				(justify left)
			)
		)
		(pad "1" thru_hole rect
			(at -1.75006 0 180)
			(size 1.397 1.397)
			(drill 0.9144)
			(layers "*.Cu" "*.Mask")
			(remove_unused_layers no)
			(net "P12V")
			(clearance 0.0127)
			(thermal_gap 0.0127)
			(padstack
				(mode front_inner_back)
				(layer "Inner"
					(shape circle)
					(size 1.397 1.397)
					(clearance 0.0127)
				)
				(layer "B.Cu"
					(shape rect)
					(size 1.397 1.397)
					(clearance 0.0127)
				)
			)
		)
		(pad "2" thru_hole circle
			(at 1.75006 0 180)
			(size 1.397 1.397)
			(drill 0.9144)
			(layers "*.Cu" "*.Mask")
			(remove_unused_layers no)
			(net "GND")
			(clearance 0.0127)
			(thermal_gap 0.0127)
		)
	)
	(footprint ""
		(layer "F.Cu")
		(at 20.408646 -446.145158 90)
		(property "Reference" "R155"
			(at -8.594852 1.446022 90)
			(unlocked yes)
			(layer "F.SilkS")
			(effects
				(font
					(size 0.7874 0.5842)
					(thickness 0.1524)
				)
				(justify left)
			)
		)
		(property "Value" ""
			(at 0 0 90)
			(layer "F.Fab")
			(effects
				(font
					(size 1.27 1.27)
				)
			)
		)
		(duplicate_pad_numbers_are_jumpers no)
		(fp_line
			(start 0.7874 -0.4064)
			(end 0.7874 0.4064)
			(stroke
				(width 0.1524)
				(type default)
			)
			(layer "F.SilkS")
		)
		(fp_line
			(start -0.7874 -0.4064)
			(end 0.7874 -0.4064)
			(stroke
				(width 0.1524)
				(type default)
			)
			(layer "F.SilkS")
		)
		(fp_line
			(start 0.7874 0.4064)
			(end -0.7874 0.4064)
			(stroke
				(width 0.1524)
				(type default)
			)
			(layer "F.SilkS")
		)
		(fp_line
			(start -0.7874 0.4064)
			(end -0.7874 -0.4064)
			(stroke
				(width 0.1524)
				(type default)
			)
			(layer "F.SilkS")
		)
		(fp_poly
			(pts
				(xy -0.508 0.2794) (xy -0.508 0.2286) (xy -0.635 0.2286) (xy -0.635 -0.254) (xy -0.5334 -0.254)
				(xy -0.5334 -0.2794) (xy 0.5334 -0.2794) (xy 0.5334 -0.254) (xy 0.635 -0.254) (xy 0.635 0.254) (xy 0.5334 0.254)
				(xy 0.5334 0.2794)
			)
			(stroke
				(width 0)
				(type default)
			)
			(fill no)
			(layer "F.CrtYd")
		)
		(pad "1" smd rect
			(at 0.40005 0 90)
			(size 0.4572 0.508)
			(layers "F.Cu" "F.Mask" "F.Paste")
			(net "P3V3_BUF")
		)
		(pad "2" smd rect
			(at -0.40005 0 90)
			(size 0.4572 0.508)
			(layers "F.Cu" "F.Mask" "F.Paste")
			(net "N42242336")
		)
	)
	(footprint ""
		(layer "F.Cu")
		(at 39.858442 -110.774226 180)
		(property "Reference" "R3"
			(at -1.626616 0.658622 0)
			(unlocked yes)
			(layer "F.SilkS")
			(effects
				(font
					(size 0.7874 0.5842)
					(thickness 0.1524)
				)
				(justify left)
			)
		)
		(property "Value" ""
			(at 0 0 180)
			(layer "F.Fab")
			(effects
				(font
					(size 1.27 1.27)
				)
			)
		)
		(duplicate_pad_numbers_are_jumpers no)
		(fp_line
			(start 0.7874 0.4064)
			(end -0.7874 0.4064)
			(stroke
				(width 0.1524)
				(type default)
			)
			(layer "F.SilkS")
		)
		(fp_line
			(start 0.7874 -0.4064)
			(end 0.7874 0.4064)
			(stroke
				(width 0.1524)
				(type default)
			)
			(layer "F.SilkS")
		)
		(fp_line
			(start -0.7874 0.4064)
			(end -0.7874 -0.4064)
			(stroke
				(width 0.1524)
				(type default)
			)
			(layer "F.SilkS")
		)
		(fp_line
			(start -0.7874 -0.4064)
			(end 0.7874 -0.4064)
			(stroke
				(width 0.1524)
				(type default)
			)
			(layer "F.SilkS")
		)
		(fp_poly
			(pts
				(xy -0.508 0.2794) (xy -0.508 0.2286) (xy -0.635 0.2286) (xy -0.635 -0.254) (xy -0.5334 -0.254)
				(xy -0.5334 -0.2794) (xy 0.5334 -0.2794) (xy 0.5334 -0.254) (xy 0.635 -0.254) (xy 0.635 0.254) (xy 0.5334 0.254)
				(xy 0.5334 0.2794)
			)
			(stroke
				(width 0)
				(type default)
			)
			(fill no)
			(layer "F.CrtYd")
		)
		(pad "1" smd rect
			(at 0.40005 0 180)
			(size 0.4572 0.508)
			(layers "F.Cu" "F.Mask" "F.Paste")
			(net "PSU2_REMOTE_P")
		)
		(pad "2" smd rect
			(at -0.40005 0 180)
			(size 0.4572 0.508)
			(layers "F.Cu" "F.Mask" "F.Paste")
			(net "P12V")
		)
	)
	(footprint ""
		(layer "F.Cu")
		(at 14.309598 -223.205294)
		(property "Reference" ""
			(at 0 0 0)
			(layer "F.SilkS")
			(hide yes)
			(effects
				(font
					(size 1.27 1.27)
				)
			)
		)
		(property "Value" ""
			(at 0 0 0)
			(layer "F.Fab")
			(effects
				(font
					(size 1.27 1.27)
				)
			)
		)
		(duplicate_pad_numbers_are_jumpers no)
		(fp_poly
			(pts
				(arc
					(start 1.4986 0)
					(mid -1.4986 0)
					(end 1.4986 0)
				)
			)
			(stroke
				(width 0)
				(type default)
			)
			(fill no)
			(layer "F.CrtYd")
		)
		(pad "1" smd circle
			(at 0 0)
			(size 0.9906 0.9906)
			(layers "F.Cu" "F.Mask" "F.Paste")
			(net "Net_196")
		)
		(zone
			(layer "F.Cu")
			(hatch none 0.5)
			(connect_pads
				(clearance 0)
			)
			(min_thickness 0.25)
			(keepout
				(tracks not_allowed)
				(vias allowed)
				(pads allowed)
				(copperpour not_allowed)
				(footprints allowed)
			)
			(placement
				(enabled no)
				(sheetname "")
			)
			(fill
				(thermal_gap 0.5)
				(thermal_bridge_width 0.5)
				(island_removal_mode 0)
			)
			(polygon
				(pts
					(arc
						(start 15.935198 -223.205294)
						(mid 12.683998 -223.205294)
						(end 15.935198 -223.205294)
					)
				)
			)
		)
	)
	(footprint ""
		(layer "F.Cu")
		(at 27.246072 -20.26412 -90)
		(property "Reference" "R87"
			(at -1.149604 0.97536 90)
			(unlocked yes)
			(layer "F.SilkS")
			(effects
				(font
					(size 0.7874 0.5842)
					(thickness 0.1524)
				)
				(justify left)
			)
		)
		(property "Value" ""
			(at 0 0 270)
			(layer "F.Fab")
			(effects
				(font
					(size 1.27 1.27)
				)
			)
		)
		(duplicate_pad_numbers_are_jumpers no)
		(fp_line
			(start -0.7874 0.4064)
			(end -0.7874 -0.4064)
			(stroke
				(width 0.1524)
				(type default)
			)
			(layer "F.SilkS")
		)
		(fp_line
			(start 0.7874 0.4064)
			(end -0.7874 0.4064)
			(stroke
				(width 0.1524)
				(type default)
			)
			(layer "F.SilkS")
		)
		(fp_line
			(start -0.7874 -0.4064)
			(end 0.7874 -0.4064)
			(stroke
				(width 0.1524)
				(type default)
			)
			(layer "F.SilkS")
		)
		(fp_line
			(start 0.7874 -0.4064)
			(end 0.7874 0.4064)
			(stroke
				(width 0.1524)
				(type default)
			)
			(layer "F.SilkS")
		)
		(fp_poly
			(pts
				(xy -0.508 0.2794) (xy -0.508 0.2286) (xy -0.635 0.2286) (xy -0.635 -0.254) (xy -0.5334 -0.254)
				(xy -0.5334 -0.2794) (xy 0.5334 -0.2794) (xy 0.5334 -0.254) (xy 0.635 -0.254) (xy 0.635 0.254) (xy 0.5334 0.254)
				(xy 0.5334 0.2794)
			)
			(stroke
				(width 0)
				(type default)
			)
			(fill no)
			(layer "F.CrtYd")
		)
		(pad "1" smd rect
			(at 0.40005 0 270)
			(size 0.4572 0.508)
			(layers "F.Cu" "F.Mask" "F.Paste")
			(net "PSU1_REMOTE_N")
		)
		(pad "2" smd rect
			(at -0.40005 0 270)
			(size 0.4572 0.508)
			(layers "F.Cu" "F.Mask" "F.Paste")
			(net "PSU1_REMOTE_R_N")
		)
	)
	(footprint ""
		(layer "F.Cu")
		(at 21.674074 -444.049658 180)
		(property "Reference" "C88"
			(at -0.189484 -7.234428 0)
			(unlocked yes)
			(layer "F.SilkS")
			(effects
				(font
					(size 0.7874 0.5842)
					(thickness 0.1524)
				)
				(justify left)
			)
		)
		(property "Value" ""
			(at 0 0 180)
			(layer "F.Fab")
			(effects
				(font
					(size 1.27 1.27)
				)
			)
		)
		(duplicate_pad_numbers_are_jumpers no)
		(fp_line
			(start 1.905 0.8636)
			(end -1.905 0.8636)
			(stroke
				(width 0.1524)
				(type default)
			)
			(layer "F.SilkS")
		)
		(fp_line
			(start 1.905 -0.8636)
			(end 1.905 0.8636)
			(stroke
				(width 0.1524)
				(type default)
			)
			(layer "F.SilkS")
		)
		(fp_line
			(start 0 0.8382)
			(end 0 -0.8382)
			(stroke
				(width 0.1524)
				(type default)
			)
			(layer "F.SilkS")
		)
		(fp_line
			(start -1.905 0.8636)
			(end -1.905 -0.8636)
			(stroke
				(width 0.1524)
				(type default)
			)
			(layer "F.SilkS")
		)
		(fp_line
			(start -1.905 -0.8636)
			(end 1.905 -0.8636)
			(stroke
				(width 0.1524)
				(type default)
			)
			(layer "F.SilkS")
		)
		(fp_rect
			(start -1.524 0.7366)
			(end 1.524 -0.7366)
			(stroke
				(width 0)
				(type default)
			)
			(fill no)
			(layer "F.CrtYd")
		)
		(pad "1" smd rect
			(at 0.94996 0 180)
			(size 1.1176 1.3716)
			(layers "F.Cu" "F.Mask" "F.Paste")
			(net "N42242336")
		)
		(pad "2" smd rect
			(at -0.94996 0 180)
			(size 1.1176 1.3716)
			(layers "F.Cu" "F.Mask" "F.Paste")
			(net "GND")
		)
	)
	(footprint ""
		(layer "F.Cu")
		(at 16.263366 -445.813434)
		(property "Reference" "C85"
			(at -1.079754 3.787394 0)
			(unlocked yes)
			(layer "F.SilkS")
			(effects
				(font
					(size 0.7874 0.5842)
					(thickness 0.1524)
				)
				(justify left)
			)
		)
		(property "Value" ""
			(at 0 0 0)
			(layer "F.Fab")
			(effects
				(font
					(size 1.27 1.27)
				)
			)
		)
		(duplicate_pad_numbers_are_jumpers no)
		(fp_line
			(start -1.905 -0.8636)
			(end 1.905 -0.8636)
			(stroke
				(width 0.1524)
				(type default)
			)
			(layer "F.SilkS")
		)
		(fp_line
			(start -1.905 0.8636)
			(end -1.905 -0.8636)
			(stroke
				(width 0.1524)
				(type default)
			)
			(layer "F.SilkS")
		)
		(fp_line
			(start 0 0.8382)
			(end 0 -0.8382)
			(stroke
				(width 0.1524)
				(type default)
			)
			(layer "F.SilkS")
		)
		(fp_line
			(start 1.905 -0.8636)
			(end 1.905 0.8636)
			(stroke
				(width 0.1524)
				(type default)
			)
			(layer "F.SilkS")
		)
		(fp_line
			(start 1.905 0.8636)
			(end -1.905 0.8636)
			(stroke
				(width 0.1524)
				(type default)
			)
			(layer "F.SilkS")
		)
		(fp_rect
			(start -1.524 0.7366)
			(end 1.524 -0.7366)
			(stroke
				(width 0)
				(type default)
			)
			(fill no)
			(layer "F.CrtYd")
		)
		(pad "1" smd rect
			(at 0.94996 0)
			(size 1.1176 1.3716)
			(layers "F.Cu" "F.Mask" "F.Paste")
			(net "P12V")
		)
		(pad "2" smd rect
			(at -0.94996 0)
			(size 1.1176 1.3716)
			(layers "F.Cu" "F.Mask" "F.Paste")
			(net "GND")
		)
	)
	(footprint ""
		(layer "F.Cu")
		(at 26.068274 -186.752992)
		(property "Reference" "R48"
			(at -3.997198 0.128524 0)
			(unlocked yes)
			(layer "F.SilkS")
			(effects
				(font
					(size 0.7874 0.5842)
					(thickness 0.1524)
				)
				(justify left)
			)
		)
		(property "Value" ""
			(at 0 0 0)
			(layer "F.Fab")
			(effects
				(font
					(size 1.27 1.27)
				)
			)
		)
		(duplicate_pad_numbers_are_jumpers no)
		(fp_line
			(start -0.7874 -0.4064)
			(end 0.7874 -0.4064)
			(stroke
				(width 0.1524)
				(type default)
			)
			(layer "F.SilkS")
		)
		(fp_line
			(start -0.7874 0.4064)
			(end -0.7874 -0.4064)
			(stroke
				(width 0.1524)
				(type default)
			)
			(layer "F.SilkS")
		)
		(fp_line
			(start 0.7874 -0.4064)
			(end 0.7874 0.4064)
			(stroke
				(width 0.1524)
				(type default)
			)
			(layer "F.SilkS")
		)
		(fp_line
			(start 0.7874 0.4064)
			(end -0.7874 0.4064)
			(stroke
				(width 0.1524)
				(type default)
			)
			(layer "F.SilkS")
		)
		(fp_poly
			(pts
				(xy -0.508 0.2794) (xy -0.508 0.2286) (xy -0.635 0.2286) (xy -0.635 -0.254) (xy -0.5334 -0.254)
				(xy -0.5334 -0.2794) (xy 0.5334 -0.2794) (xy 0.5334 -0.254) (xy 0.635 -0.254) (xy 0.635 0.254) (xy 0.5334 0.254)
				(xy 0.5334 0.2794)
			)
			(stroke
				(width 0)
				(type default)
			)
			(fill no)
			(layer "F.CrtYd")
		)
		(pad "1" smd rect
			(at 0.40005 0)
			(size 0.4572 0.508)
			(layers "F.Cu" "F.Mask" "F.Paste")
			(net "PSU3_PS_KILL")
		)
		(pad "2" smd rect
			(at -0.40005 0)
			(size 0.4572 0.508)
			(layers "F.Cu" "F.Mask" "F.Paste")
			(net "GND")
		)
	)
	(footprint ""
		(layer "F.Cu")
		(at 39.821358 -18.414238)
		(property "Reference" "R40"
			(at 1.662938 0.015494 0)
			(unlocked yes)
			(layer "F.SilkS")
			(effects
				(font
					(size 0.7874 0.5842)
					(thickness 0.1524)
				)
				(justify left)
			)
		)
		(property "Value" ""
			(at 0 0 0)
			(layer "F.Fab")
			(effects
				(font
					(size 1.27 1.27)
				)
			)
		)
		(duplicate_pad_numbers_are_jumpers no)
		(fp_line
			(start -0.7874 -0.4064)
			(end 0.7874 -0.4064)
			(stroke
				(width 0.1524)
				(type default)
			)
			(layer "F.SilkS")
		)
		(fp_line
			(start -0.7874 0.4064)
			(end -0.7874 -0.4064)
			(stroke
				(width 0.1524)
				(type default)
			)
			(layer "F.SilkS")
		)
		(fp_line
			(start 0.7874 -0.4064)
			(end 0.7874 0.4064)
			(stroke
				(width 0.1524)
				(type default)
			)
			(layer "F.SilkS")
		)
		(fp_line
			(start 0.7874 0.4064)
			(end -0.7874 0.4064)
			(stroke
				(width 0.1524)
				(type default)
			)
			(layer "F.SilkS")
		)
		(fp_poly
			(pts
				(xy -0.508 0.2794) (xy -0.508 0.2286) (xy -0.635 0.2286) (xy -0.635 -0.254) (xy -0.5334 -0.254)
				(xy -0.5334 -0.2794) (xy 0.5334 -0.2794) (xy 0.5334 -0.254) (xy 0.635 -0.254) (xy 0.635 0.254) (xy 0.5334 0.254)
				(xy 0.5334 0.2794)
			)
			(stroke
				(width 0)
				(type default)
			)
			(fill no)
			(layer "F.CrtYd")
		)
		(pad "1" smd rect
			(at 0.40005 0)
			(size 0.4572 0.508)
			(layers "F.Cu" "F.Mask" "F.Paste")
			(net "GND")
		)
		(pad "2" smd rect
			(at -0.40005 0)
			(size 0.4572 0.508)
			(layers "F.Cu" "F.Mask" "F.Paste")
			(net "P12V_STBY")
		)
	)
	(footprint ""
		(layer "F.Cu")
		(at 69.774816 -439.03646 90)
		(property "Reference" "C77"
			(at 1.382522 0.064516 90)
			(unlocked yes)
			(layer "F.SilkS")
			(effects
				(font
					(size 0.7874 0.5842)
					(thickness 0.1524)
				)
				(justify left)
			)
		)
		(property "Value" ""
			(at 0 0 90)
			(layer "F.Fab")
			(effects
				(font
					(size 1.27 1.27)
				)
			)
		)
		(duplicate_pad_numbers_are_jumpers no)
		(fp_line
			(start 0.7874 -0.4064)
			(end 0.7874 0.4064)
			(stroke
				(width 0.1524)
				(type default)
			)
			(layer "F.SilkS")
		)
		(fp_line
			(start -0.7874 -0.4064)
			(end 0.7874 -0.4064)
			(stroke
				(width 0.1524)
				(type default)
			)
			(layer "F.SilkS")
		)
		(fp_line
			(start 0 0.381)
			(end 0 -0.381)
			(stroke
				(width 0.1524)
				(type default)
			)
			(layer "F.SilkS")
		)
		(fp_line
			(start 0.7874 0.4064)
			(end -0.7874 0.4064)
			(stroke
				(width 0.1524)
				(type default)
			)
			(layer "F.SilkS")
		)
		(fp_line
			(start -0.7874 0.4064)
			(end -0.7874 -0.4064)
			(stroke
				(width 0.1524)
				(type default)
			)
			(layer "F.SilkS")
		)
		(fp_poly
			(pts
				(xy -0.5334 0.254) (xy -0.635 0.254) (xy -0.635 0.2286) (xy -0.635 -0.254) (xy -0.5334 -0.254) (xy -0.5334 -0.2794)
				(xy 0.5334 -0.2794) (xy 0.5334 -0.254) (xy 0.635 -0.254) (xy 0.635 0.254) (xy 0.5334 0.254) (xy 0.5334 0.2794)
				(xy -0.508 0.2794) (xy -0.5334 0.2794)
			)
			(stroke
				(width 0)
				(type default)
			)
			(fill no)
			(layer "F.CrtYd")
		)
		(pad "1" smd rect
			(at 0.40005 0 90)
			(size 0.4572 0.508)
			(layers "F.Cu" "F.Mask" "F.Paste")
			(net "P12V")
		)
		(pad "2" smd rect
			(at -0.40005 0 90)
			(size 0.4572 0.508)
			(layers "F.Cu" "F.Mask" "F.Paste")
			(net "GND")
		)
	)
	(footprint ""
		(layer "F.Cu")
		(at 91.399868 -331.16012)
		(property "Reference" "H26"
			(at -5.1308 -5.23113 0)
			(unlocked yes)
			(layer "F.SilkS")
			(effects
				(font
					(size 0.7874 0.5842)
					(thickness 0.1524)
				)
				(justify left)
			)
		)
		(property "Value" ""
			(at 0 0 0)
			(layer "F.Fab")
			(effects
				(font
					(size 1.27 1.27)
				)
			)
		)
		(duplicate_pad_numbers_are_jumpers no)
		(fp_circle
			(center 0 0)
			(end 4.826 0)
			(stroke
				(width 0.1524)
				(type default)
			)
			(fill no)
			(layer "F.SilkS")
		)
		(fp_circle
			(center 0 0)
			(end 4.826 0)
			(stroke
				(width 0.1524)
				(type default)
			)
			(fill no)
			(layer "B.SilkS")
		)
		(fp_poly
			(pts
				(arc
					(start 0 4.0132)
					(mid 0 -4.0132)
					(end 0 4.0132)
				)
			)
			(stroke
				(width 0)
				(type default)
			)
			(fill no)
			(layer "F.CrtYd")
		)
		(pad "" np_thru_hole circle
			(at 0 0)
			(size 8.001 8.001)
			(drill 8.001)
			(layers "*.Cu" "*.Mask")
			(clearance 0.381)
			(thermal_gap 0.381)
		)
		(zone
			(layers "F.Cu" "B.Cu" "In1.Cu" "In2.Cu" "In3.Cu" "In4.Cu" "In5.Cu" "In6.Cu")
			(hatch none 0.5)
			(connect_pads
				(clearance 0)
			)
			(min_thickness 0.25)
			(keepout
				(tracks not_allowed)
				(vias allowed)
				(pads allowed)
				(copperpour not_allowed)
				(footprints allowed)
			)
			(placement
				(enabled no)
				(sheetname "")
			)
			(fill
				(thermal_gap 0.5)
				(thermal_bridge_width 0.5)
				(island_removal_mode 0)
			)
			(polygon
				(pts
					(arc
						(start 91.399868 -326.63892)
						(mid 91.399868 -335.68132)
						(end 91.399868 -326.63892)
					)
				)
			)
		)
	)
	(footprint ""
		(layer "F.Cu")
		(at 4.204208 -414.966912 -90)
		(property "Reference" "R152"
			(at -1.520444 0.16764 90)
			(unlocked yes)
			(layer "F.SilkS")
			(effects
				(font
					(size 0.7874 0.5842)
					(thickness 0.1524)
				)
				(justify left)
			)
		)
		(property "Value" ""
			(at 0 0 270)
			(layer "F.Fab")
			(effects
				(font
					(size 1.27 1.27)
				)
			)
		)
		(duplicate_pad_numbers_are_jumpers no)
		(fp_line
			(start -0.7874 0.4064)
			(end -0.7874 -0.4064)
			(stroke
				(width 0.1524)
				(type default)
			)
			(layer "F.SilkS")
		)
		(fp_line
			(start 0.7874 0.4064)
			(end -0.7874 0.4064)
			(stroke
				(width 0.1524)
				(type default)
			)
			(layer "F.SilkS")
		)
		(fp_line
			(start -0.7874 -0.4064)
			(end 0.7874 -0.4064)
			(stroke
				(width 0.1524)
				(type default)
			)
			(layer "F.SilkS")
		)
		(fp_line
			(start 0.7874 -0.4064)
			(end 0.7874 0.4064)
			(stroke
				(width 0.1524)
				(type default)
			)
			(layer "F.SilkS")
		)
		(fp_poly
			(pts
				(xy -0.508 0.2794) (xy -0.508 0.2286) (xy -0.635 0.2286) (xy -0.635 -0.254) (xy -0.5334 -0.254)
				(xy -0.5334 -0.2794) (xy 0.5334 -0.2794) (xy 0.5334 -0.254) (xy 0.635 -0.254) (xy 0.635 0.254) (xy 0.5334 0.254)
				(xy 0.5334 0.2794)
			)
			(stroke
				(width 0)
				(type default)
			)
			(fill no)
			(layer "F.CrtYd")
		)
		(pad "1" smd rect
			(at 0.40005 0 270)
			(size 0.4572 0.508)
			(layers "F.Cu" "F.Mask" "F.Paste")
			(net "N42132933")
		)
		(pad "2" smd rect
			(at -0.40005 0 270)
			(size 0.4572 0.508)
			(layers "F.Cu" "F.Mask" "F.Paste")
			(net "GND")
		)
	)
	(footprint ""
		(layer "F.Cu")
		(at 25.931622 -94.464886)
		(property "Reference" "R69"
			(at -4.080256 -0.075692 0)
			(unlocked yes)
			(layer "F.SilkS")
			(effects
				(font
					(size 0.7874 0.5842)
					(thickness 0.1524)
				)
				(justify left)
			)
		)
		(property "Value" ""
			(at 0 0 0)
			(layer "F.Fab")
			(effects
				(font
					(size 1.27 1.27)
				)
			)
		)
		(duplicate_pad_numbers_are_jumpers no)
		(fp_line
			(start -0.7874 -0.4064)
			(end 0.7874 -0.4064)
			(stroke
				(width 0.1524)
				(type default)
			)
			(layer "F.SilkS")
		)
		(fp_line
			(start -0.7874 0.4064)
			(end -0.7874 -0.4064)
			(stroke
				(width 0.1524)
				(type default)
			)
			(layer "F.SilkS")
		)
		(fp_line
			(start 0.7874 -0.4064)
			(end 0.7874 0.4064)
			(stroke
				(width 0.1524)
				(type default)
			)
			(layer "F.SilkS")
		)
		(fp_line
			(start 0.7874 0.4064)
			(end -0.7874 0.4064)
			(stroke
				(width 0.1524)
				(type default)
			)
			(layer "F.SilkS")
		)
		(fp_poly
			(pts
				(xy -0.508 0.2794) (xy -0.508 0.2286) (xy -0.635 0.2286) (xy -0.635 -0.254) (xy -0.5334 -0.254)
				(xy -0.5334 -0.2794) (xy 0.5334 -0.2794) (xy 0.5334 -0.254) (xy 0.635 -0.254) (xy 0.635 0.254) (xy 0.5334 0.254)
				(xy 0.5334 0.2794)
			)
			(stroke
				(width 0)
				(type default)
			)
			(fill no)
			(layer "F.CrtYd")
		)
		(pad "1" smd rect
			(at 0.40005 0)
			(size 0.4572 0.508)
			(layers "F.Cu" "F.Mask" "F.Paste")
			(net "PSU2_RESET")
		)
		(pad "2" smd rect
			(at -0.40005 0)
			(size 0.4572 0.508)
			(layers "F.Cu" "F.Mask" "F.Paste")
			(net "GND")
		)
	)
	(footprint ""
		(layer "F.Cu")
		(at 77.999844 -32.29991)
		(property "Reference" "H12"
			(at 7.02183 -4.748784 0)
			(unlocked yes)
			(layer "F.SilkS")
			(effects
				(font
					(size 0.7874 0.5842)
					(thickness 0.1524)
				)
				(justify left)
			)
		)
		(property "Value" ""
			(at 0 0 0)
			(layer "F.Fab")
			(effects
				(font
					(size 1.27 1.27)
				)
			)
		)
		(duplicate_pad_numbers_are_jumpers no)
		(fp_circle
			(center 0 0)
			(end 7.999984 0)
			(stroke
				(width 0.1524)
				(type default)
			)
			(fill no)
			(layer "F.SilkS")
		)
		(fp_circle
			(center 0 0)
			(end 14.7066 0)
			(stroke
				(width 0.1524)
				(type default)
			)
			(fill no)
			(layer "B.SilkS")
		)
		(fp_poly
			(pts
				(arc
					(start 5.0038 0)
					(mid -5.0038 0)
					(end 5.0038 0)
				)
			)
			(stroke
				(width 0)
				(type default)
			)
			(fill no)
			(layer "F.CrtYd")
		)
		(pad "" np_thru_hole circle
			(at 0 0)
			(size 4.0132 4.0132)
			(drill 4.0132)
			(layers "*.Cu" "*.Mask")
			(clearance 0.381)
			(thermal_gap 0.381)
		)
		(pad "2" thru_hole circle
			(at 0 -3.50012)
			(size 0.762 0.762)
			(drill 0.5588)
			(layers "*.Cu" "*.Mask")
			(remove_unused_layers no)
			(net "GND")
			(clearance 0.1524)
			(thermal_gap 0.1524)
		)
		(pad "3" thru_hole circle
			(at -2.500122 -2.500122)
			(size 0.762 0.762)
			(drill 0.5588)
			(layers "*.Cu" "*.Mask")
			(remove_unused_layers no)
			(net "GND")
			(clearance 0.1524)
			(thermal_gap 0.1524)
		)
		(pad "4" thru_hole circle
			(at -3.50012 0)
			(size 0.762 0.762)
			(drill 0.5588)
			(layers "*.Cu" "*.Mask")
			(remove_unused_layers no)
			(net "GND")
			(clearance 0.1524)
			(thermal_gap 0.1524)
		)
		(pad "5" thru_hole circle
			(at -2.500122 2.500122)
			(size 0.762 0.762)
			(drill 0.5588)
			(layers "*.Cu" "*.Mask")
			(remove_unused_layers no)
			(net "GND")
			(clearance 0.1524)
			(thermal_gap 0.1524)
		)
		(pad "6" thru_hole circle
			(at 0 3.50012)
			(size 0.762 0.762)
			(drill 0.5588)
			(layers "*.Cu" "*.Mask")
			(remove_unused_layers no)
			(net "GND")
			(clearance 0.1524)
			(thermal_gap 0.1524)
		)
		(pad "7" thru_hole circle
			(at 2.500122 2.500122)
			(size 0.762 0.762)
			(drill 0.5588)
			(layers "*.Cu" "*.Mask")
			(remove_unused_layers no)
			(net "GND")
			(clearance 0.1524)
			(thermal_gap 0.1524)
		)
		(pad "8" thru_hole circle
			(at 3.50012 0)
			(size 0.762 0.762)
			(drill 0.5588)
			(layers "*.Cu" "*.Mask")
			(remove_unused_layers no)
			(net "GND")
			(clearance 0.1524)
			(thermal_gap 0.1524)
		)
		(pad "9" thru_hole circle
			(at 2.500122 -2.500122)
			(size 0.762 0.762)
			(drill 0.5588)
			(layers "*.Cu" "*.Mask")
			(remove_unused_layers no)
			(net "GND")
			(clearance 0.1524)
			(thermal_gap 0.1524)
		)
		(zone
			(layer "F.Cu")
			(hatch none 0.5)
			(connect_pads
				(clearance 0)
			)
			(min_thickness 0.25)
			(keepout
				(tracks not_allowed)
				(vias allowed)
				(pads allowed)
				(copperpour not_allowed)
				(footprints allowed)
			)
			(placement
				(enabled no)
				(sheetname "")
			)
			(fill
				(thermal_gap 0.5)
				(thermal_bridge_width 0.5)
				(island_removal_mode 0)
			)
			(polygon
				(pts
					(arc
						(start 77.999844 -40.30091)
						(mid 69.998844 -32.29991)
						(end 77.999844 -24.29891)
					)
					(arc
						(start 77.999844 -24.29891)
						(mid 79.434944 -25.73401)
						(end 77.999844 -27.16911)
					)
					(arc
						(start 77.999844 -27.16911)
						(mid 72.869044 -32.29991)
						(end 77.999844 -37.43071)
					)
					(arc
						(start 77.999844 -37.43071)
						(mid 79.434944 -38.86581)
						(end 77.999844 -40.30091)
					)
				)
			)
		)
		(zone
			(layer "F.Cu")
			(hatch none 0.5)
			(connect_pads
				(clearance 0)
			)
			(min_thickness 0.25)
			(keepout
				(tracks not_allowed)
				(vias allowed)
				(pads allowed)
				(copperpour not_allowed)
				(footprints allowed)
			)
			(placement
				(enabled no)
				(sheetname "")
			)
			(fill
				(thermal_gap 0.5)
				(thermal_bridge_width 0.5)
				(island_removal_mode 0)
			)
			(polygon
				(pts
					(arc
						(start 77.999844 -40.30091)
						(mid 86.000844 -32.29991)
						(end 77.999844 -24.29891)
					)
					(arc
						(start 77.999844 -24.29891)
						(mid 76.564744 -25.73401)
						(end 77.999844 -27.16911)
					)
					(arc
						(start 77.999844 -27.16911)
						(mid 83.130644 -32.29991)
						(end 77.999844 -37.43071)
					)
					(arc
						(start 77.999844 -37.43071)
						(mid 76.564744 -38.86581)
						(end 77.999844 -40.30091)
					)
				)
			)
		)
		(zone
			(layers "F.Cu" "B.Cu" "In1.Cu" "In2.Cu" "In3.Cu" "In4.Cu" "In5.Cu" "In6.Cu")
			(hatch none 0.5)
			(connect_pads
				(clearance 0)
			)
			(min_thickness 0.25)
			(keepout
				(tracks not_allowed)
				(vias allowed)
				(pads allowed)
				(copperpour not_allowed)
				(footprints allowed)
			)
			(placement
				(enabled no)
				(sheetname "")
			)
			(fill
				(thermal_gap 0.5)
				(thermal_bridge_width 0.5)
				(island_removal_mode 0)
			)
			(polygon
				(pts
					(arc
						(start 80.511904 -32.29991)
						(mid 75.487784 -32.29991)
						(end 80.511904 -32.29991)
					)
				)
			)
		)
	)
	(footprint ""
		(layer "F.Cu")
		(at 13.438124 -322.972176 180)
		(property "Reference" "R147"
			(at -1.656842 -0.102362 0)
			(unlocked yes)
			(layer "F.SilkS")
			(effects
				(font
					(size 0.7874 0.5842)
					(thickness 0.1524)
				)
				(justify left)
			)
		)
		(property "Value" ""
			(at 0 0 180)
			(layer "F.Fab")
			(effects
				(font
					(size 1.27 1.27)
				)
			)
		)
		(duplicate_pad_numbers_are_jumpers no)
		(fp_line
			(start 0.7874 0.4064)
			(end -0.7874 0.4064)
			(stroke
				(width 0.1524)
				(type default)
			)
			(layer "F.SilkS")
		)
		(fp_line
			(start 0.7874 -0.4064)
			(end 0.7874 0.4064)
			(stroke
				(width 0.1524)
				(type default)
			)
			(layer "F.SilkS")
		)
		(fp_line
			(start -0.7874 0.4064)
			(end -0.7874 -0.4064)
			(stroke
				(width 0.1524)
				(type default)
			)
			(layer "F.SilkS")
		)
		(fp_line
			(start -0.7874 -0.4064)
			(end 0.7874 -0.4064)
			(stroke
				(width 0.1524)
				(type default)
			)
			(layer "F.SilkS")
		)
		(fp_poly
			(pts
				(xy -0.508 0.2794) (xy -0.508 0.2286) (xy -0.635 0.2286) (xy -0.635 -0.254) (xy -0.5334 -0.254)
				(xy -0.5334 -0.2794) (xy 0.5334 -0.2794) (xy 0.5334 -0.254) (xy 0.635 -0.254) (xy 0.635 0.254) (xy 0.5334 0.254)
				(xy 0.5334 0.2794)
			)
			(stroke
				(width 0)
				(type default)
			)
			(fill no)
			(layer "F.CrtYd")
		)
		(pad "1" smd rect
			(at 0.40005 0 180)
			(size 0.4572 0.508)
			(layers "F.Cu" "F.Mask" "F.Paste")
			(net "FAN6_TACH")
		)
		(pad "2" smd rect
			(at -0.40005 0 180)
			(size 0.4572 0.508)
			(layers "F.Cu" "F.Mask" "F.Paste")
			(net "P12V")
		)
	)
	(footprint ""
		(layer "F.Cu")
		(at 97.946464 -505.85878)
		(property "Reference" ""
			(at 0 0 0)
			(layer "F.SilkS")
			(hide yes)
			(effects
				(font
					(size 1.27 1.27)
				)
			)
		)
		(property "Value" ""
			(at 0 0 0)
			(layer "F.Fab")
			(effects
				(font
					(size 1.27 1.27)
				)
			)
		)
		(duplicate_pad_numbers_are_jumpers no)
		(fp_poly
			(pts
				(arc
					(start 1.4986 0)
					(mid -1.4986 0)
					(end 1.4986 0)
				)
			)
			(stroke
				(width 0)
				(type default)
			)
			(fill no)
			(layer "F.CrtYd")
		)
		(pad "1" smd circle
			(at 0 0)
			(size 0.9906 0.9906)
			(layers "F.Cu" "F.Mask" "F.Paste")
			(net "Net_222")
		)
		(zone
			(layer "F.Cu")
			(hatch none 0.5)
			(connect_pads
				(clearance 0)
			)
			(min_thickness 0.25)
			(keepout
				(tracks not_allowed)
				(vias allowed)
				(pads allowed)
				(copperpour not_allowed)
				(footprints allowed)
			)
			(placement
				(enabled no)
				(sheetname "")
			)
			(fill
				(thermal_gap 0.5)
				(thermal_bridge_width 0.5)
				(island_removal_mode 0)
			)
			(polygon
				(pts
					(arc
						(start 99.572064 -505.85878)
						(mid 96.320864 -505.85878)
						(end 99.572064 -505.85878)
					)
				)
			)
		)
	)
	(footprint ""
		(layer "F.Cu")
		(at 13.964666 -52.451 -90)
		(property "Reference" "J21"
			(at -4.421378 5.357368 0)
			(unlocked yes)
			(layer "F.SilkS")
			(effects
				(font
					(size 0.7874 0.5842)
					(thickness 0.1524)
				)
				(justify left)
			)
		)
		(property "Value" ""
			(at 0 0 270)
			(layer "F.Fab")
			(effects
				(font
					(size 1.27 1.27)
				)
			)
		)
		(duplicate_pad_numbers_are_jumpers no)
		(fp_line
			(start -3.370072 12.830048)
			(end -3.370072 -3.81)
			(stroke
				(width 0.1524)
				(type default)
			)
			(layer "F.SilkS")
		)
		(fp_line
			(start 12.260072 12.830048)
			(end -3.370072 12.830048)
			(stroke
				(width 0.1524)
				(type default)
			)
			(layer "F.SilkS")
		)
		(fp_line
			(start -3.370072 -3.81)
			(end 12.260072 -3.81)
			(stroke
				(width 0.1524)
				(type default)
			)
			(layer "F.SilkS")
		)
		(fp_line
			(start 12.260072 -3.81)
			(end 12.260072 12.830048)
			(stroke
				(width 0.1524)
				(type default)
			)
			(layer "F.SilkS")
		)
		(fp_poly
			(pts
				(xy -3.576828 0) (xy -5.0038 0.713486) (xy -5.0038 -0.713486)
			)
			(stroke
				(width 0)
				(type default)
			)
			(fill yes)
			(layer "F.SilkS")
		)
		(fp_poly
			(pts
				(xy -0.762 0.762) (xy 8.382 0.762) (xy 8.382 -1.8034) (xy 9.652 -1.8034) (xy 9.652 -3.302) (xy 0.508 -3.302)
				(xy 0.508 -0.762) (xy -0.762 -0.762)
			)
			(stroke
				(width 0)
				(type default)
			)
			(fill no)
			(layer "B.CrtYd")
		)
		(fp_poly
			(pts
				(arc
					(start -1.27 4.4196)
					(mid -1.27 8.2804)
					(end -1.27 4.4196)
				)
			)
			(stroke
				(width 0)
				(type default)
			)
			(fill no)
			(layer "B.CrtYd")
		)
		(fp_poly
			(pts
				(arc
					(start 10.16 4.4196)
					(mid 10.16 8.2804)
					(end 10.16 4.4196)
				)
			)
			(stroke
				(width 0)
				(type default)
			)
			(fill no)
			(layer "B.CrtYd")
		)
		(fp_poly
			(pts
				(xy -3.370072 12.830048) (xy 12.260072 12.830048) (xy 12.260072 -3.81) (xy -3.370072 -3.81)
			)
			(stroke
				(width 0)
				(type default)
			)
			(fill no)
			(layer "F.CrtYd")
		)
		(fp_line
			(start -3.370072 12.830048)
			(end -3.370072 -3.81)
			(stroke
				(width 0.1)
				(type default)
			)
			(layer "F.Fab")
		)
		(fp_line
			(start 12.260072 12.830048)
			(end -3.370072 12.830048)
			(stroke
				(width 0.1)
				(type default)
			)
			(layer "F.Fab")
		)
		(fp_line
			(start -3.370072 -3.81)
			(end 12.260072 -3.81)
			(stroke
				(width 0.1)
				(type default)
			)
			(layer "F.Fab")
		)
		(fp_line
			(start 12.260072 -3.81)
			(end 12.260072 12.830048)
			(stroke
				(width 0.1)
				(type default)
			)
			(layer "F.Fab")
		)
		(fp_poly
			(pts
				(xy -3.576828 0) (xy -5.0038 0.713486) (xy -5.0038 -0.713486)
			)
			(stroke
				(width 0)
				(type default)
			)
			(fill yes)
			(layer "F.Fab")
		)
		(fp_text user "7"
			(at 13.08989 0.05461 0)
			(unlocked yes)
			(layer "F.SilkS")
			(effects
				(font
					(size 0.7874 0.5842)
					(thickness 0.1524)
				)
			)
		)
		(fp_text user "1"
			(at -4.066286 -1.113536 0)
			(unlocked yes)
			(layer "F.SilkS")
			(effects
				(font
					(size 0.7874 0.5842)
					(thickness 0.1524)
				)
			)
		)
		(fp_text user "8"
			(at 12.91463 -2.608834 0)
			(unlocked yes)
			(layer "F.SilkS")
			(effects
				(font
					(size 0.7874 0.5842)
					(thickness 0.1524)
				)
			)
		)
		(fp_text user "2"
			(at -4.101592 -2.863342 0)
			(unlocked yes)
			(layer "F.SilkS")
			(effects
				(font
					(size 0.7874 0.5842)
					(thickness 0.1524)
				)
			)
		)
		(fp_text user "1"
			(at -1.344676 0.284734 0)
			(unlocked yes)
			(layer "B.SilkS")
			(effects
				(font
					(size 0.7874 0.5842)
					(thickness 0.1524)
				)
				(justify mirror)
			)
		)
		(fp_text user "7"
			(at 9.505696 0.062484 0)
			(unlocked yes)
			(layer "B.SilkS")
			(effects
				(font
					(size 0.7874 0.5842)
					(thickness 0.1524)
				)
				(justify mirror)
			)
		)
		(fp_text user "2"
			(at -0.049276 -2.382266 0)
			(unlocked yes)
			(layer "B.SilkS")
			(effects
				(font
					(size 0.7874 0.5842)
					(thickness 0.1524)
				)
				(justify mirror)
			)
		)
		(fp_text user "8"
			(at 10.274808 -2.563368 0)
			(unlocked yes)
			(layer "B.SilkS")
			(effects
				(font
					(size 0.7874 0.5842)
					(thickness 0.1524)
				)
				(justify mirror)
			)
		)
		(fp_text user "7"
			(at 8.8138 0.238252 270)
			(unlocked yes)
			(layer "B.Fab")
			(effects
				(font
					(size 0.7874 0.5842)
					(thickness 0.000001)
				)
				(justify mirror)
			)
		)
		(fp_text user "1"
			(at -1.2954 0.085852 270)
			(unlocked yes)
			(layer "B.Fab")
			(effects
				(font
					(size 0.7874 0.5842)
					(thickness 0.000001)
				)
				(justify mirror)
			)
		)
		(fp_text user "8"
			(at 10.0838 -2.403348 270)
			(unlocked yes)
			(layer "B.Fab")
			(effects
				(font
					(size 0.7874 0.5842)
					(thickness 0.000001)
				)
				(justify mirror)
			)
		)
		(fp_text user "2"
			(at 0 -2.581148 270)
			(unlocked yes)
			(layer "B.Fab")
			(effects
				(font
					(size 0.7874 0.5842)
					(thickness 0.000001)
				)
				(justify mirror)
			)
		)
		(fp_text user "7"
			(at 12.7762 -0.091948 270)
			(unlocked yes)
			(layer "F.Fab")
			(effects
				(font
					(size 0.7874 0.5842)
					(thickness 0.000001)
				)
			)
		)
		(fp_text user "1"
			(at -3.9116 -0.930148 270)
			(unlocked yes)
			(layer "F.Fab")
			(effects
				(font
					(size 0.7874 0.5842)
					(thickness 0.000001)
				)
			)
		)
		(fp_text user "2"
			(at -3.9624 -2.428748 270)
			(unlocked yes)
			(layer "F.Fab")
			(effects
				(font
					(size 0.7874 0.5842)
					(thickness 0.000001)
				)
			)
		)
		(fp_text user "8"
			(at 12.7762 -2.555748 270)
			(unlocked yes)
			(layer "F.Fab")
			(effects
				(font
					(size 0.7874 0.5842)
					(thickness 0.000001)
				)
			)
		)
		(pad "" np_thru_hole circle
			(at -1.27 6.35 270)
			(size 3.3528 3.3528)
			(drill 3.3528)
			(layers "*.Cu" "*.Mask")
			(clearance 0.381)
			(thermal_gap 0.381)
		)
		(pad "" np_thru_hole circle
			(at 10.16 6.35 270)
			(size 3.3528 3.3528)
			(drill 3.3528)
			(layers "*.Cu" "*.Mask")
			(clearance 0.381)
			(thermal_gap 0.381)
		)
		(pad "1" thru_hole rect
			(at 0 0 270)
			(size 1.397 1.397)
			(drill 0.9906)
			(layers "*.Cu" "*.Mask")
			(remove_unused_layers no)
			(net "UART_RTS_P2_L_N")
			(clearance 0.0508)
			(thermal_gap 0.0508)
			(padstack
				(mode front_inner_back)
				(layer "Inner"
					(shape circle)
					(size 1.397 1.397)
					(clearance 0.0508)
				)
				(layer "B.Cu"
					(shape rect)
					(size 1.397 1.397)
					(clearance 0.0508)
				)
			)
		)
		(pad "2" thru_hole circle
			(at 1.27 -2.54 270)
			(size 1.397 1.397)
			(drill 0.9906)
			(layers "*.Cu" "*.Mask")
			(remove_unused_layers no)
			(net "UART_DSR_P2_L_N")
			(clearance 0.0508)
			(thermal_gap 0.0508)
		)
		(pad "3" thru_hole circle
			(at 2.54 0 270)
			(size 1.397 1.397)
			(drill 0.9906)
			(layers "*.Cu" "*.Mask")
			(remove_unused_layers no)
			(net "UART_RX_P2_L")
			(clearance 0.0508)
			(thermal_gap 0.0508)
		)
		(pad "4" thru_hole circle
			(at 3.81 -2.54 270)
			(size 1.397 1.397)
			(drill 0.9906)
			(layers "*.Cu" "*.Mask")
			(remove_unused_layers no)
			(net "GND")
			(clearance 0.0508)
			(thermal_gap 0.0508)
		)
		(pad "5" thru_hole circle
			(at 5.08 0 270)
			(size 1.397 1.397)
			(drill 0.9906)
			(layers "*.Cu" "*.Mask")
			(remove_unused_layers no)
			(net "GND")
			(clearance 0.0508)
			(thermal_gap 0.0508)
		)
		(pad "6" thru_hole circle
			(at 6.35 -2.54 270)
			(size 1.397 1.397)
			(drill 0.9906)
			(layers "*.Cu" "*.Mask")
			(remove_unused_layers no)
			(net "UART_TX_P2_L")
			(clearance 0.0508)
			(thermal_gap 0.0508)
		)
		(pad "7" thru_hole circle
			(at 7.62 0 270)
			(size 1.397 1.397)
			(drill 0.9906)
			(layers "*.Cu" "*.Mask")
			(remove_unused_layers no)
			(net "UART_DTR_P2_L_N")
			(clearance 0.0508)
			(thermal_gap 0.0508)
		)
		(pad "8" thru_hole circle
			(at 8.89 -2.54 270)
			(size 1.397 1.397)
			(drill 0.9906)
			(layers "*.Cu" "*.Mask")
			(remove_unused_layers no)
			(net "UART_CTS_P2_L_N")
			(clearance 0.0508)
			(thermal_gap 0.0508)
		)
		(zone
			(layers "F.Cu" "B.Cu" "In1.Cu" "In2.Cu" "In3.Cu" "In4.Cu" "In5.Cu" "In6.Cu")
			(hatch none 0.5)
			(connect_pads
				(clearance 0)
			)
			(min_thickness 0.25)
			(keepout
				(tracks not_allowed)
				(vias allowed)
				(pads allowed)
				(copperpour not_allowed)
				(footprints allowed)
			)
			(placement
				(enabled no)
				(sheetname "")
			)
			(fill
				(thermal_gap 0.5)
				(thermal_bridge_width 0.5)
				(island_removal_mode 0)
			)
			(polygon
				(pts
					(arc
						(start 9.697466 -53.721)
						(mid 5.531866 -53.721)
						(end 9.697466 -53.721)
					)
				)
			)
		)
		(zone
			(layers "F.Cu" "B.Cu" "In1.Cu" "In2.Cu" "In3.Cu" "In4.Cu" "In5.Cu" "In6.Cu")
			(hatch none 0.5)
			(connect_pads
				(clearance 0)
			)
			(min_thickness 0.25)
			(keepout
				(tracks not_allowed)
				(vias allowed)
				(pads allowed)
				(copperpour not_allowed)
				(footprints allowed)
			)
			(placement
				(enabled no)
				(sheetname "")
			)
			(fill
				(thermal_gap 0.5)
				(thermal_bridge_width 0.5)
				(island_removal_mode 0)
			)
			(polygon
				(pts
					(arc
						(start 9.697466 -42.291)
						(mid 5.531866 -42.291)
						(end 9.697466 -42.291)
					)
				)
			)
		)
	)
	(footprint ""
		(layer "F.Cu")
		(at 46.496478 -248.705116 180)
		(property "Reference" "R95"
			(at -0.92964 -0.866902 0)
			(unlocked yes)
			(layer "F.SilkS")
			(effects
				(font
					(size 0.7874 0.5842)
					(thickness 0.1524)
				)
				(justify left)
			)
		)
		(property "Value" ""
			(at 0 0 180)
			(layer "F.Fab")
			(effects
				(font
					(size 1.27 1.27)
				)
			)
		)
		(duplicate_pad_numbers_are_jumpers no)
		(fp_line
			(start 0.7874 0.4064)
			(end -0.7874 0.4064)
			(stroke
				(width 0.1524)
				(type default)
			)
			(layer "F.SilkS")
		)
		(fp_line
			(start 0.7874 -0.4064)
			(end 0.7874 0.4064)
			(stroke
				(width 0.1524)
				(type default)
			)
			(layer "F.SilkS")
		)
		(fp_line
			(start -0.7874 0.4064)
			(end -0.7874 -0.4064)
			(stroke
				(width 0.1524)
				(type default)
			)
			(layer "F.SilkS")
		)
		(fp_line
			(start -0.7874 -0.4064)
			(end 0.7874 -0.4064)
			(stroke
				(width 0.1524)
				(type default)
			)
			(layer "F.SilkS")
		)
		(fp_poly
			(pts
				(xy -0.508 0.2794) (xy -0.508 0.2286) (xy -0.635 0.2286) (xy -0.635 -0.254) (xy -0.5334 -0.254)
				(xy -0.5334 -0.2794) (xy 0.5334 -0.2794) (xy 0.5334 -0.254) (xy 0.635 -0.254) (xy 0.635 0.254) (xy 0.5334 0.254)
				(xy 0.5334 0.2794)
			)
			(stroke
				(width 0)
				(type default)
			)
			(fill no)
			(layer "F.CrtYd")
		)
		(pad "1" smd rect
			(at 0.40005 0 180)
			(size 0.4572 0.508)
			(layers "F.Cu" "F.Mask" "F.Paste")
			(net "PSU3_REMOTE_R_N")
		)
		(pad "2" smd rect
			(at -0.40005 0 180)
			(size 0.4572 0.508)
			(layers "F.Cu" "F.Mask" "F.Paste")
			(net "GND")
		)
	)
	(footprint ""
		(layer "F.Cu")
		(at 27.347672 -108.630466 -90)
		(property "Reference" "R93"
			(at -0.391414 1.160526 90)
			(unlocked yes)
			(layer "F.SilkS")
			(effects
				(font
					(size 0.7874 0.5842)
					(thickness 0.1524)
				)
				(justify left)
			)
		)
		(property "Value" ""
			(at 0 0 270)
			(layer "F.Fab")
			(effects
				(font
					(size 1.27 1.27)
				)
			)
		)
		(duplicate_pad_numbers_are_jumpers no)
		(fp_line
			(start -0.7874 0.4064)
			(end -0.7874 -0.4064)
			(stroke
				(width 0.1524)
				(type default)
			)
			(layer "F.SilkS")
		)
		(fp_line
			(start 0.7874 0.4064)
			(end -0.7874 0.4064)
			(stroke
				(width 0.1524)
				(type default)
			)
			(layer "F.SilkS")
		)
		(fp_line
			(start -0.7874 -0.4064)
			(end 0.7874 -0.4064)
			(stroke
				(width 0.1524)
				(type default)
			)
			(layer "F.SilkS")
		)
		(fp_line
			(start 0.7874 -0.4064)
			(end 0.7874 0.4064)
			(stroke
				(width 0.1524)
				(type default)
			)
			(layer "F.SilkS")
		)
		(fp_poly
			(pts
				(xy -0.508 0.2794) (xy -0.508 0.2286) (xy -0.635 0.2286) (xy -0.635 -0.254) (xy -0.5334 -0.254)
				(xy -0.5334 -0.2794) (xy 0.5334 -0.2794) (xy 0.5334 -0.254) (xy 0.635 -0.254) (xy 0.635 0.254) (xy 0.5334 0.254)
				(xy 0.5334 0.2794)
			)
			(stroke
				(width 0)
				(type default)
			)
			(fill no)
			(layer "F.CrtYd")
		)
		(pad "1" smd rect
			(at 0.40005 0 270)
			(size 0.4572 0.508)
			(layers "F.Cu" "F.Mask" "F.Paste")
			(net "PSU2_REMOTE_N")
		)
		(pad "2" smd rect
			(at -0.40005 0 270)
			(size 0.4572 0.508)
			(layers "F.Cu" "F.Mask" "F.Paste")
			(net "PSU2_REMOTE_R_N")
		)
	)
	(footprint ""
		(layer "F.Cu")
		(at 13.964666 -105.537 -90)
		(property "Reference" "J27"
			(at -4.11607 4.406138 0)
			(unlocked yes)
			(layer "F.SilkS")
			(effects
				(font
					(size 0.7874 0.5842)
					(thickness 0.1524)
				)
				(justify left)
			)
		)
		(property "Value" ""
			(at 0 0 270)
			(layer "F.Fab")
			(effects
				(font
					(size 1.27 1.27)
				)
			)
		)
		(duplicate_pad_numbers_are_jumpers no)
		(fp_line
			(start -3.370072 12.830048)
			(end -3.370072 -3.81)
			(stroke
				(width 0.1524)
				(type default)
			)
			(layer "F.SilkS")
		)
		(fp_line
			(start 12.260072 12.830048)
			(end -3.370072 12.830048)
			(stroke
				(width 0.1524)
				(type default)
			)
			(layer "F.SilkS")
		)
		(fp_line
			(start -3.370072 -3.81)
			(end 12.260072 -3.81)
			(stroke
				(width 0.1524)
				(type default)
			)
			(layer "F.SilkS")
		)
		(fp_line
			(start 12.260072 -3.81)
			(end 12.260072 12.830048)
			(stroke
				(width 0.1524)
				(type default)
			)
			(layer "F.SilkS")
		)
		(fp_poly
			(pts
				(xy -0.073914 -4.222496) (xy -0.7874 -5.649468) (xy 0.639572 -5.649468)
			)
			(stroke
				(width 0)
				(type default)
			)
			(fill yes)
			(layer "F.SilkS")
		)
		(fp_poly
			(pts
				(xy -0.762 0.762) (xy 8.382 0.762) (xy 8.382 -1.8034) (xy 9.652 -1.8034) (xy 9.652 -3.302) (xy 0.508 -3.302)
				(xy 0.508 -0.762) (xy -0.762 -0.762)
			)
			(stroke
				(width 0)
				(type default)
			)
			(fill no)
			(layer "B.CrtYd")
		)
		(fp_poly
			(pts
				(arc
					(start -1.27 4.4196)
					(mid -1.27 8.2804)
					(end -1.27 4.4196)
				)
			)
			(stroke
				(width 0)
				(type default)
			)
			(fill no)
			(layer "B.CrtYd")
		)
		(fp_poly
			(pts
				(arc
					(start 10.16 4.4196)
					(mid 10.16 8.2804)
					(end 10.16 4.4196)
				)
			)
			(stroke
				(width 0)
				(type default)
			)
			(fill no)
			(layer "B.CrtYd")
		)
		(fp_poly
			(pts
				(xy -3.370072 12.830048) (xy 12.260072 12.830048) (xy 12.260072 -3.81) (xy -3.370072 -3.81)
			)
			(stroke
				(width 0)
				(type default)
			)
			(fill no)
			(layer "F.CrtYd")
		)
		(fp_line
			(start -3.370072 12.830048)
			(end -3.370072 -3.81)
			(stroke
				(width 0.1)
				(type default)
			)
			(layer "F.Fab")
		)
		(fp_line
			(start 12.260072 12.830048)
			(end -3.370072 12.830048)
			(stroke
				(width 0.1)
				(type default)
			)
			(layer "F.Fab")
		)
		(fp_line
			(start -3.370072 -3.81)
			(end 12.260072 -3.81)
			(stroke
				(width 0.1)
				(type default)
			)
			(layer "F.Fab")
		)
		(fp_line
			(start 12.260072 -3.81)
			(end 12.260072 12.830048)
			(stroke
				(width 0.1)
				(type default)
			)
			(layer "F.Fab")
		)
		(fp_poly
			(pts
				(xy -3.576828 0) (xy -5.0038 0.713486) (xy -5.0038 -0.713486)
			)
			(stroke
				(width 0)
				(type default)
			)
			(fill yes)
			(layer "F.Fab")
		)
		(fp_text user "1"
			(at -4.192016 0.242062 0)
			(unlocked yes)
			(layer "F.SilkS")
			(effects
				(font
					(size 0.7874 0.5842)
					(thickness 0.1524)
				)
			)
		)
		(fp_text user "7"
			(at 13.095224 -0.165354 0)
			(unlocked yes)
			(layer "F.SilkS")
			(effects
				(font
					(size 0.7874 0.5842)
					(thickness 0.1524)
				)
			)
		)
		(fp_text user "2"
			(at -4.021328 -2.464308 0)
			(unlocked yes)
			(layer "F.SilkS")
			(effects
				(font
					(size 0.7874 0.5842)
					(thickness 0.1524)
				)
			)
		)
		(fp_text user "8"
			(at 13.032486 -2.6035 0)
			(unlocked yes)
			(layer "F.SilkS")
			(effects
				(font
					(size 0.7874 0.5842)
					(thickness 0.1524)
				)
			)
		)
		(fp_text user "1"
			(at -1.484376 -0.020066 0)
			(unlocked yes)
			(layer "B.SilkS")
			(effects
				(font
					(size 0.7874 0.5842)
					(thickness 0.1524)
				)
				(justify mirror)
			)
		)
		(fp_text user "7"
			(at 9.450578 -0.041148 0)
			(unlocked yes)
			(layer "B.SilkS")
			(effects
				(font
					(size 0.7874 0.5842)
					(thickness 0.1524)
				)
				(justify mirror)
			)
		)
		(fp_text user "8"
			(at 10.720578 -2.682748 0)
			(unlocked yes)
			(layer "B.SilkS")
			(effects
				(font
					(size 0.7874 0.5842)
					(thickness 0.1524)
				)
				(justify mirror)
			)
		)
		(fp_text user "2"
			(at -0.188976 -2.687066 0)
			(unlocked yes)
			(layer "B.SilkS")
			(effects
				(font
					(size 0.7874 0.5842)
					(thickness 0.1524)
				)
				(justify mirror)
			)
		)
		(fp_text user "7"
			(at 8.8138 0.238252 270)
			(unlocked yes)
			(layer "B.Fab")
			(effects
				(font
					(size 0.7874 0.5842)
					(thickness 0.000001)
				)
				(justify mirror)
			)
		)
		(fp_text user "1"
			(at -1.2954 0.085852 270)
			(unlocked yes)
			(layer "B.Fab")
			(effects
				(font
					(size 0.7874 0.5842)
					(thickness 0.000001)
				)
				(justify mirror)
			)
		)
		(fp_text user "8"
			(at 10.0838 -2.403348 270)
			(unlocked yes)
			(layer "B.Fab")
			(effects
				(font
					(size 0.7874 0.5842)
					(thickness 0.000001)
				)
				(justify mirror)
			)
		)
		(fp_text user "2"
			(at 0 -2.581148 270)
			(unlocked yes)
			(layer "B.Fab")
			(effects
				(font
					(size 0.7874 0.5842)
					(thickness 0.000001)
				)
				(justify mirror)
			)
		)
		(fp_text user "7"
			(at 12.7762 -0.091948 270)
			(unlocked yes)
			(layer "F.Fab")
			(effects
				(font
					(size 0.7874 0.5842)
					(thickness 0.000001)
				)
			)
		)
		(fp_text user "1"
			(at -3.9116 -0.930148 270)
			(unlocked yes)
			(layer "F.Fab")
			(effects
				(font
					(size 0.7874 0.5842)
					(thickness 0.000001)
				)
			)
		)
		(fp_text user "2"
			(at -3.9624 -2.428748 270)
			(unlocked yes)
			(layer "F.Fab")
			(effects
				(font
					(size 0.7874 0.5842)
					(thickness 0.000001)
				)
			)
		)
		(fp_text user "8"
			(at 12.7762 -2.555748 270)
			(unlocked yes)
			(layer "F.Fab")
			(effects
				(font
					(size 0.7874 0.5842)
					(thickness 0.000001)
				)
			)
		)
		(pad "" np_thru_hole circle
			(at -1.27 6.35 270)
			(size 3.3528 3.3528)
			(drill 3.3528)
			(layers "*.Cu" "*.Mask")
			(clearance 0.381)
			(thermal_gap 0.381)
		)
		(pad "" np_thru_hole circle
			(at 10.16 6.35 270)
			(size 3.3528 3.3528)
			(drill 3.3528)
			(layers "*.Cu" "*.Mask")
			(clearance 0.381)
			(thermal_gap 0.381)
		)
		(pad "1" thru_hole rect
			(at 0 0 270)
			(size 1.397 1.397)
			(drill 0.9906)
			(layers "*.Cu" "*.Mask")
			(remove_unused_layers no)
			(net "UART_RTS_P6_L_N")
			(clearance 0.0508)
			(thermal_gap 0.0508)
			(padstack
				(mode front_inner_back)
				(layer "Inner"
					(shape circle)
					(size 1.397 1.397)
					(clearance 0.0508)
				)
				(layer "B.Cu"
					(shape rect)
					(size 1.397 1.397)
					(clearance 0.0508)
				)
			)
		)
		(pad "2" thru_hole circle
			(at 1.27 -2.54 270)
			(size 1.397 1.397)
			(drill 0.9906)
			(layers "*.Cu" "*.Mask")
			(remove_unused_layers no)
			(net "UART_DSR_P6_L_N")
			(clearance 0.0508)
			(thermal_gap 0.0508)
		)
		(pad "3" thru_hole circle
			(at 2.54 0 270)
			(size 1.397 1.397)
			(drill 0.9906)
			(layers "*.Cu" "*.Mask")
			(remove_unused_layers no)
			(net "UART_RX_P6_L")
			(clearance 0.0508)
			(thermal_gap 0.0508)
		)
		(pad "4" thru_hole circle
			(at 3.81 -2.54 270)
			(size 1.397 1.397)
			(drill 0.9906)
			(layers "*.Cu" "*.Mask")
			(remove_unused_layers no)
			(net "UART_RI_P6_L_N")
			(clearance 0.0508)
			(thermal_gap 0.0508)
		)
		(pad "5" thru_hole circle
			(at 5.08 0 270)
			(size 1.397 1.397)
			(drill 0.9906)
			(layers "*.Cu" "*.Mask")
			(remove_unused_layers no)
			(net "GND")
			(clearance 0.0508)
			(thermal_gap 0.0508)
		)
		(pad "6" thru_hole circle
			(at 6.35 -2.54 270)
			(size 1.397 1.397)
			(drill 0.9906)
			(layers "*.Cu" "*.Mask")
			(remove_unused_layers no)
			(net "UART_TX_P6_L")
			(clearance 0.0508)
			(thermal_gap 0.0508)
		)
		(pad "7" thru_hole circle
			(at 7.62 0 270)
			(size 1.397 1.397)
			(drill 0.9906)
			(layers "*.Cu" "*.Mask")
			(remove_unused_layers no)
			(net "UART_DTR_P6_L_N")
			(clearance 0.0508)
			(thermal_gap 0.0508)
		)
		(pad "8" thru_hole circle
			(at 8.89 -2.54 270)
			(size 1.397 1.397)
			(drill 0.9906)
			(layers "*.Cu" "*.Mask")
			(remove_unused_layers no)
			(net "UART_CTS_P6_L_N")
			(clearance 0.0508)
			(thermal_gap 0.0508)
		)
		(zone
			(layers "F.Cu" "B.Cu" "In1.Cu" "In2.Cu" "In3.Cu" "In4.Cu" "In5.Cu" "In6.Cu")
			(hatch none 0.5)
			(connect_pads
				(clearance 0)
			)
			(min_thickness 0.25)
			(keepout
				(tracks not_allowed)
				(vias allowed)
				(pads allowed)
				(copperpour not_allowed)
				(footprints allowed)
			)
			(placement
				(enabled no)
				(sheetname "")
			)
			(fill
				(thermal_gap 0.5)
				(thermal_bridge_width 0.5)
				(island_removal_mode 0)
			)
			(polygon
				(pts
					(arc
						(start 9.697466 -106.807)
						(mid 5.531866 -106.807)
						(end 9.697466 -106.807)
					)
				)
			)
		)
		(zone
			(layers "F.Cu" "B.Cu" "In1.Cu" "In2.Cu" "In3.Cu" "In4.Cu" "In5.Cu" "In6.Cu")
			(hatch none 0.5)
			(connect_pads
				(clearance 0)
			)
			(min_thickness 0.25)
			(keepout
				(tracks not_allowed)
				(vias allowed)
				(pads allowed)
				(copperpour not_allowed)
				(footprints allowed)
			)
			(placement
				(enabled no)
				(sheetname "")
			)
			(fill
				(thermal_gap 0.5)
				(thermal_bridge_width 0.5)
				(island_removal_mode 0)
			)
			(polygon
				(pts
					(arc
						(start 9.697466 -95.377)
						(mid 5.531866 -95.377)
						(end 9.697466 -95.377)
					)
				)
			)
		)
	)
	(footprint ""
		(layer "F.Cu")
		(at 72.157844 -419.796722 -90)
		(property "Reference" "C64"
			(at 2.880106 -0.214376 90)
			(unlocked yes)
			(layer "F.SilkS")
			(effects
				(font
					(size 0.7874 0.5842)
					(thickness 0.1524)
				)
			)
		)
		(property "Value" ""
			(at 0 0 270)
			(layer "F.Fab")
			(effects
				(font
					(size 1.27 1.27)
				)
			)
		)
		(duplicate_pad_numbers_are_jumpers no)
		(fp_line
			(start -1.2954 0.5842)
			(end -1.2954 -0.5842)
			(stroke
				(width 0.1524)
				(type default)
			)
			(layer "F.SilkS")
		)
		(fp_line
			(start 1.2954 0.5842)
			(end -1.2954 0.5842)
			(stroke
				(width 0.1524)
				(type default)
			)
			(layer "F.SilkS")
		)
		(fp_line
			(start -1.2954 -0.5842)
			(end 1.2954 -0.5842)
			(stroke
				(width 0.1524)
				(type default)
			)
			(layer "F.SilkS")
		)
		(fp_line
			(start 0 -0.5842)
			(end 0 0.5842)
			(stroke
				(width 0.1524)
				(type default)
			)
			(layer "F.SilkS")
		)
		(fp_line
			(start 1.2954 -0.5842)
			(end 1.2954 0.5842)
			(stroke
				(width 0.1524)
				(type default)
			)
			(layer "F.SilkS")
		)
		(fp_poly
			(pts
				(xy 0.8636 -0.4572) (xy 0.8636 -0.3556) (xy 1.143 -0.3556) (xy 1.143 0.3556) (xy 0.8636 0.3556)
				(xy 0.8636 0.4572) (xy -0.8636 0.4572) (xy -0.8636 0.3556) (xy -1.143 0.3556) (xy -1.143 -0.3556)
				(xy -0.8636 -0.3556) (xy -0.8636 -0.4572)
			)
			(stroke
				(width 0)
				(type default)
			)
			(fill no)
			(layer "F.CrtYd")
		)
		(fp_line
			(start -0.884936 0.504952)
			(end -0.884936 -0.504952)
			(stroke
				(width 0.1)
				(type default)
			)
			(layer "F.Fab")
		)
		(fp_line
			(start 0.884936 0.504952)
			(end -0.884936 0.504952)
			(stroke
				(width 0.1)
				(type default)
			)
			(layer "F.Fab")
		)
		(fp_line
			(start -0.884936 -0.504952)
			(end 0.884936 -0.504952)
			(stroke
				(width 0.1)
				(type default)
			)
			(layer "F.Fab")
		)
		(fp_line
			(start 0.884936 -0.504952)
			(end 0.884936 0.504952)
			(stroke
				(width 0.1)
				(type default)
			)
			(layer "F.Fab")
		)
		(pad "1" smd rect
			(at 0.7366 0)
			(size 0.7112 0.8128)
			(layers "F.Cu" "F.Mask" "F.Paste")
			(net "P12V")
		)
		(pad "2" smd rect
			(at -0.7366 0)
			(size 0.7112 0.8128)
			(layers "F.Cu" "F.Mask" "F.Paste")
			(net "GND")
		)
	)
	(footprint ""
		(layer "F.Cu")
		(at 74.709782 -330.332588 -90)
		(property "Reference" "C52"
			(at 3.323336 -0.058674 90)
			(unlocked yes)
			(layer "F.SilkS")
			(effects
				(font
					(size 0.7874 0.5842)
					(thickness 0.1524)
				)
				(justify left)
			)
		)
		(property "Value" ""
			(at 0 0 270)
			(layer "F.Fab")
			(effects
				(font
					(size 1.27 1.27)
				)
			)
		)
		(duplicate_pad_numbers_are_jumpers no)
		(fp_line
			(start -0.7874 0.4064)
			(end -0.7874 -0.4064)
			(stroke
				(width 0.1524)
				(type default)
			)
			(layer "F.SilkS")
		)
		(fp_line
			(start 0.7874 0.4064)
			(end -0.7874 0.4064)
			(stroke
				(width 0.1524)
				(type default)
			)
			(layer "F.SilkS")
		)
		(fp_line
			(start 0 0.381)
			(end 0 -0.381)
			(stroke
				(width 0.1524)
				(type default)
			)
			(layer "F.SilkS")
		)
		(fp_line
			(start -0.7874 -0.4064)
			(end 0.7874 -0.4064)
			(stroke
				(width 0.1524)
				(type default)
			)
			(layer "F.SilkS")
		)
		(fp_line
			(start 0.7874 -0.4064)
			(end 0.7874 0.4064)
			(stroke
				(width 0.1524)
				(type default)
			)
			(layer "F.SilkS")
		)
		(fp_poly
			(pts
				(xy -0.5334 0.254) (xy -0.635 0.254) (xy -0.635 0.2286) (xy -0.635 -0.254) (xy -0.5334 -0.254) (xy -0.5334 -0.2794)
				(xy 0.5334 -0.2794) (xy 0.5334 -0.254) (xy 0.635 -0.254) (xy 0.635 0.254) (xy 0.5334 0.254) (xy 0.5334 0.2794)
				(xy -0.508 0.2794) (xy -0.5334 0.2794)
			)
			(stroke
				(width 0)
				(type default)
			)
			(fill no)
			(layer "F.CrtYd")
		)
		(pad "1" smd rect
			(at 0.40005 0 270)
			(size 0.4572 0.508)
			(layers "F.Cu" "F.Mask" "F.Paste")
			(net "P12V")
		)
		(pad "2" smd rect
			(at -0.40005 0 270)
			(size 0.4572 0.508)
			(layers "F.Cu" "F.Mask" "F.Paste")
			(net "GND")
		)
	)
	(footprint ""
		(layer "F.Cu")
		(at 26.732484 -456.748896)
		(property "Reference" "R139"
			(at -3.883914 0.13208 0)
			(unlocked yes)
			(layer "F.SilkS")
			(effects
				(font
					(size 0.7874 0.5842)
					(thickness 0.1524)
				)
				(justify left)
			)
		)
		(property "Value" ""
			(at 0 0 0)
			(layer "F.Fab")
			(effects
				(font
					(size 1.27 1.27)
				)
			)
		)
		(duplicate_pad_numbers_are_jumpers no)
		(fp_line
			(start -0.7874 -0.4064)
			(end 0.7874 -0.4064)
			(stroke
				(width 0.1524)
				(type default)
			)
			(layer "F.SilkS")
		)
		(fp_line
			(start -0.7874 0.4064)
			(end -0.7874 -0.4064)
			(stroke
				(width 0.1524)
				(type default)
			)
			(layer "F.SilkS")
		)
		(fp_line
			(start 0.7874 -0.4064)
			(end 0.7874 0.4064)
			(stroke
				(width 0.1524)
				(type default)
			)
			(layer "F.SilkS")
		)
		(fp_line
			(start 0.7874 0.4064)
			(end -0.7874 0.4064)
			(stroke
				(width 0.1524)
				(type default)
			)
			(layer "F.SilkS")
		)
		(fp_poly
			(pts
				(xy -0.508 0.2794) (xy -0.508 0.2286) (xy -0.635 0.2286) (xy -0.635 -0.254) (xy -0.5334 -0.254)
				(xy -0.5334 -0.2794) (xy 0.5334 -0.2794) (xy 0.5334 -0.254) (xy 0.635 -0.254) (xy 0.635 0.254) (xy 0.5334 0.254)
				(xy 0.5334 0.2794)
			)
			(stroke
				(width 0)
				(type default)
			)
			(fill no)
			(layer "F.CrtYd")
		)
		(pad "1" smd rect
			(at 0.40005 0)
			(size 0.4572 0.508)
			(layers "F.Cu" "F.Mask" "F.Paste")
			(net "PSU6_CSAHRE")
		)
		(pad "2" smd rect
			(at -0.40005 0)
			(size 0.4572 0.508)
			(layers "F.Cu" "F.Mask" "F.Paste")
			(net "PSU_CSAHRE")
		)
	)
	(footprint ""
		(layer "F.Cu")
		(at 25.857708 -365.50092)
		(property "Reference" "R79"
			(at -3.917442 -0.225298 0)
			(unlocked yes)
			(layer "F.SilkS")
			(effects
				(font
					(size 0.7874 0.5842)
					(thickness 0.1524)
				)
				(justify left)
			)
		)
		(property "Value" ""
			(at 0 0 0)
			(layer "F.Fab")
			(effects
				(font
					(size 1.27 1.27)
				)
			)
		)
		(duplicate_pad_numbers_are_jumpers no)
		(fp_line
			(start -0.7874 -0.4064)
			(end 0.7874 -0.4064)
			(stroke
				(width 0.1524)
				(type default)
			)
			(layer "F.SilkS")
		)
		(fp_line
			(start -0.7874 0.4064)
			(end -0.7874 -0.4064)
			(stroke
				(width 0.1524)
				(type default)
			)
			(layer "F.SilkS")
		)
		(fp_line
			(start 0.7874 -0.4064)
			(end 0.7874 0.4064)
			(stroke
				(width 0.1524)
				(type default)
			)
			(layer "F.SilkS")
		)
		(fp_line
			(start 0.7874 0.4064)
			(end -0.7874 0.4064)
			(stroke
				(width 0.1524)
				(type default)
			)
			(layer "F.SilkS")
		)
		(fp_poly
			(pts
				(xy -0.508 0.2794) (xy -0.508 0.2286) (xy -0.635 0.2286) (xy -0.635 -0.254) (xy -0.5334 -0.254)
				(xy -0.5334 -0.2794) (xy 0.5334 -0.2794) (xy 0.5334 -0.254) (xy 0.635 -0.254) (xy 0.635 0.254) (xy 0.5334 0.254)
				(xy 0.5334 0.2794)
			)
			(stroke
				(width 0)
				(type default)
			)
			(fill no)
			(layer "F.CrtYd")
		)
		(pad "1" smd rect
			(at 0.40005 0)
			(size 0.4572 0.508)
			(layers "F.Cu" "F.Mask" "F.Paste")
			(net "PSU5_PS_KILL")
		)
		(pad "2" smd rect
			(at -0.40005 0)
			(size 0.4572 0.508)
			(layers "F.Cu" "F.Mask" "F.Paste")
			(net "GND")
		)
	)
	(footprint ""
		(layer "F.Cu")
		(at 30.45968 -525.329912)
		(property "Reference" "J6"
			(at 8.641842 9.092438 90)
			(unlocked yes)
			(layer "F.SilkS")
			(effects
				(font
					(size 0.7874 0.5842)
					(thickness 0.1524)
				)
				(justify left)
			)
		)
		(property "Value" ""
			(at 0 0 0)
			(layer "F.Fab")
			(effects
				(font
					(size 1.27 1.27)
				)
			)
		)
		(duplicate_pad_numbers_are_jumpers no)
		(fp_line
			(start -2.135124 -4.560062)
			(end -2.135124 83.300062)
			(stroke
				(width 0.1524)
				(type default)
			)
			(layer "F.SilkS")
		)
		(fp_line
			(start -2.135124 83.300062)
			(end 7.215124 83.300062)
			(stroke
				(width 0.1524)
				(type default)
			)
			(layer "F.SilkS")
		)
		(fp_line
			(start 7.215124 -4.560062)
			(end -2.135124 -4.560062)
			(stroke
				(width 0.1524)
				(type default)
			)
			(layer "F.SilkS")
		)
		(fp_line
			(start 7.215124 83.300062)
			(end 7.215124 -4.560062)
			(stroke
				(width 0.1524)
				(type default)
			)
			(layer "F.SilkS")
		)
		(fp_poly
			(pts
				(xy -2.491486 0.079248) (xy -5.191506 -0.620776) (xy -5.191506 0.779272)
			)
			(stroke
				(width 0)
				(type default)
			)
			(fill yes)
			(layer "F.SilkS")
		)
		(fp_poly
			(pts
				(xy -2.28219 -0.127) (xy -4.98221 -0.827024) (xy -4.98221 0.573024)
			)
			(stroke
				(width 0)
				(type default)
			)
			(fill yes)
			(layer "B.SilkS")
		)
		(fp_poly
			(pts
				(xy -0.8636 -0.8636) (xy -0.8636 79.6036) (xy -0.8636 79.629) (xy 5.9436 79.629) (xy 5.9436 79.6036)
				(xy 5.9436 -0.8636) (xy 5.9436 -0.889) (xy -0.8636 -0.889)
			)
			(stroke
				(width 0)
				(type default)
			)
			(fill no)
			(layer "B.CrtYd")
		)
		(fp_rect
			(start -2.135124 -4.560062)
			(end 7.21487 83.300062)
			(stroke
				(width 0)
				(type default)
			)
			(fill no)
			(layer "F.CrtYd")
		)
		(fp_line
			(start -2.135124 -4.560062)
			(end 7.215124 -4.560062)
			(stroke
				(width 0.1)
				(type default)
			)
			(layer "F.Fab")
		)
		(fp_line
			(start -2.135124 83.300062)
			(end -2.135124 -4.560062)
			(stroke
				(width 0.1)
				(type default)
			)
			(layer "F.Fab")
		)
		(fp_line
			(start 7.215124 -4.560062)
			(end 7.215124 83.300062)
			(stroke
				(width 0.1)
				(type default)
			)
			(layer "F.Fab")
		)
		(fp_line
			(start 7.215124 83.300062)
			(end -2.135124 83.300062)
			(stroke
				(width 0.1)
				(type default)
			)
			(layer "F.Fab")
		)
		(fp_text user "32"
			(at -4.018788 80.194912 0)
			(unlocked yes)
			(layer "F.SilkS")
			(effects
				(font
					(size 0.7874 0.5842)
					(thickness 0.1524)
				)
				(justify left)
			)
		)
		(fp_text user "1"
			(at -3.120644 -1.027176 0)
			(unlocked yes)
			(layer "F.SilkS")
			(effects
				(font
					(size 0.7874 0.5842)
					(thickness 0.1524)
				)
				(justify left)
			)
		)
		(fp_text user "64"
			(at 7.523988 -0.308864 0)
			(unlocked yes)
			(layer "F.SilkS")
			(effects
				(font
					(size 0.7874 0.5842)
					(thickness 0.1524)
				)
				(justify left)
			)
		)
		(fp_text user "33"
			(at 7.80161 81.392268 0)
			(unlocked yes)
			(layer "F.SilkS")
			(effects
				(font
					(size 0.7874 0.5842)
					(thickness 0.1524)
				)
				(justify left)
			)
		)
		(fp_text user "32"
			(at -1.360678 79.256636 0)
			(unlocked yes)
			(layer "B.SilkS")
			(effects
				(font
					(size 0.7874 0.5842)
					(thickness 0.1524)
				)
				(justify left mirror)
			)
		)
		(fp_text user "1"
			(at -1.297686 -1.511046 0)
			(unlocked yes)
			(layer "B.SilkS")
			(effects
				(font
					(size 0.7874 0.5842)
					(thickness 0.1524)
				)
				(justify left mirror)
			)
		)
		(fp_text user "33"
			(at 5.67055 81.353152 0)
			(unlocked yes)
			(layer "B.SilkS")
			(effects
				(font
					(size 0.7874 0.5842)
					(thickness 0.1524)
				)
				(justify left mirror)
			)
		)
		(fp_text user "64"
			(at 5.908802 -1.856994 0)
			(unlocked yes)
			(layer "B.SilkS")
			(effects
				(font
					(size 0.7874 0.5842)
					(thickness 0.1524)
				)
				(justify left mirror)
			)
		)
		(pad "1" thru_hole rect
			(at 0 0 270)
			(size 1.6256 1.6256)
			(drill 1.1176)
			(layers "*.Cu" "*.Mask")
			(remove_unused_layers no)
			(net "P12V")
			(clearance 0)
			(padstack
				(mode front_inner_back)
				(layer "Inner"
					(shape circle)
					(size 1.6256 1.6256)
					(clearance 0)
				)
				(layer "B.Cu"
					(shape rect)
					(size 1.6256 1.6256)
					(clearance 0)
				)
			)
		)
		(pad "2" thru_hole circle
			(at 0 2.54 270)
			(size 1.6256 1.6256)
			(drill 1.1176)
			(layers "*.Cu" "*.Mask")
			(remove_unused_layers no)
			(net "P12V")
			(clearance 0)
		)
		(pad "3" thru_hole circle
			(at 0 5.08 270)
			(size 1.6256 1.6256)
			(drill 1.1176)
			(layers "*.Cu" "*.Mask")
			(remove_unused_layers no)
			(net "P12V")
			(clearance 0)
		)
		(pad "4" thru_hole circle
			(at 0 7.62 270)
			(size 1.6256 1.6256)
			(drill 1.1176)
			(layers "*.Cu" "*.Mask")
			(remove_unused_layers no)
			(net "P12V")
			(clearance 0)
		)
		(pad "5" thru_hole circle
			(at 0 10.16 270)
			(size 1.6256 1.6256)
			(drill 1.1176)
			(layers "*.Cu" "*.Mask")
			(remove_unused_layers no)
			(net "P12V")
			(clearance 0)
		)
		(pad "6" thru_hole circle
			(at 0 12.7 270)
			(size 1.6256 1.6256)
			(drill 1.1176)
			(layers "*.Cu" "*.Mask")
			(remove_unused_layers no)
			(net "P12V")
			(clearance 0)
		)
		(pad "7" thru_hole circle
			(at 0 15.24 270)
			(size 1.6256 1.6256)
			(drill 1.1176)
			(layers "*.Cu" "*.Mask")
			(remove_unused_layers no)
			(net "P12V")
			(clearance 0)
		)
		(pad "8" thru_hole circle
			(at 0 17.78 270)
			(size 1.6256 1.6256)
			(drill 1.1176)
			(layers "*.Cu" "*.Mask")
			(remove_unused_layers no)
			(net "P12V")
			(clearance 0)
		)
		(pad "9" thru_hole circle
			(at 0 20.32 270)
			(size 1.6256 1.6256)
			(drill 1.1176)
			(layers "*.Cu" "*.Mask")
			(remove_unused_layers no)
			(net "P12V")
			(clearance 0)
		)
		(pad "10" thru_hole circle
			(at 0 22.86 270)
			(size 1.6256 1.6256)
			(drill 1.1176)
			(layers "*.Cu" "*.Mask")
			(remove_unused_layers no)
			(net "P12V")
			(clearance 0)
		)
		(pad "11" thru_hole circle
			(at 0 25.4 270)
			(size 1.6256 1.6256)
			(drill 1.1176)
			(layers "*.Cu" "*.Mask")
			(remove_unused_layers no)
			(net "P12V")
			(clearance 0)
		)
		(pad "12" thru_hole circle
			(at 0 27.94 270)
			(size 1.6256 1.6256)
			(drill 1.1176)
			(layers "*.Cu" "*.Mask")
			(remove_unused_layers no)
			(net "P12V")
			(clearance 0)
		)
		(pad "13" thru_hole circle
			(at 0 30.48 270)
			(size 1.6256 1.6256)
			(drill 1.1176)
			(layers "*.Cu" "*.Mask")
			(remove_unused_layers no)
			(net "GND")
			(clearance 0)
		)
		(pad "14" thru_hole circle
			(at 0 33.02 270)
			(size 1.6256 1.6256)
			(drill 1.1176)
			(layers "*.Cu" "*.Mask")
			(remove_unused_layers no)
			(net "GND")
			(clearance 0)
		)
		(pad "15" thru_hole circle
			(at 0 35.56 270)
			(size 1.6256 1.6256)
			(drill 1.1176)
			(layers "*.Cu" "*.Mask")
			(remove_unused_layers no)
			(net "GND")
			(clearance 0)
		)
		(pad "16" thru_hole circle
			(at 0 38.1 270)
			(size 1.6256 1.6256)
			(drill 1.1176)
			(layers "*.Cu" "*.Mask")
			(remove_unused_layers no)
			(net "GND")
			(clearance 0)
		)
		(pad "17" thru_hole circle
			(at 0 40.64 270)
			(size 1.6256 1.6256)
			(drill 1.1176)
			(layers "*.Cu" "*.Mask")
			(remove_unused_layers no)
			(net "GND")
			(clearance 0)
		)
		(pad "18" thru_hole circle
			(at 0 43.18 270)
			(size 1.6256 1.6256)
			(drill 1.1176)
			(layers "*.Cu" "*.Mask")
			(remove_unused_layers no)
			(net "GND")
			(clearance 0)
		)
		(pad "19" thru_hole circle
			(at 0 45.72 270)
			(size 1.6256 1.6256)
			(drill 1.1176)
			(layers "*.Cu" "*.Mask")
			(remove_unused_layers no)
			(net "GND")
			(clearance 0)
		)
		(pad "20" thru_hole circle
			(at 0 48.26 270)
			(size 1.6256 1.6256)
			(drill 1.1176)
			(layers "*.Cu" "*.Mask")
			(remove_unused_layers no)
			(net "GND")
			(clearance 0)
		)
		(pad "21" thru_hole circle
			(at 0 50.8 270)
			(size 1.6256 1.6256)
			(drill 1.1176)
			(layers "*.Cu" "*.Mask")
			(remove_unused_layers no)
			(net "GND")
			(clearance 0)
		)
		(pad "22" thru_hole circle
			(at 0 53.34 270)
			(size 1.6256 1.6256)
			(drill 1.1176)
			(layers "*.Cu" "*.Mask")
			(remove_unused_layers no)
			(net "GND")
			(clearance 0)
		)
		(pad "23" thru_hole circle
			(at 0 55.88 270)
			(size 1.6256 1.6256)
			(drill 1.1176)
			(layers "*.Cu" "*.Mask")
			(remove_unused_layers no)
			(net "GND")
			(clearance 0)
		)
		(pad "24" thru_hole circle
			(at 0 58.42 270)
			(size 1.6256 1.6256)
			(drill 1.1176)
			(layers "*.Cu" "*.Mask")
			(remove_unused_layers no)
			(net "GND")
			(clearance 0)
		)
		(pad "25" thru_hole circle
			(at 0 60.96 270)
			(size 1.6256 1.6256)
			(drill 1.1176)
			(layers "*.Cu" "*.Mask")
			(remove_unused_layers no)
			(net "PHLOSS")
			(clearance 0)
		)
		(pad "26" thru_hole circle
			(at 0 63.5 270)
			(size 1.6256 1.6256)
			(drill 1.1176)
			(layers "*.Cu" "*.Mask")
			(remove_unused_layers no)
			(net "PSU6_REMOTE_N")
			(clearance 0)
		)
		(pad "27" thru_hole circle
			(at 0 66.04 270)
			(size 1.6256 1.6256)
			(drill 1.1176)
			(layers "*.Cu" "*.Mask")
			(remove_unused_layers no)
			(net "PSU6_AC_OK")
			(clearance 0)
		)
		(pad "28" thru_hole circle
			(at 0 68.58 270)
			(size 1.6256 1.6256)
			(drill 1.1176)
			(layers "*.Cu" "*.Mask")
			(remove_unused_layers no)
			(net "PSU6_CSAHRE")
			(clearance 0)
		)
		(pad "29" thru_hole circle
			(at 0 71.12 270)
			(size 1.6256 1.6256)
			(drill 1.1176)
			(layers "*.Cu" "*.Mask")
			(remove_unused_layers no)
			(net "PSU6_PS_ON_N")
			(clearance 0)
		)
		(pad "30" thru_hole circle
			(at 0 73.66 270)
			(size 1.6256 1.6256)
			(drill 1.1176)
			(layers "*.Cu" "*.Mask")
			(remove_unused_layers no)
			(net "PSU6_PS_KILL")
			(clearance 0)
		)
		(pad "31" thru_hole circle
			(at 0 76.2 270)
			(size 1.6256 1.6256)
			(drill 1.1176)
			(layers "*.Cu" "*.Mask")
			(remove_unused_layers no)
			(net "PSU6_RESET")
			(clearance 0)
		)
		(pad "32" thru_hole circle
			(at 0 78.74 270)
			(size 1.6256 1.6256)
			(drill 1.1176)
			(layers "*.Cu" "*.Mask")
			(remove_unused_layers no)
			(net "PSU_ALERT_N")
			(clearance 0)
		)
		(pad "33" thru_hole circle
			(at 5.08 78.74 270)
			(size 1.6256 1.6256)
			(drill 1.1176)
			(layers "*.Cu" "*.Mask")
			(remove_unused_layers no)
			(net "I2C_PSU3_SDA")
			(clearance 0)
		)
		(pad "34" thru_hole circle
			(at 5.08 76.2 270)
			(size 1.6256 1.6256)
			(drill 1.1176)
			(layers "*.Cu" "*.Mask")
			(remove_unused_layers no)
			(net "Net_425")
			(clearance 0)
		)
		(pad "35" thru_hole circle
			(at 5.08 73.66 270)
			(size 1.6256 1.6256)
			(drill 1.1176)
			(layers "*.Cu" "*.Mask")
			(remove_unused_layers no)
			(net "I2C_PSU3_SCL")
			(clearance 0)
		)
		(pad "36" thru_hole circle
			(at 5.08 71.12 270)
			(size 1.6256 1.6256)
			(drill 1.1176)
			(layers "*.Cu" "*.Mask")
			(remove_unused_layers no)
			(net "PSU6_RETURN")
			(clearance 0)
		)
		(pad "37" thru_hole circle
			(at 5.08 68.58 270)
			(size 1.6256 1.6256)
			(drill 1.1176)
			(layers "*.Cu" "*.Mask")
			(remove_unused_layers no)
			(net "PSU6_DC_OK")
			(clearance 0)
		)
		(pad "38" thru_hole circle
			(at 5.08 66.04 270)
			(size 1.6256 1.6256)
			(drill 1.1176)
			(layers "*.Cu" "*.Mask")
			(remove_unused_layers no)
			(net "PSU6_AD0")
			(clearance 0)
		)
		(pad "39" thru_hole circle
			(at 5.08 63.5 270)
			(size 1.6256 1.6256)
			(drill 1.1176)
			(layers "*.Cu" "*.Mask")
			(remove_unused_layers no)
			(net "P12V_STBY")
			(clearance 0)
		)
		(pad "40" thru_hole circle
			(at 5.08 60.96 270)
			(size 1.6256 1.6256)
			(drill 1.1176)
			(layers "*.Cu" "*.Mask")
			(remove_unused_layers no)
			(net "PSU6_REMOTE_P")
			(clearance 0)
		)
		(pad "41" thru_hole circle
			(at 5.08 58.42 270)
			(size 1.6256 1.6256)
			(drill 1.1176)
			(layers "*.Cu" "*.Mask")
			(remove_unused_layers no)
			(net "GND")
			(clearance 0)
		)
		(pad "42" thru_hole circle
			(at 5.08 55.88 270)
			(size 1.6256 1.6256)
			(drill 1.1176)
			(layers "*.Cu" "*.Mask")
			(remove_unused_layers no)
			(net "GND")
			(clearance 0)
		)
		(pad "43" thru_hole circle
			(at 5.08 53.34 270)
			(size 1.6256 1.6256)
			(drill 1.1176)
			(layers "*.Cu" "*.Mask")
			(remove_unused_layers no)
			(net "GND")
			(clearance 0)
		)
		(pad "44" thru_hole circle
			(at 5.08 50.8 270)
			(size 1.6256 1.6256)
			(drill 1.1176)
			(layers "*.Cu" "*.Mask")
			(remove_unused_layers no)
			(net "GND")
			(clearance 0)
		)
		(pad "45" thru_hole circle
			(at 5.08 48.26 270)
			(size 1.6256 1.6256)
			(drill 1.1176)
			(layers "*.Cu" "*.Mask")
			(remove_unused_layers no)
			(net "GND")
			(clearance 0)
		)
		(pad "46" thru_hole circle
			(at 5.08 45.72 270)
			(size 1.6256 1.6256)
			(drill 1.1176)
			(layers "*.Cu" "*.Mask")
			(remove_unused_layers no)
			(net "GND")
			(clearance 0)
		)
		(pad "47" thru_hole circle
			(at 5.08 43.18 270)
			(size 1.6256 1.6256)
			(drill 1.1176)
			(layers "*.Cu" "*.Mask")
			(remove_unused_layers no)
			(net "GND")
			(clearance 0)
		)
		(pad "48" thru_hole circle
			(at 5.08 40.64 270)
			(size 1.6256 1.6256)
			(drill 1.1176)
			(layers "*.Cu" "*.Mask")
			(remove_unused_layers no)
			(net "GND")
			(clearance 0)
		)
		(pad "49" thru_hole circle
			(at 5.08 38.1 270)
			(size 1.6256 1.6256)
			(drill 1.1176)
			(layers "*.Cu" "*.Mask")
			(remove_unused_layers no)
			(net "GND")
			(clearance 0)
		)
		(pad "50" thru_hole circle
			(at 5.08 35.56 270)
			(size 1.6256 1.6256)
			(drill 1.1176)
			(layers "*.Cu" "*.Mask")
			(remove_unused_layers no)
			(net "GND")
			(clearance 0)
		)
		(pad "51" thru_hole circle
			(at 5.08 33.02 270)
			(size 1.6256 1.6256)
			(drill 1.1176)
			(layers "*.Cu" "*.Mask")
			(remove_unused_layers no)
			(net "GND")
			(clearance 0)
		)
		(pad "52" thru_hole circle
			(at 5.08 30.48 270)
			(size 1.6256 1.6256)
			(drill 1.1176)
			(layers "*.Cu" "*.Mask")
			(remove_unused_layers no)
			(net "GND")
			(clearance 0)
		)
		(pad "53" thru_hole circle
			(at 5.08 27.94 270)
			(size 1.6256 1.6256)
			(drill 1.1176)
			(layers "*.Cu" "*.Mask")
			(remove_unused_layers no)
			(net "P12V")
			(clearance 0)
		)
		(pad "54" thru_hole circle
			(at 5.08 25.4 270)
			(size 1.6256 1.6256)
			(drill 1.1176)
			(layers "*.Cu" "*.Mask")
			(remove_unused_layers no)
			(net "P12V")
			(clearance 0)
		)
		(pad "55" thru_hole circle
			(at 5.08 22.86 270)
			(size 1.6256 1.6256)
			(drill 1.1176)
			(layers "*.Cu" "*.Mask")
			(remove_unused_layers no)
			(net "P12V")
			(clearance 0)
		)
		(pad "56" thru_hole circle
			(at 5.08 20.32 270)
			(size 1.6256 1.6256)
			(drill 1.1176)
			(layers "*.Cu" "*.Mask")
			(remove_unused_layers no)
			(net "P12V")
			(clearance 0)
		)
		(pad "57" thru_hole circle
			(at 5.08 17.78 270)
			(size 1.6256 1.6256)
			(drill 1.1176)
			(layers "*.Cu" "*.Mask")
			(remove_unused_layers no)
			(net "P12V")
			(clearance 0)
		)
		(pad "58" thru_hole circle
			(at 5.08 15.24 270)
			(size 1.6256 1.6256)
			(drill 1.1176)
			(layers "*.Cu" "*.Mask")
			(remove_unused_layers no)
			(net "P12V")
			(clearance 0)
		)
		(pad "59" thru_hole circle
			(at 5.08 12.7 270)
			(size 1.6256 1.6256)
			(drill 1.1176)
			(layers "*.Cu" "*.Mask")
			(remove_unused_layers no)
			(net "P12V")
			(clearance 0)
		)
		(pad "60" thru_hole circle
			(at 5.08 10.16 270)
			(size 1.6256 1.6256)
			(drill 1.1176)
			(layers "*.Cu" "*.Mask")
			(remove_unused_layers no)
			(net "P12V")
			(clearance 0)
		)
		(pad "61" thru_hole circle
			(at 5.08 7.62 270)
			(size 1.6256 1.6256)
			(drill 1.1176)
			(layers "*.Cu" "*.Mask")
			(remove_unused_layers no)
			(net "P12V")
			(clearance 0)
		)
		(pad "62" thru_hole circle
			(at 5.08 5.08 270)
			(size 1.6256 1.6256)
			(drill 1.1176)
			(layers "*.Cu" "*.Mask")
			(remove_unused_layers no)
			(net "P12V")
			(clearance 0)
		)
		(pad "63" thru_hole circle
			(at 5.08 2.54 270)
			(size 1.6256 1.6256)
			(drill 1.1176)
			(layers "*.Cu" "*.Mask")
			(remove_unused_layers no)
			(net "P12V")
			(clearance 0)
		)
		(pad "64" thru_hole circle
			(at 5.08 0 270)
			(size 1.6256 1.6256)
			(drill 1.1176)
			(layers "*.Cu" "*.Mask")
			(remove_unused_layers no)
			(net "P12V")
			(clearance 0)
		)
	)
	(footprint ""
		(layer "F.Cu")
		(at 25.857708 -360.550968)
		(property "Reference" "R59"
			(at -3.917442 -0.225298 0)
			(unlocked yes)
			(layer "F.SilkS")
			(effects
				(font
					(size 0.7874 0.5842)
					(thickness 0.1524)
				)
				(justify left)
			)
		)
		(property "Value" ""
			(at 0 0 0)
			(layer "F.Fab")
			(effects
				(font
					(size 1.27 1.27)
				)
			)
		)
		(duplicate_pad_numbers_are_jumpers no)
		(fp_line
			(start -0.7874 -0.4064)
			(end 0.7874 -0.4064)
			(stroke
				(width 0.1524)
				(type default)
			)
			(layer "F.SilkS")
		)
		(fp_line
			(start -0.7874 0.4064)
			(end -0.7874 -0.4064)
			(stroke
				(width 0.1524)
				(type default)
			)
			(layer "F.SilkS")
		)
		(fp_line
			(start 0.7874 -0.4064)
			(end 0.7874 0.4064)
			(stroke
				(width 0.1524)
				(type default)
			)
			(layer "F.SilkS")
		)
		(fp_line
			(start 0.7874 0.4064)
			(end -0.7874 0.4064)
			(stroke
				(width 0.1524)
				(type default)
			)
			(layer "F.SilkS")
		)
		(fp_poly
			(pts
				(xy -0.508 0.2794) (xy -0.508 0.2286) (xy -0.635 0.2286) (xy -0.635 -0.254) (xy -0.5334 -0.254)
				(xy -0.5334 -0.2794) (xy 0.5334 -0.2794) (xy 0.5334 -0.254) (xy 0.635 -0.254) (xy 0.635 0.254) (xy 0.5334 0.254)
				(xy 0.5334 0.2794)
			)
			(stroke
				(width 0)
				(type default)
			)
			(fill no)
			(layer "F.CrtYd")
		)
		(pad "1" smd rect
			(at 0.40005 0)
			(size 0.4572 0.508)
			(layers "F.Cu" "F.Mask" "F.Paste")
			(net "PSU5_RESET")
		)
		(pad "2" smd rect
			(at -0.40005 0)
			(size 0.4572 0.508)
			(layers "F.Cu" "F.Mask" "F.Paste")
			(net "GND")
		)
	)
	(footprint ""
		(layer "F.Cu")
		(at 39.90086 -194.114674 180)
		(property "Reference" "R13"
			(at -1.710182 -0.085344 0)
			(unlocked yes)
			(layer "F.SilkS")
			(effects
				(font
					(size 0.7874 0.5842)
					(thickness 0.1524)
				)
				(justify left)
			)
		)
		(property "Value" ""
			(at 0 0 180)
			(layer "F.Fab")
			(effects
				(font
					(size 1.27 1.27)
				)
			)
		)
		(duplicate_pad_numbers_are_jumpers no)
		(fp_line
			(start 0.7874 0.4064)
			(end -0.7874 0.4064)
			(stroke
				(width 0.1524)
				(type default)
			)
			(layer "F.SilkS")
		)
		(fp_line
			(start 0.7874 -0.4064)
			(end 0.7874 0.4064)
			(stroke
				(width 0.1524)
				(type default)
			)
			(layer "F.SilkS")
		)
		(fp_line
			(start -0.7874 0.4064)
			(end -0.7874 -0.4064)
			(stroke
				(width 0.1524)
				(type default)
			)
			(layer "F.SilkS")
		)
		(fp_line
			(start -0.7874 -0.4064)
			(end 0.7874 -0.4064)
			(stroke
				(width 0.1524)
				(type default)
			)
			(layer "F.SilkS")
		)
		(fp_poly
			(pts
				(xy -0.508 0.2794) (xy -0.508 0.2286) (xy -0.635 0.2286) (xy -0.635 -0.254) (xy -0.5334 -0.254)
				(xy -0.5334 -0.2794) (xy 0.5334 -0.2794) (xy 0.5334 -0.254) (xy 0.635 -0.254) (xy 0.635 0.254) (xy 0.5334 0.254)
				(xy 0.5334 0.2794)
			)
			(stroke
				(width 0)
				(type default)
			)
			(fill no)
			(layer "F.CrtYd")
		)
		(pad "1" smd rect
			(at 0.40005 0 180)
			(size 0.4572 0.508)
			(layers "F.Cu" "F.Mask" "F.Paste")
			(net "PSU3_AD0")
		)
		(pad "2" smd rect
			(at -0.40005 0 180)
			(size 0.4572 0.508)
			(layers "F.Cu" "F.Mask" "F.Paste")
			(net "GND")
		)
	)
	(footprint ""
		(layer "F.Cu")
		(at 13.386308 -319.438782 180)
		(property "Reference" "R141"
			(at -1.77546 -0.128016 0)
			(unlocked yes)
			(layer "F.SilkS")
			(effects
				(font
					(size 0.7874 0.5842)
					(thickness 0.1524)
				)
				(justify left)
			)
		)
		(property "Value" ""
			(at 0 0 180)
			(layer "F.Fab")
			(effects
				(font
					(size 1.27 1.27)
				)
			)
		)
		(duplicate_pad_numbers_are_jumpers no)
		(fp_line
			(start 0.7874 0.4064)
			(end -0.7874 0.4064)
			(stroke
				(width 0.1524)
				(type default)
			)
			(layer "F.SilkS")
		)
		(fp_line
			(start 0.7874 -0.4064)
			(end 0.7874 0.4064)
			(stroke
				(width 0.1524)
				(type default)
			)
			(layer "F.SilkS")
		)
		(fp_line
			(start -0.7874 0.4064)
			(end -0.7874 -0.4064)
			(stroke
				(width 0.1524)
				(type default)
			)
			(layer "F.SilkS")
		)
		(fp_line
			(start -0.7874 -0.4064)
			(end 0.7874 -0.4064)
			(stroke
				(width 0.1524)
				(type default)
			)
			(layer "F.SilkS")
		)
		(fp_poly
			(pts
				(xy -0.508 0.2794) (xy -0.508 0.2286) (xy -0.635 0.2286) (xy -0.635 -0.254) (xy -0.5334 -0.254)
				(xy -0.5334 -0.2794) (xy 0.5334 -0.2794) (xy 0.5334 -0.254) (xy 0.635 -0.254) (xy 0.635 0.254) (xy 0.5334 0.254)
				(xy 0.5334 0.2794)
			)
			(stroke
				(width 0)
				(type default)
			)
			(fill no)
			(layer "F.CrtYd")
		)
		(pad "1" smd rect
			(at 0.40005 0 180)
			(size 0.4572 0.508)
			(layers "F.Cu" "F.Mask" "F.Paste")
			(net "FAN_PWM")
		)
		(pad "2" smd rect
			(at -0.40005 0 180)
			(size 0.4572 0.508)
			(layers "F.Cu" "F.Mask" "F.Paste")
			(net "P12V")
		)
	)
	(footprint ""
		(layer "F.Cu")
		(at 27.347672 -107.830366 90)
		(property "Reference" "R117"
			(at -3.30327 -1.060196 90)
			(unlocked yes)
			(layer "F.SilkS")
			(effects
				(font
					(size 0.7874 0.5842)
					(thickness 0.1524)
				)
				(justify left)
			)
		)
		(property "Value" ""
			(at 0 0 90)
			(layer "F.Fab")
			(effects
				(font
					(size 1.27 1.27)
				)
			)
		)
		(duplicate_pad_numbers_are_jumpers no)
		(fp_line
			(start 0.7874 -0.4064)
			(end 0.7874 0.4064)
			(stroke
				(width 0.1524)
				(type default)
			)
			(layer "F.SilkS")
		)
		(fp_line
			(start -0.7874 -0.4064)
			(end 0.7874 -0.4064)
			(stroke
				(width 0.1524)
				(type default)
			)
			(layer "F.SilkS")
		)
		(fp_line
			(start 0.7874 0.4064)
			(end -0.7874 0.4064)
			(stroke
				(width 0.1524)
				(type default)
			)
			(layer "F.SilkS")
		)
		(fp_line
			(start -0.7874 0.4064)
			(end -0.7874 -0.4064)
			(stroke
				(width 0.1524)
				(type default)
			)
			(layer "F.SilkS")
		)
		(fp_poly
			(pts
				(xy -0.508 0.2794) (xy -0.508 0.2286) (xy -0.635 0.2286) (xy -0.635 -0.254) (xy -0.5334 -0.254)
				(xy -0.5334 -0.2794) (xy 0.5334 -0.2794) (xy 0.5334 -0.254) (xy 0.635 -0.254) (xy 0.635 0.254) (xy 0.5334 0.254)
				(xy 0.5334 0.2794)
			)
			(stroke
				(width 0)
				(type default)
			)
			(fill no)
			(layer "F.CrtYd")
		)
		(pad "1" smd rect
			(at 0.40005 0 90)
			(size 0.4572 0.508)
			(layers "F.Cu" "F.Mask" "F.Paste")
			(net "PSU2_REMOTE_N")
		)
		(pad "2" smd rect
			(at -0.40005 0 90)
			(size 0.4572 0.508)
			(layers "F.Cu" "F.Mask" "F.Paste")
			(net "PSU2_REMOTE_R2_N")
		)
	)
	(footprint ""
		(layer "F.Cu")
		(at 69.370956 -197.900544 -90)
		(property "Reference" "C29"
			(at 3.031998 -0.19685 90)
			(unlocked yes)
			(layer "F.SilkS")
			(effects
				(font
					(size 0.7874 0.5842)
					(thickness 0.1524)
				)
			)
		)
		(property "Value" ""
			(at 0 0 270)
			(layer "F.Fab")
			(effects
				(font
					(size 1.27 1.27)
				)
			)
		)
		(duplicate_pad_numbers_are_jumpers no)
		(fp_line
			(start -1.2954 0.5842)
			(end -1.2954 -0.5842)
			(stroke
				(width 0.1524)
				(type default)
			)
			(layer "F.SilkS")
		)
		(fp_line
			(start 1.2954 0.5842)
			(end -1.2954 0.5842)
			(stroke
				(width 0.1524)
				(type default)
			)
			(layer "F.SilkS")
		)
		(fp_line
			(start -1.2954 -0.5842)
			(end 1.2954 -0.5842)
			(stroke
				(width 0.1524)
				(type default)
			)
			(layer "F.SilkS")
		)
		(fp_line
			(start 0 -0.5842)
			(end 0 0.5842)
			(stroke
				(width 0.1524)
				(type default)
			)
			(layer "F.SilkS")
		)
		(fp_line
			(start 1.2954 -0.5842)
			(end 1.2954 0.5842)
			(stroke
				(width 0.1524)
				(type default)
			)
			(layer "F.SilkS")
		)
		(fp_poly
			(pts
				(xy 0.8636 -0.4572) (xy 0.8636 -0.3556) (xy 1.143 -0.3556) (xy 1.143 0.3556) (xy 0.8636 0.3556)
				(xy 0.8636 0.4572) (xy -0.8636 0.4572) (xy -0.8636 0.3556) (xy -1.143 0.3556) (xy -1.143 -0.3556)
				(xy -0.8636 -0.3556) (xy -0.8636 -0.4572)
			)
			(stroke
				(width 0)
				(type default)
			)
			(fill no)
			(layer "F.CrtYd")
		)
		(fp_line
			(start -0.884936 0.504952)
			(end -0.884936 -0.504952)
			(stroke
				(width 0.1)
				(type default)
			)
			(layer "F.Fab")
		)
		(fp_line
			(start 0.884936 0.504952)
			(end -0.884936 0.504952)
			(stroke
				(width 0.1)
				(type default)
			)
			(layer "F.Fab")
		)
		(fp_line
			(start -0.884936 -0.504952)
			(end 0.884936 -0.504952)
			(stroke
				(width 0.1)
				(type default)
			)
			(layer "F.Fab")
		)
		(fp_line
			(start 0.884936 -0.504952)
			(end 0.884936 0.504952)
			(stroke
				(width 0.1)
				(type default)
			)
			(layer "F.Fab")
		)
		(pad "1" smd rect
			(at 0.7366 0)
			(size 0.7112 0.8128)
			(layers "F.Cu" "F.Mask" "F.Paste")
			(net "P12V")
		)
		(pad "2" smd rect
			(at -0.7366 0)
			(size 0.7112 0.8128)
			(layers "F.Cu" "F.Mask" "F.Paste")
			(net "GND")
		)
	)
	(footprint ""
		(layer "F.Cu")
		(at 46.40834 -243.096034 180)
		(property "Reference" "R92"
			(at 4.252722 -0.212598 0)
			(unlocked yes)
			(layer "F.SilkS")
			(effects
				(font
					(size 0.7874 0.5842)
					(thickness 0.1524)
				)
				(justify left)
			)
		)
		(property "Value" ""
			(at 0 0 180)
			(layer "F.Fab")
			(effects
				(font
					(size 1.27 1.27)
				)
			)
		)
		(duplicate_pad_numbers_are_jumpers no)
		(fp_line
			(start 0.7874 0.4064)
			(end -0.7874 0.4064)
			(stroke
				(width 0.1524)
				(type default)
			)
			(layer "F.SilkS")
		)
		(fp_line
			(start 0.7874 -0.4064)
			(end 0.7874 0.4064)
			(stroke
				(width 0.1524)
				(type default)
			)
			(layer "F.SilkS")
		)
		(fp_line
			(start -0.7874 0.4064)
			(end -0.7874 -0.4064)
			(stroke
				(width 0.1524)
				(type default)
			)
			(layer "F.SilkS")
		)
		(fp_line
			(start -0.7874 -0.4064)
			(end 0.7874 -0.4064)
			(stroke
				(width 0.1524)
				(type default)
			)
			(layer "F.SilkS")
		)
		(fp_poly
			(pts
				(xy -0.508 0.2794) (xy -0.508 0.2286) (xy -0.635 0.2286) (xy -0.635 -0.254) (xy -0.5334 -0.254)
				(xy -0.5334 -0.2794) (xy 0.5334 -0.2794) (xy 0.5334 -0.254) (xy 0.635 -0.254) (xy 0.635 0.254) (xy 0.5334 0.254)
				(xy 0.5334 0.2794)
			)
			(stroke
				(width 0)
				(type default)
			)
			(fill no)
			(layer "F.CrtYd")
		)
		(pad "1" smd rect
			(at 0.40005 0 180)
			(size 0.4572 0.508)
			(layers "F.Cu" "F.Mask" "F.Paste")
			(net "PSU2_REMOTE_R_P")
		)
		(pad "2" smd rect
			(at -0.40005 0 180)
			(size 0.4572 0.508)
			(layers "F.Cu" "F.Mask" "F.Paste")
			(net "P12V")
		)
	)
	(footprint ""
		(layer "F.Cu")
		(at 26.18613 -190.368174)
		(property "Reference" "R136"
			(at -4.256532 0.268224 0)
			(unlocked yes)
			(layer "F.SilkS")
			(effects
				(font
					(size 0.7874 0.5842)
					(thickness 0.1524)
				)
				(justify left)
			)
		)
		(property "Value" ""
			(at 0 0 0)
			(layer "F.Fab")
			(effects
				(font
					(size 1.27 1.27)
				)
			)
		)
		(duplicate_pad_numbers_are_jumpers no)
		(fp_line
			(start -0.7874 -0.4064)
			(end 0.7874 -0.4064)
			(stroke
				(width 0.1524)
				(type default)
			)
			(layer "F.SilkS")
		)
		(fp_line
			(start -0.7874 0.4064)
			(end -0.7874 -0.4064)
			(stroke
				(width 0.1524)
				(type default)
			)
			(layer "F.SilkS")
		)
		(fp_line
			(start 0.7874 -0.4064)
			(end 0.7874 0.4064)
			(stroke
				(width 0.1524)
				(type default)
			)
			(layer "F.SilkS")
		)
		(fp_line
			(start 0.7874 0.4064)
			(end -0.7874 0.4064)
			(stroke
				(width 0.1524)
				(type default)
			)
			(layer "F.SilkS")
		)
		(fp_poly
			(pts
				(xy -0.508 0.2794) (xy -0.508 0.2286) (xy -0.635 0.2286) (xy -0.635 -0.254) (xy -0.5334 -0.254)
				(xy -0.5334 -0.2794) (xy 0.5334 -0.2794) (xy 0.5334 -0.254) (xy 0.635 -0.254) (xy 0.635 0.254) (xy 0.5334 0.254)
				(xy 0.5334 0.2794)
			)
			(stroke
				(width 0)
				(type default)
			)
			(fill no)
			(layer "F.CrtYd")
		)
		(pad "1" smd rect
			(at 0.40005 0)
			(size 0.4572 0.508)
			(layers "F.Cu" "F.Mask" "F.Paste")
			(net "PSU3_CSAHRE")
		)
		(pad "2" smd rect
			(at -0.40005 0)
			(size 0.4572 0.508)
			(layers "F.Cu" "F.Mask" "F.Paste")
			(net "PSU_CSAHRE")
		)
	)
	(footprint ""
		(layer "F.Cu")
		(at 70.658736 -197.392544 -90)
		(property "Reference" "C30"
			(at 3.603498 -0.19812 90)
			(unlocked yes)
			(layer "F.SilkS")
			(effects
				(font
					(size 0.7874 0.5842)
					(thickness 0.1524)
				)
				(justify left)
			)
		)
		(property "Value" ""
			(at 0 0 270)
			(layer "F.Fab")
			(effects
				(font
					(size 1.27 1.27)
				)
			)
		)
		(duplicate_pad_numbers_are_jumpers no)
		(fp_line
			(start -0.7874 0.4064)
			(end -0.7874 -0.4064)
			(stroke
				(width 0.1524)
				(type default)
			)
			(layer "F.SilkS")
		)
		(fp_line
			(start 0.7874 0.4064)
			(end -0.7874 0.4064)
			(stroke
				(width 0.1524)
				(type default)
			)
			(layer "F.SilkS")
		)
		(fp_line
			(start 0 0.381)
			(end 0 -0.381)
			(stroke
				(width 0.1524)
				(type default)
			)
			(layer "F.SilkS")
		)
		(fp_line
			(start -0.7874 -0.4064)
			(end 0.7874 -0.4064)
			(stroke
				(width 0.1524)
				(type default)
			)
			(layer "F.SilkS")
		)
		(fp_line
			(start 0.7874 -0.4064)
			(end 0.7874 0.4064)
			(stroke
				(width 0.1524)
				(type default)
			)
			(layer "F.SilkS")
		)
		(fp_poly
			(pts
				(xy -0.5334 0.254) (xy -0.635 0.254) (xy -0.635 0.2286) (xy -0.635 -0.254) (xy -0.5334 -0.254) (xy -0.5334 -0.2794)
				(xy 0.5334 -0.2794) (xy 0.5334 -0.254) (xy 0.635 -0.254) (xy 0.635 0.254) (xy 0.5334 0.254) (xy 0.5334 0.2794)
				(xy -0.508 0.2794) (xy -0.5334 0.2794)
			)
			(stroke
				(width 0)
				(type default)
			)
			(fill no)
			(layer "F.CrtYd")
		)
		(pad "1" smd rect
			(at 0.40005 0 270)
			(size 0.4572 0.508)
			(layers "F.Cu" "F.Mask" "F.Paste")
			(net "P12V")
		)
		(pad "2" smd rect
			(at -0.40005 0 270)
			(size 0.4572 0.508)
			(layers "F.Cu" "F.Mask" "F.Paste")
			(net "GND")
		)
	)
	(footprint ""
		(layer "F.Cu")
		(at 67.867276 -304.009806 90)
		(property "Reference" "C55"
			(at 1.053846 0.04826 90)
			(unlocked yes)
			(layer "F.SilkS")
			(effects
				(font
					(size 0.7874 0.5842)
					(thickness 0.1524)
				)
				(justify left)
			)
		)
		(property "Value" ""
			(at 0 0 90)
			(layer "F.Fab")
			(effects
				(font
					(size 1.27 1.27)
				)
			)
		)
		(duplicate_pad_numbers_are_jumpers no)
		(fp_line
			(start 0.7874 -0.4064)
			(end 0.7874 0.4064)
			(stroke
				(width 0.1524)
				(type default)
			)
			(layer "F.SilkS")
		)
		(fp_line
			(start -0.7874 -0.4064)
			(end 0.7874 -0.4064)
			(stroke
				(width 0.1524)
				(type default)
			)
			(layer "F.SilkS")
		)
		(fp_line
			(start 0 0.381)
			(end 0 -0.381)
			(stroke
				(width 0.1524)
				(type default)
			)
			(layer "F.SilkS")
		)
		(fp_line
			(start 0.7874 0.4064)
			(end -0.7874 0.4064)
			(stroke
				(width 0.1524)
				(type default)
			)
			(layer "F.SilkS")
		)
		(fp_line
			(start -0.7874 0.4064)
			(end -0.7874 -0.4064)
			(stroke
				(width 0.1524)
				(type default)
			)
			(layer "F.SilkS")
		)
		(fp_poly
			(pts
				(xy -0.5334 0.254) (xy -0.635 0.254) (xy -0.635 0.2286) (xy -0.635 -0.254) (xy -0.5334 -0.254) (xy -0.5334 -0.2794)
				(xy 0.5334 -0.2794) (xy 0.5334 -0.254) (xy 0.635 -0.254) (xy 0.635 0.254) (xy 0.5334 0.254) (xy 0.5334 0.2794)
				(xy -0.508 0.2794) (xy -0.5334 0.2794)
			)
			(stroke
				(width 0)
				(type default)
			)
			(fill no)
			(layer "F.CrtYd")
		)
		(pad "1" smd rect
			(at 0.40005 0 90)
			(size 0.4572 0.508)
			(layers "F.Cu" "F.Mask" "F.Paste")
			(net "P12V")
		)
		(pad "2" smd rect
			(at -0.40005 0 90)
			(size 0.4572 0.508)
			(layers "F.Cu" "F.Mask" "F.Paste")
			(net "GND")
		)
	)
	(footprint ""
		(layer "F.Cu")
		(at 98.702114 -15.774924)
		(property "Reference" ""
			(at 0 0 0)
			(layer "F.SilkS")
			(hide yes)
			(effects
				(font
					(size 1.27 1.27)
				)
			)
		)
		(property "Value" ""
			(at 0 0 0)
			(layer "F.Fab")
			(effects
				(font
					(size 1.27 1.27)
				)
			)
		)
		(duplicate_pad_numbers_are_jumpers no)
		(fp_poly
			(pts
				(arc
					(start 1.4986 0)
					(mid -1.4986 0)
					(end 1.4986 0)
				)
			)
			(stroke
				(width 0)
				(type default)
			)
			(fill no)
			(layer "F.CrtYd")
		)
		(pad "1" smd circle
			(at 0 0)
			(size 0.9906 0.9906)
			(layers "F.Cu" "F.Mask" "F.Paste")
			(net "Net_223")
		)
		(zone
			(layer "F.Cu")
			(hatch none 0.5)
			(connect_pads
				(clearance 0)
			)
			(min_thickness 0.25)
			(keepout
				(tracks not_allowed)
				(vias allowed)
				(pads allowed)
				(copperpour not_allowed)
				(footprints allowed)
			)
			(placement
				(enabled no)
				(sheetname "")
			)
			(fill
				(thermal_gap 0.5)
				(thermal_bridge_width 0.5)
				(island_removal_mode 0)
			)
			(polygon
				(pts
					(arc
						(start 100.327714 -15.774924)
						(mid 97.076514 -15.774924)
						(end 100.327714 -15.774924)
					)
				)
			)
		)
	)
	(footprint ""
		(layer "F.Cu")
		(at 69.44487 -127.633476 90)
		(property "Reference" "C26"
			(at 1.175512 -0.0254 90)
			(unlocked yes)
			(layer "F.SilkS")
			(effects
				(font
					(size 0.7874 0.5842)
					(thickness 0.1524)
				)
				(justify left)
			)
		)
		(property "Value" ""
			(at 0 0 90)
			(layer "F.Fab")
			(effects
				(font
					(size 1.27 1.27)
				)
			)
		)
		(duplicate_pad_numbers_are_jumpers no)
		(fp_line
			(start 0.7874 -0.4064)
			(end 0.7874 0.4064)
			(stroke
				(width 0.1524)
				(type default)
			)
			(layer "F.SilkS")
		)
		(fp_line
			(start -0.7874 -0.4064)
			(end 0.7874 -0.4064)
			(stroke
				(width 0.1524)
				(type default)
			)
			(layer "F.SilkS")
		)
		(fp_line
			(start 0 0.381)
			(end 0 -0.381)
			(stroke
				(width 0.1524)
				(type default)
			)
			(layer "F.SilkS")
		)
		(fp_line
			(start 0.7874 0.4064)
			(end -0.7874 0.4064)
			(stroke
				(width 0.1524)
				(type default)
			)
			(layer "F.SilkS")
		)
		(fp_line
			(start -0.7874 0.4064)
			(end -0.7874 -0.4064)
			(stroke
				(width 0.1524)
				(type default)
			)
			(layer "F.SilkS")
		)
		(fp_poly
			(pts
				(xy -0.5334 0.254) (xy -0.635 0.254) (xy -0.635 0.2286) (xy -0.635 -0.254) (xy -0.5334 -0.254) (xy -0.5334 -0.2794)
				(xy 0.5334 -0.2794) (xy 0.5334 -0.254) (xy 0.635 -0.254) (xy 0.635 0.254) (xy 0.5334 0.254) (xy 0.5334 0.2794)
				(xy -0.508 0.2794) (xy -0.5334 0.2794)
			)
			(stroke
				(width 0)
				(type default)
			)
			(fill no)
			(layer "F.CrtYd")
		)
		(pad "1" smd rect
			(at 0.40005 0 90)
			(size 0.4572 0.508)
			(layers "F.Cu" "F.Mask" "F.Paste")
			(net "P12V")
		)
		(pad "2" smd rect
			(at -0.40005 0 90)
			(size 0.4572 0.508)
			(layers "F.Cu" "F.Mask" "F.Paste")
			(net "GND")
		)
	)
	(footprint ""
		(layer "F.Cu")
		(at 5.780024 -31.909766)
		(property "Reference" "J33"
			(at -1.9304 -3.978148 0)
			(unlocked yes)
			(layer "F.SilkS")
			(effects
				(font
					(size 0.7874 0.5842)
					(thickness 0.1524)
				)
				(justify left)
			)
		)
		(property "Value" ""
			(at 0 0 0)
			(layer "F.Fab")
			(effects
				(font
					(size 1.27 1.27)
				)
			)
		)
		(duplicate_pad_numbers_are_jumpers no)
		(fp_line
			(start -3.10007 0.199898)
			(end -3.10007 2.800096)
			(stroke
				(width 0.1524)
				(type default)
			)
			(layer "F.SilkS")
		)
		(fp_line
			(start -3.10007 2.800096)
			(end -1.89992 2.800096)
			(stroke
				(width 0.1524)
				(type default)
			)
			(layer "F.SilkS")
		)
		(fp_line
			(start -1.89992 -3.325114)
			(end -1.89992 0.199898)
			(stroke
				(width 0.1524)
				(type default)
			)
			(layer "F.SilkS")
		)
		(fp_line
			(start -1.89992 0.199898)
			(end -3.10007 0.199898)
			(stroke
				(width 0.1524)
				(type default)
			)
			(layer "F.SilkS")
		)
		(fp_line
			(start -1.89992 2.800096)
			(end -1.89992 6.325108)
			(stroke
				(width 0.1524)
				(type default)
			)
			(layer "F.SilkS")
		)
		(fp_line
			(start -1.89992 6.325108)
			(end 1.016 6.325108)
			(stroke
				(width 0.1524)
				(type default)
			)
			(layer "F.SilkS")
		)
		(fp_line
			(start 1.016 -3.325114)
			(end -1.89992 -3.325114)
			(stroke
				(width 0.1524)
				(type default)
			)
			(layer "F.SilkS")
		)
		(fp_line
			(start 2.469896 5.133594)
			(end 2.469896 -2.130806)
			(stroke
				(width 0.1524)
				(type default)
			)
			(layer "F.SilkS")
		)
		(fp_poly
			(pts
				(xy 0.8509 0.8509) (xy -0.8509 0.8509) (xy -0.8509 -0.8509) (xy 0.8509 -0.8509)
			)
			(stroke
				(width 0)
				(type default)
			)
			(fill no)
			(layer "B.CrtYd")
		)
		(fp_poly
			(pts
				(arc
					(start 0.8509 2.999994)
					(mid -0.8509 2.999994)
					(end 0.8509 2.999994)
				)
			)
			(stroke
				(width 0)
				(type default)
			)
			(fill no)
			(layer "B.CrtYd")
		)
		(fp_poly
			(pts
				(arc
					(start 2.874518 -2.999994)
					(mid 1.045718 -2.999994)
					(end 2.874518 -2.999994)
				)
			)
			(stroke
				(width 0)
				(type default)
			)
			(fill no)
			(layer "B.CrtYd")
		)
		(fp_poly
			(pts
				(arc
					(start 2.874518 5.999988)
					(mid 1.045718 5.999988)
					(end 2.874518 5.999988)
				)
			)
			(stroke
				(width 0)
				(type default)
			)
			(fill no)
			(layer "B.CrtYd")
		)
		(fp_poly
			(pts
				(xy 2.469896 5.233924) (xy 2.469896 -2.233676) (xy 2.8956 -2.233676) (xy 2.8956 -3.935476) (xy 1.0922 -3.935476)
				(xy 1.0922 -3.325114) (xy -1.89992 -3.325114) (xy -1.89992 0.199898) (xy -3.10007 0.199898) (xy -3.10007 2.800096)
				(xy -1.89992 2.800096) (xy -1.89992 6.325108) (xy 1.0922 6.325108) (xy 1.0922 6.935724) (xy 2.8956 6.935724)
				(xy 2.8956 5.233924)
			)
			(stroke
				(width 0)
				(type default)
			)
			(fill no)
			(layer "F.CrtYd")
		)
		(fp_line
			(start -3.10007 0.199898)
			(end -3.10007 2.800096)
			(stroke
				(width 0.1)
				(type default)
			)
			(layer "F.Fab")
		)
		(fp_line
			(start -3.10007 2.800096)
			(end -1.89992 2.800096)
			(stroke
				(width 0.1)
				(type default)
			)
			(layer "F.Fab")
		)
		(fp_line
			(start -1.89992 -3.325114)
			(end -1.89992 0.199898)
			(stroke
				(width 0.1)
				(type default)
			)
			(layer "F.Fab")
		)
		(fp_line
			(start -1.89992 0.199898)
			(end -3.10007 0.199898)
			(stroke
				(width 0.1)
				(type default)
			)
			(layer "F.Fab")
		)
		(fp_line
			(start -1.89992 2.800096)
			(end -1.89992 6.325108)
			(stroke
				(width 0.1)
				(type default)
			)
			(layer "F.Fab")
		)
		(fp_line
			(start -1.89992 6.325108)
			(end 2.469896 6.325108)
			(stroke
				(width 0.1)
				(type default)
			)
			(layer "F.Fab")
		)
		(fp_line
			(start 2.469896 -3.325114)
			(end -1.89992 -3.325114)
			(stroke
				(width 0.1)
				(type default)
			)
			(layer "F.Fab")
		)
		(fp_line
			(start 2.469896 6.325108)
			(end 2.469896 -3.325114)
			(stroke
				(width 0.1)
				(type default)
			)
			(layer "F.Fab")
		)
		(pad "" np_thru_hole circle
			(at 1.960118 -2.999994 90)
			(size 1.3208 1.3208)
			(drill 1.3208)
			(layers "*.Cu" "*.Mask")
			(clearance 0.381)
			(thermal_gap 0.381)
		)
		(pad "" np_thru_hole circle
			(at 1.960118 5.999988 90)
			(size 1.3208 1.3208)
			(drill 1.3208)
			(layers "*.Cu" "*.Mask")
			(clearance 0.381)
			(thermal_gap 0.381)
		)
		(pad "1" thru_hole rect
			(at 0 0 90)
			(size 1.6002 1.6002)
			(drill 1.0922)
			(layers "*.Cu" "*.Mask")
			(remove_unused_layers no)
			(net "CM_PWR_CTL_IN")
			(clearance 0)
			(padstack
				(mode front_inner_back)
				(layer "Inner"
					(shape circle)
					(size 1.6002 1.6002)
					(clearance 0)
				)
				(layer "B.Cu"
					(shape rect)
					(size 1.6002 1.6002)
					(clearance 0)
				)
			)
		)
		(pad "2" thru_hole circle
			(at 0 2.999994 90)
			(size 1.6002 1.6002)
			(drill 1.0922)
			(layers "*.Cu" "*.Mask")
			(remove_unused_layers no)
			(net "GND")
			(clearance 0)
		)
		(zone
			(layers "F.Cu" "B.Cu" "In1.Cu" "In2.Cu" "In3.Cu" "In4.Cu" "In5.Cu" "In6.Cu")
			(hatch none 0.5)
			(connect_pads
				(clearance 0)
			)
			(min_thickness 0.25)
			(keepout
				(tracks not_allowed)
				(vias allowed)
				(pads allowed)
				(copperpour not_allowed)
				(footprints allowed)
			)
			(placement
				(enabled no)
				(sheetname "")
			)
			(fill
				(thermal_gap 0.5)
				(thermal_bridge_width 0.5)
				(island_removal_mode 0)
			)
			(polygon
				(pts
					(arc
						(start 8.806942 -34.90976)
						(mid 6.673342 -34.90976)
						(end 8.806942 -34.90976)
					)
				)
			)
		)
		(zone
			(layers "F.Cu" "B.Cu" "In1.Cu" "In2.Cu" "In3.Cu" "In4.Cu" "In5.Cu" "In6.Cu")
			(hatch none 0.5)
			(connect_pads
				(clearance 0)
			)
			(min_thickness 0.25)
			(keepout
				(tracks not_allowed)
				(vias allowed)
				(pads allowed)
				(copperpour not_allowed)
				(footprints allowed)
			)
			(placement
				(enabled no)
				(sheetname "")
			)
			(fill
				(thermal_gap 0.5)
				(thermal_bridge_width 0.5)
				(island_removal_mode 0)
			)
			(polygon
				(pts
					(arc
						(start 8.806942 -25.909778)
						(mid 6.673342 -25.909778)
						(end 8.806942 -25.909778)
					)
				)
			)
		)
	)
	(footprint ""
		(layer "F.Cu")
		(at 91.399868 -508.96012)
		(property "Reference" "H24"
			(at -5.1308 -5.23113 0)
			(unlocked yes)
			(layer "F.SilkS")
			(effects
				(font
					(size 0.7874 0.5842)
					(thickness 0.1524)
				)
				(justify left)
			)
		)
		(property "Value" ""
			(at 0 0 0)
			(layer "F.Fab")
			(effects
				(font
					(size 1.27 1.27)
				)
			)
		)
		(duplicate_pad_numbers_are_jumpers no)
		(fp_circle
			(center 0 0)
			(end 4.826 0)
			(stroke
				(width 0.1524)
				(type default)
			)
			(fill no)
			(layer "F.SilkS")
		)
		(fp_circle
			(center 0 0)
			(end 4.826 0)
			(stroke
				(width 0.1524)
				(type default)
			)
			(fill no)
			(layer "B.SilkS")
		)
		(fp_poly
			(pts
				(arc
					(start 0 4.0132)
					(mid 0 -4.0132)
					(end 0 4.0132)
				)
			)
			(stroke
				(width 0)
				(type default)
			)
			(fill no)
			(layer "F.CrtYd")
		)
		(pad "" np_thru_hole circle
			(at 0 0)
			(size 8.001 8.001)
			(drill 8.001)
			(layers "*.Cu" "*.Mask")
			(clearance 0.381)
			(thermal_gap 0.381)
		)
		(zone
			(layers "F.Cu" "B.Cu" "In1.Cu" "In2.Cu" "In3.Cu" "In4.Cu" "In5.Cu" "In6.Cu")
			(hatch none 0.5)
			(connect_pads
				(clearance 0)
			)
			(min_thickness 0.25)
			(keepout
				(tracks not_allowed)
				(vias allowed)
				(pads allowed)
				(copperpour not_allowed)
				(footprints allowed)
			)
			(placement
				(enabled no)
				(sheetname "")
			)
			(fill
				(thermal_gap 0.5)
				(thermal_bridge_width 0.5)
				(island_removal_mode 0)
			)
			(polygon
				(pts
					(arc
						(start 91.399868 -504.43892)
						(mid 91.399868 -513.48132)
						(end 91.399868 -504.43892)
					)
				)
			)
		)
	)
	(footprint ""
		(layer "F.Cu")
		(at 26.947622 -108.230416)
		(property "Reference" "R7"
			(at -2.66192 0.007112 0)
			(unlocked yes)
			(layer "F.SilkS")
			(effects
				(font
					(size 0.7874 0.5842)
					(thickness 0.1524)
				)
				(justify left)
			)
		)
		(property "Value" ""
			(at 0 0 0)
			(layer "F.Fab")
			(effects
				(font
					(size 1.27 1.27)
				)
			)
		)
		(duplicate_pad_numbers_are_jumpers no)
		(fp_line
			(start -0.7874 -0.4064)
			(end 0.7874 -0.4064)
			(stroke
				(width 0.1524)
				(type default)
			)
			(layer "F.SilkS")
		)
		(fp_line
			(start -0.7874 0.4064)
			(end -0.7874 -0.4064)
			(stroke
				(width 0.1524)
				(type default)
			)
			(layer "F.SilkS")
		)
		(fp_line
			(start 0.7874 -0.4064)
			(end 0.7874 0.4064)
			(stroke
				(width 0.1524)
				(type default)
			)
			(layer "F.SilkS")
		)
		(fp_line
			(start 0.7874 0.4064)
			(end -0.7874 0.4064)
			(stroke
				(width 0.1524)
				(type default)
			)
			(layer "F.SilkS")
		)
		(fp_poly
			(pts
				(xy -0.508 0.2794) (xy -0.508 0.2286) (xy -0.635 0.2286) (xy -0.635 -0.254) (xy -0.5334 -0.254)
				(xy -0.5334 -0.2794) (xy 0.5334 -0.2794) (xy 0.5334 -0.254) (xy 0.635 -0.254) (xy 0.635 0.254) (xy 0.5334 0.254)
				(xy 0.5334 0.2794)
			)
			(stroke
				(width 0)
				(type default)
			)
			(fill no)
			(layer "F.CrtYd")
		)
		(pad "1" smd rect
			(at 0.40005 0)
			(size 0.4572 0.508)
			(layers "F.Cu" "F.Mask" "F.Paste")
			(net "PSU2_REMOTE_N")
		)
		(pad "2" smd rect
			(at -0.40005 0)
			(size 0.4572 0.508)
			(layers "F.Cu" "F.Mask" "F.Paste")
			(net "GND")
		)
	)
	(footprint ""
		(layer "F.Cu")
		(at 39.863776 -199.171814 180)
		(property "Reference" "R2"
			(at -1.93802 0.367792 0)
			(unlocked yes)
			(layer "F.SilkS")
			(effects
				(font
					(size 0.7874 0.5842)
					(thickness 0.1524)
				)
				(justify left)
			)
		)
		(property "Value" ""
			(at 0 0 180)
			(layer "F.Fab")
			(effects
				(font
					(size 1.27 1.27)
				)
			)
		)
		(duplicate_pad_numbers_are_jumpers no)
		(fp_line
			(start 0.7874 0.4064)
			(end -0.7874 0.4064)
			(stroke
				(width 0.1524)
				(type default)
			)
			(layer "F.SilkS")
		)
		(fp_line
			(start 0.7874 -0.4064)
			(end 0.7874 0.4064)
			(stroke
				(width 0.1524)
				(type default)
			)
			(layer "F.SilkS")
		)
		(fp_line
			(start -0.7874 0.4064)
			(end -0.7874 -0.4064)
			(stroke
				(width 0.1524)
				(type default)
			)
			(layer "F.SilkS")
		)
		(fp_line
			(start -0.7874 -0.4064)
			(end 0.7874 -0.4064)
			(stroke
				(width 0.1524)
				(type default)
			)
			(layer "F.SilkS")
		)
		(fp_poly
			(pts
				(xy -0.508 0.2794) (xy -0.508 0.2286) (xy -0.635 0.2286) (xy -0.635 -0.254) (xy -0.5334 -0.254)
				(xy -0.5334 -0.2794) (xy 0.5334 -0.2794) (xy 0.5334 -0.254) (xy 0.635 -0.254) (xy 0.635 0.254) (xy 0.5334 0.254)
				(xy 0.5334 0.2794)
			)
			(stroke
				(width 0)
				(type default)
			)
			(fill no)
			(layer "F.CrtYd")
		)
		(pad "1" smd rect
			(at 0.40005 0 180)
			(size 0.4572 0.508)
			(layers "F.Cu" "F.Mask" "F.Paste")
			(net "PSU3_REMOTE_P")
		)
		(pad "2" smd rect
			(at -0.40005 0 180)
			(size 0.4572 0.508)
			(layers "F.Cu" "F.Mask" "F.Paste")
			(net "P12V")
		)
	)
	(footprint ""
		(layer "F.Cu")
		(at 26.226008 -448.493388)
		(property "Reference" "R85"
			(at -2.9972 0.666242 0)
			(unlocked yes)
			(layer "F.SilkS")
			(effects
				(font
					(size 0.7874 0.5842)
					(thickness 0.1524)
				)
				(justify left)
			)
		)
		(property "Value" ""
			(at 0 0 0)
			(layer "F.Fab")
			(effects
				(font
					(size 1.27 1.27)
				)
			)
		)
		(duplicate_pad_numbers_are_jumpers no)
		(fp_line
			(start -0.7874 -0.4064)
			(end 0.7874 -0.4064)
			(stroke
				(width 0.1524)
				(type default)
			)
			(layer "F.SilkS")
		)
		(fp_line
			(start -0.7874 0.4064)
			(end -0.7874 -0.4064)
			(stroke
				(width 0.1524)
				(type default)
			)
			(layer "F.SilkS")
		)
		(fp_line
			(start 0.7874 -0.4064)
			(end 0.7874 0.4064)
			(stroke
				(width 0.1524)
				(type default)
			)
			(layer "F.SilkS")
		)
		(fp_line
			(start 0.7874 0.4064)
			(end -0.7874 0.4064)
			(stroke
				(width 0.1524)
				(type default)
			)
			(layer "F.SilkS")
		)
		(fp_poly
			(pts
				(xy -0.508 0.2794) (xy -0.508 0.2286) (xy -0.635 0.2286) (xy -0.635 -0.254) (xy -0.5334 -0.254)
				(xy -0.5334 -0.2794) (xy 0.5334 -0.2794) (xy 0.5334 -0.254) (xy 0.635 -0.254) (xy 0.635 0.254) (xy 0.5334 0.254)
				(xy 0.5334 0.2794)
			)
			(stroke
				(width 0)
				(type default)
			)
			(fill no)
			(layer "F.CrtYd")
		)
		(pad "1" smd rect
			(at 0.40005 0)
			(size 0.4572 0.508)
			(layers "F.Cu" "F.Mask" "F.Paste")
			(net "PSU6_RESET")
		)
		(pad "2" smd rect
			(at -0.40005 0)
			(size 0.4572 0.508)
			(layers "F.Cu" "F.Mask" "F.Paste")
			(net "GND")
		)
	)
	(footprint ""
		(layer "F.Cu")
		(at 39.936674 -464.36915 180)
		(property "Reference" "R17"
			(at -1.699514 0.166624 0)
			(unlocked yes)
			(layer "F.SilkS")
			(effects
				(font
					(size 0.7874 0.5842)
					(thickness 0.1524)
				)
				(justify left)
			)
		)
		(property "Value" ""
			(at 0 0 180)
			(layer "F.Fab")
			(effects
				(font
					(size 1.27 1.27)
				)
			)
		)
		(duplicate_pad_numbers_are_jumpers no)
		(fp_line
			(start 0.7874 0.4064)
			(end -0.7874 0.4064)
			(stroke
				(width 0.1524)
				(type default)
			)
			(layer "F.SilkS")
		)
		(fp_line
			(start 0.7874 -0.4064)
			(end 0.7874 0.4064)
			(stroke
				(width 0.1524)
				(type default)
			)
			(layer "F.SilkS")
		)
		(fp_line
			(start -0.7874 0.4064)
			(end -0.7874 -0.4064)
			(stroke
				(width 0.1524)
				(type default)
			)
			(layer "F.SilkS")
		)
		(fp_line
			(start -0.7874 -0.4064)
			(end 0.7874 -0.4064)
			(stroke
				(width 0.1524)
				(type default)
			)
			(layer "F.SilkS")
		)
		(fp_poly
			(pts
				(xy -0.508 0.2794) (xy -0.508 0.2286) (xy -0.635 0.2286) (xy -0.635 -0.254) (xy -0.5334 -0.254)
				(xy -0.5334 -0.2794) (xy 0.5334 -0.2794) (xy 0.5334 -0.254) (xy 0.635 -0.254) (xy 0.635 0.254) (xy 0.5334 0.254)
				(xy 0.5334 0.2794)
			)
			(stroke
				(width 0)
				(type default)
			)
			(fill no)
			(layer "F.CrtYd")
		)
		(pad "1" smd rect
			(at 0.40005 0 180)
			(size 0.4572 0.508)
			(layers "F.Cu" "F.Mask" "F.Paste")
			(net "PSU6_REMOTE_P")
		)
		(pad "2" smd rect
			(at -0.40005 0 180)
			(size 0.4572 0.508)
			(layers "F.Cu" "F.Mask" "F.Paste")
			(net "P12V")
		)
	)
	(footprint ""
		(layer "F.Cu")
		(at 40.86098 -283.09824 -90)
		(property "Reference" "R21"
			(at 0.946912 -2.85623 90)
			(unlocked yes)
			(layer "F.SilkS")
			(effects
				(font
					(size 0.7874 0.5842)
					(thickness 0.1524)
				)
				(justify left)
			)
		)
		(property "Value" ""
			(at 0 0 270)
			(layer "F.Fab")
			(effects
				(font
					(size 1.27 1.27)
				)
			)
		)
		(duplicate_pad_numbers_are_jumpers no)
		(fp_line
			(start -0.7874 0.4064)
			(end -0.7874 -0.4064)
			(stroke
				(width 0.1524)
				(type default)
			)
			(layer "F.SilkS")
		)
		(fp_line
			(start 0.7874 0.4064)
			(end -0.7874 0.4064)
			(stroke
				(width 0.1524)
				(type default)
			)
			(layer "F.SilkS")
		)
		(fp_line
			(start -0.7874 -0.4064)
			(end 0.7874 -0.4064)
			(stroke
				(width 0.1524)
				(type default)
			)
			(layer "F.SilkS")
		)
		(fp_line
			(start 0.7874 -0.4064)
			(end 0.7874 0.4064)
			(stroke
				(width 0.1524)
				(type default)
			)
			(layer "F.SilkS")
		)
		(fp_poly
			(pts
				(xy -0.508 0.2794) (xy -0.508 0.2286) (xy -0.635 0.2286) (xy -0.635 -0.254) (xy -0.5334 -0.254)
				(xy -0.5334 -0.2794) (xy 0.5334 -0.2794) (xy 0.5334 -0.254) (xy 0.635 -0.254) (xy 0.635 0.254) (xy 0.5334 0.254)
				(xy 0.5334 0.2794)
			)
			(stroke
				(width 0)
				(type default)
			)
			(fill no)
			(layer "F.CrtYd")
		)
		(pad "1" smd rect
			(at 0.40005 0 270)
			(size 0.4572 0.508)
			(layers "F.Cu" "F.Mask" "F.Paste")
			(net "PSU4_AD0")
		)
		(pad "2" smd rect
			(at -0.40005 0 270)
			(size 0.4572 0.508)
			(layers "F.Cu" "F.Mask" "F.Paste")
			(net "GND")
		)
	)
	(footprint ""
		(layer "F.Cu")
		(at 14.034516 -409.576016 -90)
		(property "Reference" "J28"
			(at -1.48209 -5.22351 90)
			(unlocked yes)
			(layer "F.SilkS")
			(effects
				(font
					(size 0.7874 0.5842)
					(thickness 0.1524)
				)
				(justify left)
			)
		)
		(property "Value" ""
			(at 0 0 270)
			(layer "F.Fab")
			(effects
				(font
					(size 1.27 1.27)
				)
			)
		)
		(duplicate_pad_numbers_are_jumpers no)
		(fp_line
			(start -3.754882 12.899898)
			(end -3.754882 3.7846)
			(stroke
				(width 0.1524)
				(type default)
			)
			(layer "F.SilkS")
		)
		(fp_line
			(start 12.644882 12.899898)
			(end -3.754882 12.899898)
			(stroke
				(width 0.1524)
				(type default)
			)
			(layer "F.SilkS")
		)
		(fp_line
			(start 12.644882 3.7846)
			(end 12.644882 12.899898)
			(stroke
				(width 0.1524)
				(type default)
			)
			(layer "F.SilkS")
		)
		(fp_line
			(start -3.754882 1.2192)
			(end -3.754882 -3.800094)
			(stroke
				(width 0.1524)
				(type default)
			)
			(layer "F.SilkS")
		)
		(fp_line
			(start -3.754882 -3.800094)
			(end 12.644882 -3.800094)
			(stroke
				(width 0.1524)
				(type default)
			)
			(layer "F.SilkS")
		)
		(fp_line
			(start 12.644882 -3.800094)
			(end 12.644882 1.2192)
			(stroke
				(width 0.1524)
				(type default)
			)
			(layer "F.SilkS")
		)
		(fp_poly
			(pts
				(xy -3.807714 -0.117094) (xy -4.479544 0.218948) (xy -4.479544 -0.453136)
			)
			(stroke
				(width 0)
				(type default)
			)
			(fill yes)
			(layer "F.SilkS")
		)
		(fp_poly
			(pts
				(xy -2.591562 11.176) (xy 1.370838 11.176) (xy 1.370838 9.7282) (xy -2.591562 9.7282)
			)
			(stroke
				(width 0)
				(type default)
			)
			(fill no)
			(layer "B.CrtYd")
		)
		(fp_poly
			(pts
				(xy 7.5184 11.176) (xy 11.4808 11.176) (xy 11.4808 9.7282) (xy 7.5184 9.7282)
			)
			(stroke
				(width 0)
				(type default)
			)
			(fill no)
			(layer "B.CrtYd")
		)
		(fp_poly
			(pts
				(xy 9.627362 -3.256026) (xy 9.627362 -1.808226) (xy 8.357362 -1.808226) (xy 8.357362 0.731774) (xy -0.735838 0.731774)
				(xy -0.735838 -0.741426) (xy 0.534162 -0.741426) (xy 0.534162 -3.256026)
			)
			(stroke
				(width 0)
				(type default)
			)
			(fill no)
			(layer "B.CrtYd")
		)
		(fp_poly
			(pts
				(arc
					(start -3.430016 1.268222)
					(mid -3.430016 3.732022)
					(end -3.430016 1.268222)
				)
			)
			(stroke
				(width 0)
				(type default)
			)
			(fill no)
			(layer "B.CrtYd")
		)
		(fp_poly
			(pts
				(arc
					(start 12.320016 1.267968)
					(mid 12.320016 3.732276)
					(end 12.320016 1.267968)
				)
			)
			(stroke
				(width 0)
				(type default)
			)
			(fill no)
			(layer "B.CrtYd")
		)
		(fp_poly
			(pts
				(arc
					(start -1.27 4.4958)
					(mid -1.27 8.2042)
					(end -1.27 4.4958)
				)
			)
			(stroke
				(width 0)
				(type default)
			)
			(fill no)
			(layer "B.CrtYd")
		)
		(fp_poly
			(pts
				(arc
					(start 10.16 4.4958)
					(mid 10.16 8.2042)
					(end 10.16 4.4958)
				)
			)
			(stroke
				(width 0)
				(type default)
			)
			(fill no)
			(layer "B.CrtYd")
		)
		(fp_poly
			(pts
				(xy -3.754882 12.899898)
				(arc
					(start -3.754882 3.688334)
					(mid -4.662083 2.499901)
					(end -3.754882 1.311656)
				)
				(xy -3.754882 -3.800094) (xy 12.644882 -3.800094)
				(arc
					(start 12.644882 1.311656)
					(mid 13.551838 2.499901)
					(end 12.644882 3.688334)
				)
				(xy 12.644882 12.899898)
			)
			(stroke
				(width 0)
				(type default)
			)
			(fill no)
			(layer "F.CrtYd")
		)
		(fp_line
			(start -3.754882 12.899898)
			(end -3.754882 -3.800094)
			(stroke
				(width 0.1)
				(type default)
			)
			(layer "F.Fab")
		)
		(fp_line
			(start 12.644882 12.899898)
			(end -3.754882 12.899898)
			(stroke
				(width 0.1)
				(type default)
			)
			(layer "F.Fab")
		)
		(fp_line
			(start -3.754882 -3.800094)
			(end 12.644882 -3.800094)
			(stroke
				(width 0.1)
				(type default)
			)
			(layer "F.Fab")
		)
		(fp_line
			(start 12.644882 -3.800094)
			(end 12.644882 12.899898)
			(stroke
				(width 0.1)
				(type default)
			)
			(layer "F.Fab")
		)
		(fp_poly
			(pts
				(xy -4.125214 0) (xy -5.806186 0.840486) (xy -5.806186 -0.840486)
			)
			(stroke
				(width 0)
				(type default)
			)
			(fill yes)
			(layer "F.Fab")
		)
		(fp_text user "7"
			(at 13.598398 -0.217932 0)
			(unlocked yes)
			(layer "F.SilkS")
			(effects
				(font
					(size 0.7874 0.5842)
					(thickness 0.1524)
				)
			)
		)
		(fp_text user "1"
			(at -4.614164 -0.854964 0)
			(unlocked yes)
			(layer "F.SilkS")
			(effects
				(font
					(size 0.7874 0.5842)
					(thickness 0.1524)
				)
			)
		)
		(fp_text user "8"
			(at 13.521944 -2.506726 0)
			(unlocked yes)
			(layer "F.SilkS")
			(effects
				(font
					(size 0.7874 0.5842)
					(thickness 0.1524)
				)
			)
		)
		(fp_text user "2"
			(at -4.563364 -2.729992 0)
			(unlocked yes)
			(layer "F.SilkS")
			(effects
				(font
					(size 0.7874 0.5842)
					(thickness 0.1524)
				)
			)
		)
		(fp_text user "1"
			(at -1.320038 0.081026 0)
			(unlocked yes)
			(layer "B.SilkS")
			(effects
				(font
					(size 0.7874 0.5842)
					(thickness 0.1524)
				)
				(justify mirror)
			)
		)
		(fp_text user "7"
			(at 9.437116 0.013462 0)
			(unlocked yes)
			(layer "B.SilkS")
			(effects
				(font
					(size 0.7874 0.5842)
					(thickness 0.1524)
				)
				(justify mirror)
			)
		)
		(fp_text user "2"
			(at -0.599694 -2.592832 0)
			(unlocked yes)
			(layer "B.SilkS")
			(effects
				(font
					(size 0.7874 0.5842)
					(thickness 0.1524)
				)
				(justify mirror)
			)
		)
		(fp_text user "8"
			(at 9.335008 -3.694938 0)
			(unlocked yes)
			(layer "B.SilkS")
			(effects
				(font
					(size 0.7874 0.5842)
					(thickness 0.1524)
				)
				(justify mirror)
			)
		)
		(fp_text user "7"
			(at 8.8646 0.085852 270)
			(unlocked yes)
			(layer "B.Fab")
			(effects
				(font
					(size 0.7874 0.5842)
					(thickness 0.000001)
				)
				(justify mirror)
			)
		)
		(fp_text user "1"
			(at -1.1811 -0.053848 270)
			(unlocked yes)
			(layer "B.Fab")
			(effects
				(font
					(size 0.7874 0.5842)
					(thickness 0.000001)
				)
				(justify mirror)
			)
		)
		(fp_text user "8"
			(at 10.1219 -2.479548 270)
			(unlocked yes)
			(layer "B.Fab")
			(effects
				(font
					(size 0.7874 0.5842)
					(thickness 0.000001)
				)
				(justify mirror)
			)
		)
		(fp_text user "2"
			(at -0.0635 -2.631948 270)
			(unlocked yes)
			(layer "B.Fab")
			(effects
				(font
					(size 0.7874 0.5842)
					(thickness 0.000001)
				)
				(justify mirror)
			)
		)
		(fp_text user "7"
			(at 13.2334 -0.079248 270)
			(unlocked yes)
			(layer "F.Fab")
			(effects
				(font
					(size 0.7874 0.5842)
					(thickness 0.000001)
				)
			)
		)
		(fp_text user "1"
			(at -4.4323 -1.019048 270)
			(unlocked yes)
			(layer "F.Fab")
			(effects
				(font
					(size 0.7874 0.5842)
					(thickness 0.000001)
				)
			)
		)
		(fp_text user "2"
			(at -4.4704 -2.581148 270)
			(unlocked yes)
			(layer "F.Fab")
			(effects
				(font
					(size 0.7874 0.5842)
					(thickness 0.000001)
				)
			)
		)
		(fp_text user "8"
			(at 13.2715 -2.593848 270)
			(unlocked yes)
			(layer "F.Fab")
			(effects
				(font
					(size 0.7874 0.5842)
					(thickness 0.000001)
				)
			)
		)
		(pad "" np_thru_hole circle
			(at -1.27 6.35 270)
			(size 3.2004 3.2004)
			(drill 3.2004)
			(layers "*.Cu" "*.Mask")
			(clearance 0.381)
			(thermal_gap 0.381)
		)
		(pad "" np_thru_hole circle
			(at 10.16 6.35 270)
			(size 3.2004 3.2004)
			(drill 3.2004)
			(layers "*.Cu" "*.Mask")
			(clearance 0.381)
			(thermal_gap 0.381)
		)
		(pad "1" thru_hole rect
			(at 0 0 270)
			(size 1.3208 1.3208)
			(drill 0.9144)
			(layers "*.Cu" "*.Mask")
			(remove_unused_layers no)
			(net "LAN2_P1_P")
			(clearance 0.0508)
			(thermal_gap 0.0508)
			(padstack
				(mode front_inner_back)
				(layer "Inner"
					(shape circle)
					(size 1.3208 1.3208)
					(clearance 0.0508)
				)
				(layer "B.Cu"
					(shape rect)
					(size 1.3208 1.3208)
					(clearance 0.0508)
				)
			)
		)
		(pad "2" thru_hole circle
			(at 1.27 -2.54 270)
			(size 1.3208 1.3208)
			(drill 0.9144)
			(layers "*.Cu" "*.Mask")
			(remove_unused_layers no)
			(net "LAN2_P1_N")
			(clearance 0.0508)
			(thermal_gap 0.0508)
		)
		(pad "3" thru_hole circle
			(at 2.54 0 270)
			(size 1.3208 1.3208)
			(drill 0.9144)
			(layers "*.Cu" "*.Mask")
			(remove_unused_layers no)
			(net "LAN2_P2_P")
			(clearance 0.0508)
			(thermal_gap 0.0508)
		)
		(pad "4" thru_hole circle
			(at 3.81 -2.54 270)
			(size 1.3208 1.3208)
			(drill 0.9144)
			(layers "*.Cu" "*.Mask")
			(remove_unused_layers no)
			(net "LAN2_P3_P")
			(clearance 0.0508)
			(thermal_gap 0.0508)
		)
		(pad "5" thru_hole circle
			(at 5.08 0 270)
			(size 1.3208 1.3208)
			(drill 0.9144)
			(layers "*.Cu" "*.Mask")
			(remove_unused_layers no)
			(net "LAN2_P3_N")
			(clearance 0.0508)
			(thermal_gap 0.0508)
		)
		(pad "6" thru_hole circle
			(at 6.35 -2.54 270)
			(size 1.3208 1.3208)
			(drill 0.9144)
			(layers "*.Cu" "*.Mask")
			(remove_unused_layers no)
			(net "LAN2_P2_N")
			(clearance 0.0508)
			(thermal_gap 0.0508)
		)
		(pad "7" thru_hole circle
			(at 7.62 0 270)
			(size 1.3208 1.3208)
			(drill 0.9144)
			(layers "*.Cu" "*.Mask")
			(remove_unused_layers no)
			(net "LAN2_P4_P")
			(clearance 0.0508)
			(thermal_gap 0.0508)
		)
		(pad "8" thru_hole circle
			(at 8.89 -2.54 270)
			(size 1.3208 1.3208)
			(drill 0.9144)
			(layers "*.Cu" "*.Mask")
			(remove_unused_layers no)
			(net "LAN2_P4_N")
			(clearance 0.0508)
			(thermal_gap 0.0508)
		)
		(pad "9" thru_hole circle
			(at -1.854962 10.459974 270)
			(size 1.3208 1.3208)
			(drill 0.9144)
			(layers "*.Cu" "*.Mask")
			(remove_unused_layers no)
			(net "N42132933")
			(clearance 0.0508)
			(thermal_gap 0.0508)
		)
		(pad "10" thru_hole circle
			(at 0.635 10.459974 270)
			(size 1.3208 1.3208)
			(drill 0.9144)
			(layers "*.Cu" "*.Mask")
			(remove_unused_layers no)
			(net "N42132545")
			(clearance 0.0508)
			(thermal_gap 0.0508)
		)
		(pad "11" thru_hole circle
			(at 8.255 10.459974 270)
			(size 1.3208 1.3208)
			(drill 0.9144)
			(layers "*.Cu" "*.Mask")
			(remove_unused_layers no)
			(net "Net_115")
			(clearance 0.0508)
			(thermal_gap 0.0508)
		)
		(pad "12" thru_hole circle
			(at 10.744962 10.459974 270)
			(size 1.3208 1.3208)
			(drill 0.9144)
			(layers "*.Cu" "*.Mask")
			(remove_unused_layers no)
			(net "N42132358")
			(clearance 0.0508)
			(thermal_gap 0.0508)
		)
		(pad "G1" thru_hole circle
			(at -3.430016 2.500122 270)
			(size 2.3622 2.3622)
			(drill 1.6002)
			(layers "*.Cu" "*.Mask")
			(remove_unused_layers no)
			(net "GND")
			(clearance -0.127)
		)
		(pad "G2" thru_hole circle
			(at 12.320016 2.500122 270)
			(size 2.3622 2.3622)
			(drill 1.6002)
			(layers "*.Cu" "*.Mask")
			(remove_unused_layers no)
			(net "GND")
			(clearance -0.127)
		)
		(zone
			(layers "F.Cu" "B.Cu" "In1.Cu" "In2.Cu" "In3.Cu" "In4.Cu" "In5.Cu" "In6.Cu")
			(hatch none 0.5)
			(connect_pads
				(clearance 0)
			)
			(min_thickness 0.25)
			(keepout
				(tracks not_allowed)
				(vias allowed)
				(pads allowed)
				(copperpour not_allowed)
				(footprints allowed)
			)
			(placement
				(enabled no)
				(sheetname "")
			)
			(fill
				(thermal_gap 0.5)
				(thermal_bridge_width 0.5)
				(island_removal_mode 0)
			)
			(polygon
				(pts
					(arc
						(start 9.691116 -410.846016)
						(mid 5.677916 -410.846016)
						(end 9.691116 -410.846016)
					)
				)
			)
		)
		(zone
			(layers "F.Cu" "B.Cu" "In1.Cu" "In2.Cu" "In3.Cu" "In4.Cu" "In5.Cu" "In6.Cu")
			(hatch none 0.5)
			(connect_pads
				(clearance 0)
			)
			(min_thickness 0.25)
			(keepout
				(tracks not_allowed)
				(vias allowed)
				(pads allowed)
				(copperpour not_allowed)
				(footprints allowed)
			)
			(placement
				(enabled no)
				(sheetname "")
			)
			(fill
				(thermal_gap 0.5)
				(thermal_bridge_width 0.5)
				(island_removal_mode 0)
			)
			(polygon
				(pts
					(arc
						(start 9.691116 -399.416016)
						(mid 5.677916 -399.416016)
						(end 9.691116 -399.416016)
					)
				)
			)
		)
	)
	(footprint ""
		(layer "F.Cu")
		(at 27.640026 -461.429862 90)
		(property "Reference" "R133"
			(at -3.59664 -1.369314 90)
			(unlocked yes)
			(layer "F.SilkS")
			(effects
				(font
					(size 0.7874 0.5842)
					(thickness 0.1524)
				)
				(justify left)
			)
		)
		(property "Value" ""
			(at 0 0 90)
			(layer "F.Fab")
			(effects
				(font
					(size 1.27 1.27)
				)
			)
		)
		(duplicate_pad_numbers_are_jumpers no)
		(fp_line
			(start 0.7874 -0.4064)
			(end 0.7874 0.4064)
			(stroke
				(width 0.1524)
				(type default)
			)
			(layer "F.SilkS")
		)
		(fp_line
			(start -0.7874 -0.4064)
			(end 0.7874 -0.4064)
			(stroke
				(width 0.1524)
				(type default)
			)
			(layer "F.SilkS")
		)
		(fp_line
			(start 0.7874 0.4064)
			(end -0.7874 0.4064)
			(stroke
				(width 0.1524)
				(type default)
			)
			(layer "F.SilkS")
		)
		(fp_line
			(start -0.7874 0.4064)
			(end -0.7874 -0.4064)
			(stroke
				(width 0.1524)
				(type default)
			)
			(layer "F.SilkS")
		)
		(fp_poly
			(pts
				(xy -0.508 0.2794) (xy -0.508 0.2286) (xy -0.635 0.2286) (xy -0.635 -0.254) (xy -0.5334 -0.254)
				(xy -0.5334 -0.2794) (xy 0.5334 -0.2794) (xy 0.5334 -0.254) (xy 0.635 -0.254) (xy 0.635 0.254) (xy 0.5334 0.254)
				(xy 0.5334 0.2794)
			)
			(stroke
				(width 0)
				(type default)
			)
			(fill no)
			(layer "F.CrtYd")
		)
		(pad "1" smd rect
			(at 0.40005 0 90)
			(size 0.4572 0.508)
			(layers "F.Cu" "F.Mask" "F.Paste")
			(net "PSU6_REMOTE_N")
		)
		(pad "2" smd rect
			(at -0.40005 0 90)
			(size 0.4572 0.508)
			(layers "F.Cu" "F.Mask" "F.Paste")
			(net "PSU6_REMOTE_R2_N")
		)
	)
	(footprint ""
		(layer "F.Cu")
		(at 39.653718 -283.096208 -90)
		(property "Reference" "R16"
			(at 0.95885 -2.95783 90)
			(unlocked yes)
			(layer "F.SilkS")
			(effects
				(font
					(size 0.7874 0.5842)
					(thickness 0.1524)
				)
				(justify left)
			)
		)
		(property "Value" ""
			(at 0 0 270)
			(layer "F.Fab")
			(effects
				(font
					(size 1.27 1.27)
				)
			)
		)
		(duplicate_pad_numbers_are_jumpers no)
		(fp_line
			(start -0.7874 0.4064)
			(end -0.7874 -0.4064)
			(stroke
				(width 0.1524)
				(type default)
			)
			(layer "F.SilkS")
		)
		(fp_line
			(start 0.7874 0.4064)
			(end -0.7874 0.4064)
			(stroke
				(width 0.1524)
				(type default)
			)
			(layer "F.SilkS")
		)
		(fp_line
			(start -0.7874 -0.4064)
			(end 0.7874 -0.4064)
			(stroke
				(width 0.1524)
				(type default)
			)
			(layer "F.SilkS")
		)
		(fp_line
			(start 0.7874 -0.4064)
			(end 0.7874 0.4064)
			(stroke
				(width 0.1524)
				(type default)
			)
			(layer "F.SilkS")
		)
		(fp_poly
			(pts
				(xy -0.508 0.2794) (xy -0.508 0.2286) (xy -0.635 0.2286) (xy -0.635 -0.254) (xy -0.5334 -0.254)
				(xy -0.5334 -0.2794) (xy 0.5334 -0.2794) (xy 0.5334 -0.254) (xy 0.635 -0.254) (xy 0.635 0.254) (xy 0.5334 0.254)
				(xy 0.5334 0.2794)
			)
			(stroke
				(width 0)
				(type default)
			)
			(fill no)
			(layer "F.CrtYd")
		)
		(pad "1" smd rect
			(at 0.40005 0 270)
			(size 0.4572 0.508)
			(layers "F.Cu" "F.Mask" "F.Paste")
			(net "PSU4_AD0")
		)
		(pad "2" smd rect
			(at -0.40005 0 270)
			(size 0.4572 0.508)
			(layers "F.Cu" "F.Mask" "F.Paste")
			(net "P12V_STBY")
		)
	)
	(footprint ""
		(layer "F.Cu")
		(at 71.518526 -109.07776 -90)
		(property "Reference" "C15"
			(at -3.25374 -0.008128 90)
			(unlocked yes)
			(layer "F.SilkS")
			(effects
				(font
					(size 0.7874 0.5842)
					(thickness 0.1524)
				)
			)
		)
		(property "Value" ""
			(at 0 0 270)
			(layer "F.Fab")
			(effects
				(font
					(size 1.27 1.27)
				)
			)
		)
		(duplicate_pad_numbers_are_jumpers no)
		(fp_line
			(start -1.2954 0.5842)
			(end -1.2954 -0.5842)
			(stroke
				(width 0.1524)
				(type default)
			)
			(layer "F.SilkS")
		)
		(fp_line
			(start 1.2954 0.5842)
			(end -1.2954 0.5842)
			(stroke
				(width 0.1524)
				(type default)
			)
			(layer "F.SilkS")
		)
		(fp_line
			(start -1.2954 -0.5842)
			(end 1.2954 -0.5842)
			(stroke
				(width 0.1524)
				(type default)
			)
			(layer "F.SilkS")
		)
		(fp_line
			(start 0 -0.5842)
			(end 0 0.5842)
			(stroke
				(width 0.1524)
				(type default)
			)
			(layer "F.SilkS")
		)
		(fp_line
			(start 1.2954 -0.5842)
			(end 1.2954 0.5842)
			(stroke
				(width 0.1524)
				(type default)
			)
			(layer "F.SilkS")
		)
		(fp_poly
			(pts
				(xy 0.8636 -0.4572) (xy 0.8636 -0.3556) (xy 1.143 -0.3556) (xy 1.143 0.3556) (xy 0.8636 0.3556)
				(xy 0.8636 0.4572) (xy -0.8636 0.4572) (xy -0.8636 0.3556) (xy -1.143 0.3556) (xy -1.143 -0.3556)
				(xy -0.8636 -0.3556) (xy -0.8636 -0.4572)
			)
			(stroke
				(width 0)
				(type default)
			)
			(fill no)
			(layer "F.CrtYd")
		)
		(fp_line
			(start -0.884936 0.504952)
			(end -0.884936 -0.504952)
			(stroke
				(width 0.1)
				(type default)
			)
			(layer "F.Fab")
		)
		(fp_line
			(start 0.884936 0.504952)
			(end -0.884936 0.504952)
			(stroke
				(width 0.1)
				(type default)
			)
			(layer "F.Fab")
		)
		(fp_line
			(start -0.884936 -0.504952)
			(end 0.884936 -0.504952)
			(stroke
				(width 0.1)
				(type default)
			)
			(layer "F.Fab")
		)
		(fp_line
			(start 0.884936 -0.504952)
			(end 0.884936 0.504952)
			(stroke
				(width 0.1)
				(type default)
			)
			(layer "F.Fab")
		)
		(pad "1" smd rect
			(at 0.7366 0)
			(size 0.7112 0.8128)
			(layers "F.Cu" "F.Mask" "F.Paste")
			(net "P12V")
		)
		(pad "2" smd rect
			(at -0.7366 0)
			(size 0.7112 0.8128)
			(layers "F.Cu" "F.Mask" "F.Paste")
			(net "GND")
		)
	)
	(footprint ""
		(layer "F.Cu")
		(at 26.226008 -453.535034)
		(property "Reference" "R60"
			(at -3.522472 -0.815594 0)
			(unlocked yes)
			(layer "F.SilkS")
			(effects
				(font
					(size 0.7874 0.5842)
					(thickness 0.1524)
				)
				(justify left)
			)
		)
		(property "Value" ""
			(at 0 0 0)
			(layer "F.Fab")
			(effects
				(font
					(size 1.27 1.27)
				)
			)
		)
		(duplicate_pad_numbers_are_jumpers no)
		(fp_line
			(start -0.7874 -0.4064)
			(end 0.7874 -0.4064)
			(stroke
				(width 0.1524)
				(type default)
			)
			(layer "F.SilkS")
		)
		(fp_line
			(start -0.7874 0.4064)
			(end -0.7874 -0.4064)
			(stroke
				(width 0.1524)
				(type default)
			)
			(layer "F.SilkS")
		)
		(fp_line
			(start 0.7874 -0.4064)
			(end 0.7874 0.4064)
			(stroke
				(width 0.1524)
				(type default)
			)
			(layer "F.SilkS")
		)
		(fp_line
			(start 0.7874 0.4064)
			(end -0.7874 0.4064)
			(stroke
				(width 0.1524)
				(type default)
			)
			(layer "F.SilkS")
		)
		(fp_poly
			(pts
				(xy -0.508 0.2794) (xy -0.508 0.2286) (xy -0.635 0.2286) (xy -0.635 -0.254) (xy -0.5334 -0.254)
				(xy -0.5334 -0.2794) (xy 0.5334 -0.2794) (xy 0.5334 -0.254) (xy 0.635 -0.254) (xy 0.635 0.254) (xy 0.5334 0.254)
				(xy 0.5334 0.2794)
			)
			(stroke
				(width 0)
				(type default)
			)
			(fill no)
			(layer "F.CrtYd")
		)
		(pad "1" smd rect
			(at 0.40005 0)
			(size 0.4572 0.508)
			(layers "F.Cu" "F.Mask" "F.Paste")
			(net "PSU6_PS_KILL")
		)
		(pad "2" smd rect
			(at -0.40005 0)
			(size 0.4572 0.508)
			(layers "F.Cu" "F.Mask" "F.Paste")
			(net "GND")
		)
	)
	(footprint ""
		(layer "F.Cu")
		(at 30.45968 -83.330034)
		(property "Reference" "J1"
			(at 7.517892 2.350516 0)
			(unlocked yes)
			(layer "F.SilkS")
			(effects
				(font
					(size 0.7874 0.5842)
					(thickness 0.1524)
				)
				(justify left)
			)
		)
		(property "Value" ""
			(at 0 0 0)
			(layer "F.Fab")
			(effects
				(font
					(size 1.27 1.27)
				)
			)
		)
		(duplicate_pad_numbers_are_jumpers no)
		(fp_line
			(start -2.135124 -4.560062)
			(end -2.135124 83.300062)
			(stroke
				(width 0.1524)
				(type default)
			)
			(layer "F.SilkS")
		)
		(fp_line
			(start -2.135124 83.300062)
			(end 7.215124 83.300062)
			(stroke
				(width 0.1524)
				(type default)
			)
			(layer "F.SilkS")
		)
		(fp_line
			(start 7.215124 -4.560062)
			(end -2.135124 -4.560062)
			(stroke
				(width 0.1524)
				(type default)
			)
			(layer "F.SilkS")
		)
		(fp_line
			(start 7.215124 83.300062)
			(end 7.215124 -4.560062)
			(stroke
				(width 0.1524)
				(type default)
			)
			(layer "F.SilkS")
		)
		(fp_poly
			(pts
				(xy -2.467864 0.208026) (xy -5.167884 -0.491998) (xy -5.167884 0.90805)
			)
			(stroke
				(width 0)
				(type default)
			)
			(fill yes)
			(layer "F.SilkS")
		)
		(fp_poly
			(pts
				(xy -2.28219 -0.127) (xy -4.98221 -0.827024) (xy -4.98221 0.573024)
			)
			(stroke
				(width 0)
				(type default)
			)
			(fill yes)
			(layer "B.SilkS")
		)
		(fp_poly
			(pts
				(xy -0.8636 -0.8636) (xy -0.8636 79.6036) (xy -0.8636 79.629) (xy 5.9436 79.629) (xy 5.9436 79.6036)
				(xy 5.9436 -0.8636) (xy 5.9436 -0.889) (xy -0.8636 -0.889)
			)
			(stroke
				(width 0)
				(type default)
			)
			(fill no)
			(layer "B.CrtYd")
		)
		(fp_rect
			(start -2.135124 -4.560062)
			(end 7.21487 83.300062)
			(stroke
				(width 0)
				(type default)
			)
			(fill no)
			(layer "F.CrtYd")
		)
		(fp_line
			(start -2.135124 -4.560062)
			(end 7.215124 -4.560062)
			(stroke
				(width 0.1)
				(type default)
			)
			(layer "F.Fab")
		)
		(fp_line
			(start -2.135124 83.300062)
			(end -2.135124 -4.560062)
			(stroke
				(width 0.1)
				(type default)
			)
			(layer "F.Fab")
		)
		(fp_line
			(start 7.215124 -4.560062)
			(end 7.215124 83.300062)
			(stroke
				(width 0.1)
				(type default)
			)
			(layer "F.Fab")
		)
		(fp_line
			(start 7.215124 83.300062)
			(end -2.135124 83.300062)
			(stroke
				(width 0.1)
				(type default)
			)
			(layer "F.Fab")
		)
		(fp_text user "1"
			(at -3.01625 -0.658368 0)
			(unlocked yes)
			(layer "F.SilkS")
			(effects
				(font
					(size 0.7874 0.5842)
					(thickness 0.1524)
				)
				(justify left)
			)
		)
		(fp_text user "32"
			(at -1.971802 79.99095 0)
			(unlocked yes)
			(layer "F.SilkS")
			(effects
				(font
					(size 0.7874 0.5842)
					(thickness 0.1524)
				)
				(justify left)
			)
		)
		(fp_text user "33"
			(at 7.57428 78.22184 0)
			(unlocked yes)
			(layer "F.SilkS")
			(effects
				(font
					(size 0.7874 0.5842)
					(thickness 0.1524)
				)
				(justify left)
			)
		)
		(fp_text user "64"
			(at 7.666736 -0.128016 0)
			(unlocked yes)
			(layer "F.SilkS")
			(effects
				(font
					(size 0.7874 0.5842)
					(thickness 0.1524)
				)
				(justify left)
			)
		)
		(fp_text user "32"
			(at -1.060958 79.574644 0)
			(unlocked yes)
			(layer "B.SilkS")
			(effects
				(font
					(size 0.7874 0.5842)
					(thickness 0.1524)
				)
				(justify left mirror)
			)
		)
		(fp_text user "1"
			(at -1.044448 -0.912622 0)
			(unlocked yes)
			(layer "B.SilkS")
			(effects
				(font
					(size 0.7874 0.5842)
					(thickness 0.1524)
				)
				(justify left mirror)
			)
		)
		(fp_text user "64"
			(at 5.82168 -1.531112 0)
			(unlocked yes)
			(layer "B.SilkS")
			(effects
				(font
					(size 0.7874 0.5842)
					(thickness 0.1524)
				)
				(justify left mirror)
			)
		)
		(fp_text user "33"
			(at 6.15696 80.823308 0)
			(unlocked yes)
			(layer "B.SilkS")
			(effects
				(font
					(size 0.7874 0.5842)
					(thickness 0.1524)
				)
				(justify left mirror)
			)
		)
		(pad "1" thru_hole rect
			(at 0 0 270)
			(size 1.6256 1.6256)
			(drill 1.1176)
			(layers "*.Cu" "*.Mask")
			(remove_unused_layers no)
			(net "P12V")
			(clearance 0)
			(padstack
				(mode front_inner_back)
				(layer "Inner"
					(shape circle)
					(size 1.6256 1.6256)
					(clearance 0)
				)
				(layer "B.Cu"
					(shape rect)
					(size 1.6256 1.6256)
					(clearance 0)
				)
			)
		)
		(pad "2" thru_hole circle
			(at 0 2.54 270)
			(size 1.6256 1.6256)
			(drill 1.1176)
			(layers "*.Cu" "*.Mask")
			(remove_unused_layers no)
			(net "P12V")
			(clearance 0)
		)
		(pad "3" thru_hole circle
			(at 0 5.08 270)
			(size 1.6256 1.6256)
			(drill 1.1176)
			(layers "*.Cu" "*.Mask")
			(remove_unused_layers no)
			(net "P12V")
			(clearance 0)
		)
		(pad "4" thru_hole circle
			(at 0 7.62 270)
			(size 1.6256 1.6256)
			(drill 1.1176)
			(layers "*.Cu" "*.Mask")
			(remove_unused_layers no)
			(net "P12V")
			(clearance 0)
		)
		(pad "5" thru_hole circle
			(at 0 10.16 270)
			(size 1.6256 1.6256)
			(drill 1.1176)
			(layers "*.Cu" "*.Mask")
			(remove_unused_layers no)
			(net "P12V")
			(clearance 0)
		)
		(pad "6" thru_hole circle
			(at 0 12.7 270)
			(size 1.6256 1.6256)
			(drill 1.1176)
			(layers "*.Cu" "*.Mask")
			(remove_unused_layers no)
			(net "P12V")
			(clearance 0)
		)
		(pad "7" thru_hole circle
			(at 0 15.24 270)
			(size 1.6256 1.6256)
			(drill 1.1176)
			(layers "*.Cu" "*.Mask")
			(remove_unused_layers no)
			(net "P12V")
			(clearance 0)
		)
		(pad "8" thru_hole circle
			(at 0 17.78 270)
			(size 1.6256 1.6256)
			(drill 1.1176)
			(layers "*.Cu" "*.Mask")
			(remove_unused_layers no)
			(net "P12V")
			(clearance 0)
		)
		(pad "9" thru_hole circle
			(at 0 20.32 270)
			(size 1.6256 1.6256)
			(drill 1.1176)
			(layers "*.Cu" "*.Mask")
			(remove_unused_layers no)
			(net "P12V")
			(clearance 0)
		)
		(pad "10" thru_hole circle
			(at 0 22.86 270)
			(size 1.6256 1.6256)
			(drill 1.1176)
			(layers "*.Cu" "*.Mask")
			(remove_unused_layers no)
			(net "P12V")
			(clearance 0)
		)
		(pad "11" thru_hole circle
			(at 0 25.4 270)
			(size 1.6256 1.6256)
			(drill 1.1176)
			(layers "*.Cu" "*.Mask")
			(remove_unused_layers no)
			(net "P12V")
			(clearance 0)
		)
		(pad "12" thru_hole circle
			(at 0 27.94 270)
			(size 1.6256 1.6256)
			(drill 1.1176)
			(layers "*.Cu" "*.Mask")
			(remove_unused_layers no)
			(net "P12V")
			(clearance 0)
		)
		(pad "13" thru_hole circle
			(at 0 30.48 270)
			(size 1.6256 1.6256)
			(drill 1.1176)
			(layers "*.Cu" "*.Mask")
			(remove_unused_layers no)
			(net "GND")
			(clearance 0)
		)
		(pad "14" thru_hole circle
			(at 0 33.02 270)
			(size 1.6256 1.6256)
			(drill 1.1176)
			(layers "*.Cu" "*.Mask")
			(remove_unused_layers no)
			(net "GND")
			(clearance 0)
		)
		(pad "15" thru_hole circle
			(at 0 35.56 270)
			(size 1.6256 1.6256)
			(drill 1.1176)
			(layers "*.Cu" "*.Mask")
			(remove_unused_layers no)
			(net "GND")
			(clearance 0)
		)
		(pad "16" thru_hole circle
			(at 0 38.1 270)
			(size 1.6256 1.6256)
			(drill 1.1176)
			(layers "*.Cu" "*.Mask")
			(remove_unused_layers no)
			(net "GND")
			(clearance 0)
		)
		(pad "17" thru_hole circle
			(at 0 40.64 270)
			(size 1.6256 1.6256)
			(drill 1.1176)
			(layers "*.Cu" "*.Mask")
			(remove_unused_layers no)
			(net "GND")
			(clearance 0)
		)
		(pad "18" thru_hole circle
			(at 0 43.18 270)
			(size 1.6256 1.6256)
			(drill 1.1176)
			(layers "*.Cu" "*.Mask")
			(remove_unused_layers no)
			(net "GND")
			(clearance 0)
		)
		(pad "19" thru_hole circle
			(at 0 45.72 270)
			(size 1.6256 1.6256)
			(drill 1.1176)
			(layers "*.Cu" "*.Mask")
			(remove_unused_layers no)
			(net "GND")
			(clearance 0)
		)
		(pad "20" thru_hole circle
			(at 0 48.26 270)
			(size 1.6256 1.6256)
			(drill 1.1176)
			(layers "*.Cu" "*.Mask")
			(remove_unused_layers no)
			(net "GND")
			(clearance 0)
		)
		(pad "21" thru_hole circle
			(at 0 50.8 270)
			(size 1.6256 1.6256)
			(drill 1.1176)
			(layers "*.Cu" "*.Mask")
			(remove_unused_layers no)
			(net "GND")
			(clearance 0)
		)
		(pad "22" thru_hole circle
			(at 0 53.34 270)
			(size 1.6256 1.6256)
			(drill 1.1176)
			(layers "*.Cu" "*.Mask")
			(remove_unused_layers no)
			(net "GND")
			(clearance 0)
		)
		(pad "23" thru_hole circle
			(at 0 55.88 270)
			(size 1.6256 1.6256)
			(drill 1.1176)
			(layers "*.Cu" "*.Mask")
			(remove_unused_layers no)
			(net "GND")
			(clearance 0)
		)
		(pad "24" thru_hole circle
			(at 0 58.42 270)
			(size 1.6256 1.6256)
			(drill 1.1176)
			(layers "*.Cu" "*.Mask")
			(remove_unused_layers no)
			(net "GND")
			(clearance 0)
		)
		(pad "25" thru_hole circle
			(at 0 60.96 270)
			(size 1.6256 1.6256)
			(drill 1.1176)
			(layers "*.Cu" "*.Mask")
			(remove_unused_layers no)
			(net "PHLOSS")
			(clearance 0)
		)
		(pad "26" thru_hole circle
			(at 0 63.5 270)
			(size 1.6256 1.6256)
			(drill 1.1176)
			(layers "*.Cu" "*.Mask")
			(remove_unused_layers no)
			(net "PSU1_REMOTE_N")
			(clearance 0)
		)
		(pad "27" thru_hole circle
			(at 0 66.04 270)
			(size 1.6256 1.6256)
			(drill 1.1176)
			(layers "*.Cu" "*.Mask")
			(remove_unused_layers no)
			(net "PSU1_AC_OK")
			(clearance 0)
		)
		(pad "28" thru_hole circle
			(at 0 68.58 270)
			(size 1.6256 1.6256)
			(drill 1.1176)
			(layers "*.Cu" "*.Mask")
			(remove_unused_layers no)
			(net "PSU1_CSAHRE")
			(clearance 0)
		)
		(pad "29" thru_hole circle
			(at 0 71.12 270)
			(size 1.6256 1.6256)
			(drill 1.1176)
			(layers "*.Cu" "*.Mask")
			(remove_unused_layers no)
			(net "PSU1_PS_ON_N")
			(clearance 0)
		)
		(pad "30" thru_hole circle
			(at 0 73.66 270)
			(size 1.6256 1.6256)
			(drill 1.1176)
			(layers "*.Cu" "*.Mask")
			(remove_unused_layers no)
			(net "PSU1_PS_KILL")
			(clearance 0)
		)
		(pad "31" thru_hole circle
			(at 0 76.2 270)
			(size 1.6256 1.6256)
			(drill 1.1176)
			(layers "*.Cu" "*.Mask")
			(remove_unused_layers no)
			(net "PSU1_RESET")
			(clearance 0)
		)
		(pad "32" thru_hole circle
			(at 0 78.74 270)
			(size 1.6256 1.6256)
			(drill 1.1176)
			(layers "*.Cu" "*.Mask")
			(remove_unused_layers no)
			(net "PSU_ALERT_N")
			(clearance 0)
		)
		(pad "33" thru_hole circle
			(at 5.08 78.74 270)
			(size 1.6256 1.6256)
			(drill 1.1176)
			(layers "*.Cu" "*.Mask")
			(remove_unused_layers no)
			(net "I2C_PSU1_SDA")
			(clearance 0)
		)
		(pad "34" thru_hole circle
			(at 5.08 76.2 270)
			(size 1.6256 1.6256)
			(drill 1.1176)
			(layers "*.Cu" "*.Mask")
			(remove_unused_layers no)
			(net "Net_430")
			(clearance 0)
		)
		(pad "35" thru_hole circle
			(at 5.08 73.66 270)
			(size 1.6256 1.6256)
			(drill 1.1176)
			(layers "*.Cu" "*.Mask")
			(remove_unused_layers no)
			(net "I2C_PSU1_SCL")
			(clearance 0)
		)
		(pad "36" thru_hole circle
			(at 5.08 71.12 270)
			(size 1.6256 1.6256)
			(drill 1.1176)
			(layers "*.Cu" "*.Mask")
			(remove_unused_layers no)
			(net "PSU1_RETURN")
			(clearance 0)
		)
		(pad "37" thru_hole circle
			(at 5.08 68.58 270)
			(size 1.6256 1.6256)
			(drill 1.1176)
			(layers "*.Cu" "*.Mask")
			(remove_unused_layers no)
			(net "PSU1_DC_OK")
			(clearance 0)
		)
		(pad "38" thru_hole circle
			(at 5.08 66.04 270)
			(size 1.6256 1.6256)
			(drill 1.1176)
			(layers "*.Cu" "*.Mask")
			(remove_unused_layers no)
			(net "PSU1_AD0")
			(clearance 0)
		)
		(pad "39" thru_hole circle
			(at 5.08 63.5 270)
			(size 1.6256 1.6256)
			(drill 1.1176)
			(layers "*.Cu" "*.Mask")
			(remove_unused_layers no)
			(net "P12V_STBY")
			(clearance 0)
		)
		(pad "40" thru_hole circle
			(at 5.08 60.96 270)
			(size 1.6256 1.6256)
			(drill 1.1176)
			(layers "*.Cu" "*.Mask")
			(remove_unused_layers no)
			(net "PSU1_REMOTE_P")
			(clearance 0)
		)
		(pad "41" thru_hole circle
			(at 5.08 58.42 270)
			(size 1.6256 1.6256)
			(drill 1.1176)
			(layers "*.Cu" "*.Mask")
			(remove_unused_layers no)
			(net "GND")
			(clearance 0)
		)
		(pad "42" thru_hole circle
			(at 5.08 55.88 270)
			(size 1.6256 1.6256)
			(drill 1.1176)
			(layers "*.Cu" "*.Mask")
			(remove_unused_layers no)
			(net "GND")
			(clearance 0)
		)
		(pad "43" thru_hole circle
			(at 5.08 53.34 270)
			(size 1.6256 1.6256)
			(drill 1.1176)
			(layers "*.Cu" "*.Mask")
			(remove_unused_layers no)
			(net "GND")
			(clearance 0)
		)
		(pad "44" thru_hole circle
			(at 5.08 50.8 270)
			(size 1.6256 1.6256)
			(drill 1.1176)
			(layers "*.Cu" "*.Mask")
			(remove_unused_layers no)
			(net "GND")
			(clearance 0)
		)
		(pad "45" thru_hole circle
			(at 5.08 48.26 270)
			(size 1.6256 1.6256)
			(drill 1.1176)
			(layers "*.Cu" "*.Mask")
			(remove_unused_layers no)
			(net "GND")
			(clearance 0)
		)
		(pad "46" thru_hole circle
			(at 5.08 45.72 270)
			(size 1.6256 1.6256)
			(drill 1.1176)
			(layers "*.Cu" "*.Mask")
			(remove_unused_layers no)
			(net "GND")
			(clearance 0)
		)
		(pad "47" thru_hole circle
			(at 5.08 43.18 270)
			(size 1.6256 1.6256)
			(drill 1.1176)
			(layers "*.Cu" "*.Mask")
			(remove_unused_layers no)
			(net "GND")
			(clearance 0)
		)
		(pad "48" thru_hole circle
			(at 5.08 40.64 270)
			(size 1.6256 1.6256)
			(drill 1.1176)
			(layers "*.Cu" "*.Mask")
			(remove_unused_layers no)
			(net "GND")
			(clearance 0)
		)
		(pad "49" thru_hole circle
			(at 5.08 38.1 270)
			(size 1.6256 1.6256)
			(drill 1.1176)
			(layers "*.Cu" "*.Mask")
			(remove_unused_layers no)
			(net "GND")
			(clearance 0)
		)
		(pad "50" thru_hole circle
			(at 5.08 35.56 270)
			(size 1.6256 1.6256)
			(drill 1.1176)
			(layers "*.Cu" "*.Mask")
			(remove_unused_layers no)
			(net "GND")
			(clearance 0)
		)
		(pad "51" thru_hole circle
			(at 5.08 33.02 270)
			(size 1.6256 1.6256)
			(drill 1.1176)
			(layers "*.Cu" "*.Mask")
			(remove_unused_layers no)
			(net "GND")
			(clearance 0)
		)
		(pad "52" thru_hole circle
			(at 5.08 30.48 270)
			(size 1.6256 1.6256)
			(drill 1.1176)
			(layers "*.Cu" "*.Mask")
			(remove_unused_layers no)
			(net "GND")
			(clearance 0)
		)
		(pad "53" thru_hole circle
			(at 5.08 27.94 270)
			(size 1.6256 1.6256)
			(drill 1.1176)
			(layers "*.Cu" "*.Mask")
			(remove_unused_layers no)
			(net "P12V")
			(clearance 0)
		)
		(pad "54" thru_hole circle
			(at 5.08 25.4 270)
			(size 1.6256 1.6256)
			(drill 1.1176)
			(layers "*.Cu" "*.Mask")
			(remove_unused_layers no)
			(net "P12V")
			(clearance 0)
		)
		(pad "55" thru_hole circle
			(at 5.08 22.86 270)
			(size 1.6256 1.6256)
			(drill 1.1176)
			(layers "*.Cu" "*.Mask")
			(remove_unused_layers no)
			(net "P12V")
			(clearance 0)
		)
		(pad "56" thru_hole circle
			(at 5.08 20.32 270)
			(size 1.6256 1.6256)
			(drill 1.1176)
			(layers "*.Cu" "*.Mask")
			(remove_unused_layers no)
			(net "P12V")
			(clearance 0)
		)
		(pad "57" thru_hole circle
			(at 5.08 17.78 270)
			(size 1.6256 1.6256)
			(drill 1.1176)
			(layers "*.Cu" "*.Mask")
			(remove_unused_layers no)
			(net "P12V")
			(clearance 0)
		)
		(pad "58" thru_hole circle
			(at 5.08 15.24 270)
			(size 1.6256 1.6256)
			(drill 1.1176)
			(layers "*.Cu" "*.Mask")
			(remove_unused_layers no)
			(net "P12V")
			(clearance 0)
		)
		(pad "59" thru_hole circle
			(at 5.08 12.7 270)
			(size 1.6256 1.6256)
			(drill 1.1176)
			(layers "*.Cu" "*.Mask")
			(remove_unused_layers no)
			(net "P12V")
			(clearance 0)
		)
		(pad "60" thru_hole circle
			(at 5.08 10.16 270)
			(size 1.6256 1.6256)
			(drill 1.1176)
			(layers "*.Cu" "*.Mask")
			(remove_unused_layers no)
			(net "P12V")
			(clearance 0)
		)
		(pad "61" thru_hole circle
			(at 5.08 7.62 270)
			(size 1.6256 1.6256)
			(drill 1.1176)
			(layers "*.Cu" "*.Mask")
			(remove_unused_layers no)
			(net "P12V")
			(clearance 0)
		)
		(pad "62" thru_hole circle
			(at 5.08 5.08 270)
			(size 1.6256 1.6256)
			(drill 1.1176)
			(layers "*.Cu" "*.Mask")
			(remove_unused_layers no)
			(net "P12V")
			(clearance 0)
		)
		(pad "63" thru_hole circle
			(at 5.08 2.54 270)
			(size 1.6256 1.6256)
			(drill 1.1176)
			(layers "*.Cu" "*.Mask")
			(remove_unused_layers no)
			(net "P12V")
			(clearance 0)
		)
		(pad "64" thru_hole circle
			(at 5.08 0 270)
			(size 1.6256 1.6256)
			(drill 1.1176)
			(layers "*.Cu" "*.Mask")
			(remove_unused_layers no)
			(net "P12V")
			(clearance 0)
		)
	)
	(footprint ""
		(layer "F.Cu")
		(at 77.999844 -341.250016)
		(property "Reference" "H5"
			(at -6.4516 -7.127748 0)
			(unlocked yes)
			(layer "F.SilkS")
			(effects
				(font
					(size 0.7874 0.5842)
					(thickness 0.1524)
				)
				(justify left)
			)
		)
		(property "Value" ""
			(at 0 0 0)
			(layer "F.Fab")
			(effects
				(font
					(size 1.27 1.27)
				)
			)
		)
		(duplicate_pad_numbers_are_jumpers no)
		(fp_circle
			(center 0 0)
			(end 7.999984 0)
			(stroke
				(width 0.1524)
				(type default)
			)
			(fill no)
			(layer "F.SilkS")
		)
		(fp_circle
			(center 0 0)
			(end 14.7066 0)
			(stroke
				(width 0.1524)
				(type default)
			)
			(fill no)
			(layer "B.SilkS")
		)
		(fp_poly
			(pts
				(arc
					(start 5.0038 0)
					(mid -5.0038 0)
					(end 5.0038 0)
				)
			)
			(stroke
				(width 0)
				(type default)
			)
			(fill no)
			(layer "F.CrtYd")
		)
		(pad "" np_thru_hole circle
			(at 0 0)
			(size 4.0132 4.0132)
			(drill 4.0132)
			(layers "*.Cu" "*.Mask")
			(clearance 0.381)
			(thermal_gap 0.381)
		)
		(pad "2" thru_hole circle
			(at 0 -3.50012)
			(size 0.762 0.762)
			(drill 0.5588)
			(layers "*.Cu" "*.Mask")
			(remove_unused_layers no)
			(net "GND")
			(clearance 0.1524)
			(thermal_gap 0.1524)
		)
		(pad "3" thru_hole circle
			(at -2.500122 -2.500122)
			(size 0.762 0.762)
			(drill 0.5588)
			(layers "*.Cu" "*.Mask")
			(remove_unused_layers no)
			(net "GND")
			(clearance 0.1524)
			(thermal_gap 0.1524)
		)
		(pad "4" thru_hole circle
			(at -3.50012 0)
			(size 0.762 0.762)
			(drill 0.5588)
			(layers "*.Cu" "*.Mask")
			(remove_unused_layers no)
			(net "GND")
			(clearance 0.1524)
			(thermal_gap 0.1524)
		)
		(pad "5" thru_hole circle
			(at -2.500122 2.500122)
			(size 0.762 0.762)
			(drill 0.5588)
			(layers "*.Cu" "*.Mask")
			(remove_unused_layers no)
			(net "GND")
			(clearance 0.1524)
			(thermal_gap 0.1524)
		)
		(pad "6" thru_hole circle
			(at 0 3.50012)
			(size 0.762 0.762)
			(drill 0.5588)
			(layers "*.Cu" "*.Mask")
			(remove_unused_layers no)
			(net "GND")
			(clearance 0.1524)
			(thermal_gap 0.1524)
		)
		(pad "7" thru_hole circle
			(at 2.500122 2.500122)
			(size 0.762 0.762)
			(drill 0.5588)
			(layers "*.Cu" "*.Mask")
			(remove_unused_layers no)
			(net "GND")
			(clearance 0.1524)
			(thermal_gap 0.1524)
		)
		(pad "8" thru_hole circle
			(at 3.50012 0)
			(size 0.762 0.762)
			(drill 0.5588)
			(layers "*.Cu" "*.Mask")
			(remove_unused_layers no)
			(net "GND")
			(clearance 0.1524)
			(thermal_gap 0.1524)
		)
		(pad "9" thru_hole circle
			(at 2.500122 -2.500122)
			(size 0.762 0.762)
			(drill 0.5588)
			(layers "*.Cu" "*.Mask")
			(remove_unused_layers no)
			(net "GND")
			(clearance 0.1524)
			(thermal_gap 0.1524)
		)
		(zone
			(layer "F.Cu")
			(hatch none 0.5)
			(connect_pads
				(clearance 0)
			)
			(min_thickness 0.25)
			(keepout
				(tracks not_allowed)
				(vias allowed)
				(pads allowed)
				(copperpour not_allowed)
				(footprints allowed)
			)
			(placement
				(enabled no)
				(sheetname "")
			)
			(fill
				(thermal_gap 0.5)
				(thermal_bridge_width 0.5)
				(island_removal_mode 0)
			)
			(polygon
				(pts
					(arc
						(start 77.999844 -349.251016)
						(mid 69.998844 -341.250016)
						(end 77.999844 -333.249016)
					)
					(arc
						(start 77.999844 -333.249016)
						(mid 79.434944 -334.684116)
						(end 77.999844 -336.119216)
					)
					(arc
						(start 77.999844 -336.119216)
						(mid 72.869044 -341.250016)
						(end 77.999844 -346.380816)
					)
					(arc
						(start 77.999844 -346.380816)
						(mid 79.434944 -347.815916)
						(end 77.999844 -349.251016)
					)
				)
			)
		)
		(zone
			(layer "F.Cu")
			(hatch none 0.5)
			(connect_pads
				(clearance 0)
			)
			(min_thickness 0.25)
			(keepout
				(tracks not_allowed)
				(vias allowed)
				(pads allowed)
				(copperpour not_allowed)
				(footprints allowed)
			)
			(placement
				(enabled no)
				(sheetname "")
			)
			(fill
				(thermal_gap 0.5)
				(thermal_bridge_width 0.5)
				(island_removal_mode 0)
			)
			(polygon
				(pts
					(arc
						(start 77.999844 -349.251016)
						(mid 86.000844 -341.250016)
						(end 77.999844 -333.249016)
					)
					(arc
						(start 77.999844 -333.249016)
						(mid 76.564744 -334.684116)
						(end 77.999844 -336.119216)
					)
					(arc
						(start 77.999844 -336.119216)
						(mid 83.130644 -341.250016)
						(end 77.999844 -346.380816)
					)
					(arc
						(start 77.999844 -346.380816)
						(mid 76.564744 -347.815916)
						(end 77.999844 -349.251016)
					)
				)
			)
		)
		(zone
			(layers "F.Cu" "B.Cu" "In1.Cu" "In2.Cu" "In3.Cu" "In4.Cu" "In5.Cu" "In6.Cu")
			(hatch none 0.5)
			(connect_pads
				(clearance 0)
			)
			(min_thickness 0.25)
			(keepout
				(tracks not_allowed)
				(vias allowed)
				(pads allowed)
				(copperpour not_allowed)
				(footprints allowed)
			)
			(placement
				(enabled no)
				(sheetname "")
			)
			(fill
				(thermal_gap 0.5)
				(thermal_bridge_width 0.5)
				(island_removal_mode 0)
			)
			(polygon
				(pts
					(arc
						(start 80.511904 -341.250016)
						(mid 75.487784 -341.250016)
						(end 80.511904 -341.250016)
					)
				)
			)
		)
	)
	(footprint ""
		(layer "F.Cu")
		(at 91.399868 -153.359866)
		(property "Reference" "H22"
			(at -5.1308 -5.23113 0)
			(unlocked yes)
			(layer "F.SilkS")
			(effects
				(font
					(size 0.7874 0.5842)
					(thickness 0.1524)
				)
				(justify left)
			)
		)
		(property "Value" ""
			(at 0 0 0)
			(layer "F.Fab")
			(effects
				(font
					(size 1.27 1.27)
				)
			)
		)
		(duplicate_pad_numbers_are_jumpers no)
		(fp_circle
			(center 0 0)
			(end 4.826 0)
			(stroke
				(width 0.1524)
				(type default)
			)
			(fill no)
			(layer "F.SilkS")
		)
		(fp_circle
			(center 0 0)
			(end 4.826 0)
			(stroke
				(width 0.1524)
				(type default)
			)
			(fill no)
			(layer "B.SilkS")
		)
		(fp_poly
			(pts
				(arc
					(start 0 4.0132)
					(mid 0 -4.0132)
					(end 0 4.0132)
				)
			)
			(stroke
				(width 0)
				(type default)
			)
			(fill no)
			(layer "F.CrtYd")
		)
		(pad "" np_thru_hole circle
			(at 0 0)
			(size 8.001 8.001)
			(drill 8.001)
			(layers "*.Cu" "*.Mask")
			(clearance 0.381)
			(thermal_gap 0.381)
		)
		(zone
			(layers "F.Cu" "B.Cu" "In1.Cu" "In2.Cu" "In3.Cu" "In4.Cu" "In5.Cu" "In6.Cu")
			(hatch none 0.5)
			(connect_pads
				(clearance 0)
			)
			(min_thickness 0.25)
			(keepout
				(tracks not_allowed)
				(vias allowed)
				(pads allowed)
				(copperpour not_allowed)
				(footprints allowed)
			)
			(placement
				(enabled no)
				(sheetname "")
			)
			(fill
				(thermal_gap 0.5)
				(thermal_bridge_width 0.5)
				(island_removal_mode 0)
			)
			(polygon
				(pts
					(arc
						(start 91.399868 -148.838666)
						(mid 91.399868 -157.881066)
						(end 91.399868 -148.838666)
					)
				)
			)
		)
	)
	(footprint ""
		(layer "F.Cu")
		(at 15.509748 -452.87819 180)
		(property "Reference" "R154"
			(at 1.36779 3.459226 0)
			(unlocked yes)
			(layer "F.SilkS")
			(effects
				(font
					(size 0.7874 0.5842)
					(thickness 0.1524)
				)
				(justify left)
			)
		)
		(property "Value" ""
			(at 0 0 180)
			(layer "F.Fab")
			(effects
				(font
					(size 1.27 1.27)
				)
			)
		)
		(duplicate_pad_numbers_are_jumpers no)
		(fp_line
			(start 0.7874 0.4064)
			(end -0.7874 0.4064)
			(stroke
				(width 0.1524)
				(type default)
			)
			(layer "F.SilkS")
		)
		(fp_line
			(start 0.7874 -0.4064)
			(end 0.7874 0.4064)
			(stroke
				(width 0.1524)
				(type default)
			)
			(layer "F.SilkS")
		)
		(fp_line
			(start -0.7874 0.4064)
			(end -0.7874 -0.4064)
			(stroke
				(width 0.1524)
				(type default)
			)
			(layer "F.SilkS")
		)
		(fp_line
			(start -0.7874 -0.4064)
			(end 0.7874 -0.4064)
			(stroke
				(width 0.1524)
				(type default)
			)
			(layer "F.SilkS")
		)
		(fp_poly
			(pts
				(xy -0.508 0.2794) (xy -0.508 0.2286) (xy -0.635 0.2286) (xy -0.635 -0.254) (xy -0.5334 -0.254)
				(xy -0.5334 -0.2794) (xy 0.5334 -0.2794) (xy 0.5334 -0.254) (xy 0.635 -0.254) (xy 0.635 0.254) (xy 0.5334 0.254)
				(xy 0.5334 0.2794)
			)
			(stroke
				(width 0)
				(type default)
			)
			(fill no)
			(layer "F.CrtYd")
		)
		(pad "1" smd rect
			(at 0.40005 0 180)
			(size 0.4572 0.508)
			(layers "F.Cu" "F.Mask" "F.Paste")
			(net "P12V")
		)
		(pad "2" smd rect
			(at -0.40005 0 180)
			(size 0.4572 0.508)
			(layers "F.Cu" "F.Mask" "F.Paste")
			(net "N42241895")
		)
	)
	(footprint ""
		(layer "F.Cu")
		(at 80.932782 -295.215564 180)
		(property "Reference" "R124"
			(at 1.303528 -1.245108 0)
			(unlocked yes)
			(layer "F.SilkS")
			(effects
				(font
					(size 0.7874 0.5842)
					(thickness 0.1524)
				)
				(justify left)
			)
		)
		(property "Value" ""
			(at 0 0 180)
			(layer "F.Fab")
			(effects
				(font
					(size 1.27 1.27)
				)
			)
		)
		(duplicate_pad_numbers_are_jumpers no)
		(fp_line
			(start 0.7874 0.4064)
			(end -0.7874 0.4064)
			(stroke
				(width 0.1524)
				(type default)
			)
			(layer "F.SilkS")
		)
		(fp_line
			(start 0.7874 -0.4064)
			(end 0.7874 0.4064)
			(stroke
				(width 0.1524)
				(type default)
			)
			(layer "F.SilkS")
		)
		(fp_line
			(start -0.7874 0.4064)
			(end -0.7874 -0.4064)
			(stroke
				(width 0.1524)
				(type default)
			)
			(layer "F.SilkS")
		)
		(fp_line
			(start -0.7874 -0.4064)
			(end 0.7874 -0.4064)
			(stroke
				(width 0.1524)
				(type default)
			)
			(layer "F.SilkS")
		)
		(fp_poly
			(pts
				(xy -0.508 0.2794) (xy -0.508 0.2286) (xy -0.635 0.2286) (xy -0.635 -0.254) (xy -0.5334 -0.254)
				(xy -0.5334 -0.2794) (xy 0.5334 -0.2794) (xy 0.5334 -0.254) (xy 0.635 -0.254) (xy 0.635 0.254) (xy 0.5334 0.254)
				(xy 0.5334 0.2794)
			)
			(stroke
				(width 0)
				(type default)
			)
			(fill no)
			(layer "F.CrtYd")
		)
		(pad "1" smd rect
			(at 0.40005 0 180)
			(size 0.4572 0.508)
			(layers "F.Cu" "F.Mask" "F.Paste")
			(net "PSU4_REMOTE_R2_N")
		)
		(pad "2" smd rect
			(at -0.40005 0 180)
			(size 0.4572 0.508)
			(layers "F.Cu" "F.Mask" "F.Paste")
			(net "GND")
		)
	)
	(footprint ""
		(layer "F.Cu")
		(at 25.997662 -7.19328)
		(property "Reference" "R62"
			(at -3.764788 0.113792 0)
			(unlocked yes)
			(layer "F.SilkS")
			(effects
				(font
					(size 0.7874 0.5842)
					(thickness 0.1524)
				)
				(justify left)
			)
		)
		(property "Value" ""
			(at 0 0 0)
			(layer "F.Fab")
			(effects
				(font
					(size 1.27 1.27)
				)
			)
		)
		(duplicate_pad_numbers_are_jumpers no)
		(fp_line
			(start -0.7874 -0.4064)
			(end 0.7874 -0.4064)
			(stroke
				(width 0.1524)
				(type default)
			)
			(layer "F.SilkS")
		)
		(fp_line
			(start -0.7874 0.4064)
			(end -0.7874 -0.4064)
			(stroke
				(width 0.1524)
				(type default)
			)
			(layer "F.SilkS")
		)
		(fp_line
			(start 0.7874 -0.4064)
			(end 0.7874 0.4064)
			(stroke
				(width 0.1524)
				(type default)
			)
			(layer "F.SilkS")
		)
		(fp_line
			(start 0.7874 0.4064)
			(end -0.7874 0.4064)
			(stroke
				(width 0.1524)
				(type default)
			)
			(layer "F.SilkS")
		)
		(fp_poly
			(pts
				(xy -0.508 0.2794) (xy -0.508 0.2286) (xy -0.635 0.2286) (xy -0.635 -0.254) (xy -0.5334 -0.254)
				(xy -0.5334 -0.2794) (xy 0.5334 -0.2794) (xy 0.5334 -0.254) (xy 0.635 -0.254) (xy 0.635 0.254) (xy 0.5334 0.254)
				(xy 0.5334 0.2794)
			)
			(stroke
				(width 0)
				(type default)
			)
			(fill no)
			(layer "F.CrtYd")
		)
		(pad "1" smd rect
			(at 0.40005 0)
			(size 0.4572 0.508)
			(layers "F.Cu" "F.Mask" "F.Paste")
			(net "PSU1_PS_KILL")
		)
		(pad "2" smd rect
			(at -0.40005 0)
			(size 0.4572 0.508)
			(layers "F.Cu" "F.Mask" "F.Paste")
			(net "P12V_STBY")
		)
	)
	(footprint ""
		(layer "F.Cu")
		(at 25.976072 -6.147562)
		(property "Reference" "R64"
			(at -3.764788 0.113792 0)
			(unlocked yes)
			(layer "F.SilkS")
			(effects
				(font
					(size 0.7874 0.5842)
					(thickness 0.1524)
				)
				(justify left)
			)
		)
		(property "Value" ""
			(at 0 0 0)
			(layer "F.Fab")
			(effects
				(font
					(size 1.27 1.27)
				)
			)
		)
		(duplicate_pad_numbers_are_jumpers no)
		(fp_line
			(start -0.7874 -0.4064)
			(end 0.7874 -0.4064)
			(stroke
				(width 0.1524)
				(type default)
			)
			(layer "F.SilkS")
		)
		(fp_line
			(start -0.7874 0.4064)
			(end -0.7874 -0.4064)
			(stroke
				(width 0.1524)
				(type default)
			)
			(layer "F.SilkS")
		)
		(fp_line
			(start 0.7874 -0.4064)
			(end 0.7874 0.4064)
			(stroke
				(width 0.1524)
				(type default)
			)
			(layer "F.SilkS")
		)
		(fp_line
			(start 0.7874 0.4064)
			(end -0.7874 0.4064)
			(stroke
				(width 0.1524)
				(type default)
			)
			(layer "F.SilkS")
		)
		(fp_poly
			(pts
				(xy -0.508 0.2794) (xy -0.508 0.2286) (xy -0.635 0.2286) (xy -0.635 -0.254) (xy -0.5334 -0.254)
				(xy -0.5334 -0.2794) (xy 0.5334 -0.2794) (xy 0.5334 -0.254) (xy 0.635 -0.254) (xy 0.635 0.254) (xy 0.5334 0.254)
				(xy 0.5334 0.2794)
			)
			(stroke
				(width 0)
				(type default)
			)
			(fill no)
			(layer "F.CrtYd")
		)
		(pad "1" smd rect
			(at 0.40005 0)
			(size 0.4572 0.508)
			(layers "F.Cu" "F.Mask" "F.Paste")
			(net "PSU1_RESET")
		)
		(pad "2" smd rect
			(at -0.40005 0)
			(size 0.4572 0.508)
			(layers "F.Cu" "F.Mask" "F.Paste")
			(net "P12V_STBY")
		)
	)
	(footprint ""
		(layer "F.Cu")
		(at 45.911008 -261.777988 180)
		(property "Reference" "R104"
			(at 4.5974 0.054356 0)
			(unlocked yes)
			(layer "F.SilkS")
			(effects
				(font
					(size 0.7874 0.5842)
					(thickness 0.1524)
				)
				(justify left)
			)
		)
		(property "Value" ""
			(at 0 0 180)
			(layer "F.Fab")
			(effects
				(font
					(size 1.27 1.27)
				)
			)
		)
		(duplicate_pad_numbers_are_jumpers no)
		(fp_line
			(start 0.7874 0.4064)
			(end -0.7874 0.4064)
			(stroke
				(width 0.1524)
				(type default)
			)
			(layer "F.SilkS")
		)
		(fp_line
			(start 0.7874 -0.4064)
			(end 0.7874 0.4064)
			(stroke
				(width 0.1524)
				(type default)
			)
			(layer "F.SilkS")
		)
		(fp_line
			(start -0.7874 0.4064)
			(end -0.7874 -0.4064)
			(stroke
				(width 0.1524)
				(type default)
			)
			(layer "F.SilkS")
		)
		(fp_line
			(start -0.7874 -0.4064)
			(end 0.7874 -0.4064)
			(stroke
				(width 0.1524)
				(type default)
			)
			(layer "F.SilkS")
		)
		(fp_poly
			(pts
				(xy -0.508 0.2794) (xy -0.508 0.2286) (xy -0.635 0.2286) (xy -0.635 -0.254) (xy -0.5334 -0.254)
				(xy -0.5334 -0.2794) (xy 0.5334 -0.2794) (xy 0.5334 -0.254) (xy 0.635 -0.254) (xy 0.635 0.254) (xy 0.5334 0.254)
				(xy 0.5334 0.2794)
			)
			(stroke
				(width 0)
				(type default)
			)
			(fill no)
			(layer "F.CrtYd")
		)
		(pad "1" smd rect
			(at 0.40005 0 180)
			(size 0.4572 0.508)
			(layers "F.Cu" "F.Mask" "F.Paste")
			(net "PSU5_REMOTE_R_P")
		)
		(pad "2" smd rect
			(at -0.40005 0 180)
			(size 0.4572 0.508)
			(layers "F.Cu" "F.Mask" "F.Paste")
			(net "P12V")
		)
	)
	(footprint ""
		(layer "F.Cu")
		(at 27.05481 -11.75639 180)
		(property "Reference" "R49"
			(at 3.972306 0.169926 0)
			(unlocked yes)
			(layer "F.SilkS")
			(effects
				(font
					(size 0.7874 0.5842)
					(thickness 0.1524)
				)
				(justify left)
			)
		)
		(property "Value" ""
			(at 0 0 180)
			(layer "F.Fab")
			(effects
				(font
					(size 1.27 1.27)
				)
			)
		)
		(duplicate_pad_numbers_are_jumpers no)
		(fp_line
			(start 0.7874 0.4064)
			(end -0.7874 0.4064)
			(stroke
				(width 0.1524)
				(type default)
			)
			(layer "F.SilkS")
		)
		(fp_line
			(start 0.7874 -0.4064)
			(end 0.7874 0.4064)
			(stroke
				(width 0.1524)
				(type default)
			)
			(layer "F.SilkS")
		)
		(fp_line
			(start -0.7874 0.4064)
			(end -0.7874 -0.4064)
			(stroke
				(width 0.1524)
				(type default)
			)
			(layer "F.SilkS")
		)
		(fp_line
			(start -0.7874 -0.4064)
			(end 0.7874 -0.4064)
			(stroke
				(width 0.1524)
				(type default)
			)
			(layer "F.SilkS")
		)
		(fp_poly
			(pts
				(xy -0.508 0.2794) (xy -0.508 0.2286) (xy -0.635 0.2286) (xy -0.635 -0.254) (xy -0.5334 -0.254)
				(xy -0.5334 -0.2794) (xy 0.5334 -0.2794) (xy 0.5334 -0.254) (xy 0.635 -0.254) (xy 0.635 0.254) (xy 0.5334 0.254)
				(xy 0.5334 0.2794)
			)
			(stroke
				(width 0)
				(type default)
			)
			(fill no)
			(layer "F.CrtYd")
		)
		(pad "1" smd rect
			(at 0.40005 0 180)
			(size 0.4572 0.508)
			(layers "F.Cu" "F.Mask" "F.Paste")
			(net "GND")
		)
		(pad "2" smd rect
			(at -0.40005 0 180)
			(size 0.4572 0.508)
			(layers "F.Cu" "F.Mask" "F.Paste")
			(net "PSU1_PS_ON_N")
		)
	)
	(footprint ""
		(layer "F.Cu")
		(at 25.931622 -95.65132)
		(property "Reference" "R47"
			(at -4.080256 -0.075692 0)
			(unlocked yes)
			(layer "F.SilkS")
			(effects
				(font
					(size 0.7874 0.5842)
					(thickness 0.1524)
				)
				(justify left)
			)
		)
		(property "Value" ""
			(at 0 0 0)
			(layer "F.Fab")
			(effects
				(font
					(size 1.27 1.27)
				)
			)
		)
		(duplicate_pad_numbers_are_jumpers no)
		(fp_line
			(start -0.7874 -0.4064)
			(end 0.7874 -0.4064)
			(stroke
				(width 0.1524)
				(type default)
			)
			(layer "F.SilkS")
		)
		(fp_line
			(start -0.7874 0.4064)
			(end -0.7874 -0.4064)
			(stroke
				(width 0.1524)
				(type default)
			)
			(layer "F.SilkS")
		)
		(fp_line
			(start 0.7874 -0.4064)
			(end 0.7874 0.4064)
			(stroke
				(width 0.1524)
				(type default)
			)
			(layer "F.SilkS")
		)
		(fp_line
			(start 0.7874 0.4064)
			(end -0.7874 0.4064)
			(stroke
				(width 0.1524)
				(type default)
			)
			(layer "F.SilkS")
		)
		(fp_poly
			(pts
				(xy -0.508 0.2794) (xy -0.508 0.2286) (xy -0.635 0.2286) (xy -0.635 -0.254) (xy -0.5334 -0.254)
				(xy -0.5334 -0.2794) (xy 0.5334 -0.2794) (xy 0.5334 -0.254) (xy 0.635 -0.254) (xy 0.635 0.254) (xy 0.5334 0.254)
				(xy 0.5334 0.2794)
			)
			(stroke
				(width 0)
				(type default)
			)
			(fill no)
			(layer "F.CrtYd")
		)
		(pad "1" smd rect
			(at 0.40005 0)
			(size 0.4572 0.508)
			(layers "F.Cu" "F.Mask" "F.Paste")
			(net "PSU2_RESET")
		)
		(pad "2" smd rect
			(at -0.40005 0)
			(size 0.4572 0.508)
			(layers "F.Cu" "F.Mask" "F.Paste")
			(net "GND")
		)
	)
	(footprint ""
		(layer "F.Cu")
		(at 27.640026 -462.229962 -90)
		(property "Reference" "R101"
			(at -1.561592 0.00381 90)
			(unlocked yes)
			(layer "F.SilkS")
			(effects
				(font
					(size 0.7874 0.5842)
					(thickness 0.1524)
				)
				(justify left)
			)
		)
		(property "Value" ""
			(at 0 0 270)
			(layer "F.Fab")
			(effects
				(font
					(size 1.27 1.27)
				)
			)
		)
		(duplicate_pad_numbers_are_jumpers no)
		(fp_line
			(start -0.7874 0.4064)
			(end -0.7874 -0.4064)
			(stroke
				(width 0.1524)
				(type default)
			)
			(layer "F.SilkS")
		)
		(fp_line
			(start 0.7874 0.4064)
			(end -0.7874 0.4064)
			(stroke
				(width 0.1524)
				(type default)
			)
			(layer "F.SilkS")
		)
		(fp_line
			(start -0.7874 -0.4064)
			(end 0.7874 -0.4064)
			(stroke
				(width 0.1524)
				(type default)
			)
			(layer "F.SilkS")
		)
		(fp_line
			(start 0.7874 -0.4064)
			(end 0.7874 0.4064)
			(stroke
				(width 0.1524)
				(type default)
			)
			(layer "F.SilkS")
		)
		(fp_poly
			(pts
				(xy -0.508 0.2794) (xy -0.508 0.2286) (xy -0.635 0.2286) (xy -0.635 -0.254) (xy -0.5334 -0.254)
				(xy -0.5334 -0.2794) (xy 0.5334 -0.2794) (xy 0.5334 -0.254) (xy 0.635 -0.254) (xy 0.635 0.254) (xy 0.5334 0.254)
				(xy 0.5334 0.2794)
			)
			(stroke
				(width 0)
				(type default)
			)
			(fill no)
			(layer "F.CrtYd")
		)
		(pad "1" smd rect
			(at 0.40005 0 270)
			(size 0.4572 0.508)
			(layers "F.Cu" "F.Mask" "F.Paste")
			(net "PSU6_REMOTE_N")
		)
		(pad "2" smd rect
			(at -0.40005 0 270)
			(size 0.4572 0.508)
			(layers "F.Cu" "F.Mask" "F.Paste")
			(net "PSU6_REMOTE_R_N")
		)
	)
	(footprint ""
		(layer "F.Cu")
		(at 6.448806 -261.670546)
		(property "Reference" "J26"
			(at 6.660642 8.995918 90)
			(unlocked yes)
			(layer "F.SilkS")
			(effects
				(font
					(size 0.7874 0.5842)
					(thickness 0.1524)
				)
				(justify left)
			)
		)
		(property "Value" ""
			(at 0 0 0)
			(layer "F.Fab")
			(effects
				(font
					(size 1.27 1.27)
				)
			)
		)
		(duplicate_pad_numbers_are_jumpers no)
		(fp_line
			(start -9.400032 -5.999988)
			(end -9.400032 89.229946)
			(stroke
				(width 0.1524)
				(type default)
			)
			(layer "F.SilkS")
		)
		(fp_line
			(start -9.400032 89.229946)
			(end 5.649976 89.229946)
			(stroke
				(width 0.1524)
				(type default)
			)
			(layer "F.SilkS")
		)
		(fp_line
			(start -6.400038 -2.999994)
			(end 2.649982 -2.999994)
			(stroke
				(width 0.1524)
				(type default)
			)
			(layer "F.SilkS")
		)
		(fp_line
			(start -6.400038 86.229952)
			(end -6.400038 -2.999994)
			(stroke
				(width 0.1524)
				(type default)
			)
			(layer "F.SilkS")
		)
		(fp_line
			(start -2.265172 86.229952)
			(end -6.400038 86.229952)
			(stroke
				(width 0.1524)
				(type default)
			)
			(layer "F.SilkS")
		)
		(fp_line
			(start 2.649982 -2.999994)
			(end 2.649982 86.229952)
			(stroke
				(width 0.1524)
				(type default)
			)
			(layer "F.SilkS")
		)
		(fp_line
			(start 2.649982 86.229952)
			(end -0.334772 86.229952)
			(stroke
				(width 0.1524)
				(type default)
			)
			(layer "F.SilkS")
		)
		(fp_line
			(start 5.649976 -5.999988)
			(end -9.400032 -5.999988)
			(stroke
				(width 0.1524)
				(type default)
			)
			(layer "F.SilkS")
		)
		(fp_line
			(start 5.649976 89.229946)
			(end 5.649976 -5.999988)
			(stroke
				(width 0.1524)
				(type default)
			)
			(layer "F.SilkS")
		)
		(fp_poly
			(pts
				(xy -0.360426 -0.83439) (xy -0.60325 -2.871724) (xy -1.941322 -2.142236)
			)
			(stroke
				(width 0)
				(type default)
			)
			(fill yes)
			(layer "F.SilkS")
		)
		(fp_line
			(start -9.400032 -5.999988)
			(end -9.400032 89.229946)
			(stroke
				(width 0.1524)
				(type default)
			)
			(layer "B.SilkS")
		)
		(fp_line
			(start -9.400032 89.229946)
			(end 5.649976 89.229946)
			(stroke
				(width 0.1524)
				(type default)
			)
			(layer "B.SilkS")
		)
		(fp_line
			(start -6.400038 -2.999994)
			(end 2.649982 -2.999994)
			(stroke
				(width 0.1524)
				(type default)
			)
			(layer "B.SilkS")
		)
		(fp_line
			(start -6.400038 86.229952)
			(end -6.400038 -2.999994)
			(stroke
				(width 0.1524)
				(type default)
			)
			(layer "B.SilkS")
		)
		(fp_line
			(start -2.265172 86.229952)
			(end -6.400038 86.229952)
			(stroke
				(width 0.1524)
				(type default)
			)
			(layer "B.SilkS")
		)
		(fp_line
			(start 2.649982 -2.999994)
			(end 2.649982 86.229952)
			(stroke
				(width 0.1524)
				(type default)
			)
			(layer "B.SilkS")
		)
		(fp_line
			(start 2.649982 86.229952)
			(end -0.334772 86.229952)
			(stroke
				(width 0.1524)
				(type default)
			)
			(layer "B.SilkS")
		)
		(fp_line
			(start 5.649976 -5.999988)
			(end -9.400032 -5.999988)
			(stroke
				(width 0.1524)
				(type default)
			)
			(layer "B.SilkS")
		)
		(fp_line
			(start 5.649976 89.229946)
			(end 5.649976 -5.999988)
			(stroke
				(width 0.1524)
				(type default)
			)
			(layer "B.SilkS")
		)
		(fp_poly
			(pts
				(xy 0.048514 -2.26187) (xy 0.810514 -4.16687) (xy -0.713486 -4.16687)
			)
			(stroke
				(width 0)
				(type default)
			)
			(fill yes)
			(layer "B.SilkS")
		)
		(fp_poly
			(pts
				(xy 2.5654 -0.5842) (xy -5.08 -0.5842) (xy -5.08 86.2838) (xy 2.5654 86.2838)
			)
			(stroke
				(width 0)
				(type default)
			)
			(fill no)
			(layer "B.CrtYd")
		)
		(fp_poly
			(pts
				(xy -6.400038 -2.999994) (xy -6.400038 86.229952) (xy -1.624838 86.229952) (xy -1.624838 86.2838)
				(xy -0.964438 86.2838) (xy -0.964438 86.229952) (xy 2.649982 86.229952) (xy 2.649982 -2.999994)
			)
			(stroke
				(width 0)
				(type default)
			)
			(fill no)
			(layer "F.CrtYd")
		)
		(fp_line
			(start -6.400038 -2.999994)
			(end -6.400038 86.229952)
			(stroke
				(width 0.1)
				(type default)
			)
			(layer "F.Fab")
		)
		(fp_line
			(start -6.400038 86.229952)
			(end 2.649982 86.229952)
			(stroke
				(width 0.1)
				(type default)
			)
			(layer "F.Fab")
		)
		(fp_line
			(start 2.649982 -2.999994)
			(end -6.400038 -2.999994)
			(stroke
				(width 0.1)
				(type default)
			)
			(layer "F.Fab")
		)
		(fp_line
			(start 2.649982 86.229952)
			(end 2.649982 -2.999994)
			(stroke
				(width 0.1)
				(type default)
			)
			(layer "F.Fab")
		)
		(fp_text user "B82"
			(at -4.50723 88.688418 90)
			(unlocked yes)
			(layer "F.SilkS")
			(effects
				(font
					(size 0.7874 0.5842)
					(thickness 0.1524)
				)
				(justify left)
			)
		)
		(fp_text user "B2"
			(at -4.239006 -0.997966 90)
			(unlocked yes)
			(layer "F.SilkS")
			(effects
				(font
					(size 0.7874 0.5842)
					(thickness 0.1524)
				)
				(justify left)
			)
		)
		(fp_text user "B1"
			(at -2.661666 -1.078484 90)
			(unlocked yes)
			(layer "F.SilkS")
			(effects
				(font
					(size 0.7874 0.5842)
					(thickness 0.1524)
				)
				(justify left)
			)
		)
		(fp_text user "B81"
			(at -2.507234 88.688418 90)
			(unlocked yes)
			(layer "F.SilkS")
			(effects
				(font
					(size 0.7874 0.5842)
					(thickness 0.1524)
				)
				(justify left)
			)
		)
		(fp_text user "A81"
			(at -0.007366 88.688418 90)
			(unlocked yes)
			(layer "F.SilkS")
			(effects
				(font
					(size 0.7874 0.5842)
					(thickness 0.1524)
				)
				(justify left)
			)
		)
		(fp_text user "A1"
			(at 0.225298 -1.08204 90)
			(unlocked yes)
			(layer "F.SilkS")
			(effects
				(font
					(size 0.7874 0.5842)
					(thickness 0.1524)
				)
				(justify left)
			)
		)
		(fp_text user "A2"
			(at 1.592326 -1.11887 90)
			(unlocked yes)
			(layer "F.SilkS")
			(effects
				(font
					(size 0.7874 0.5842)
					(thickness 0.1524)
				)
				(justify left)
			)
		)
		(fp_text user "A82"
			(at 1.992884 88.688418 90)
			(unlocked yes)
			(layer "F.SilkS")
			(effects
				(font
					(size 0.7874 0.5842)
					(thickness 0.1524)
				)
				(justify left)
			)
		)
		(fp_text user "PRESS  FIT"
			(at 8.512556 30.283404 90)
			(unlocked yes)
			(layer "F.SilkS")
			(effects
				(font
					(size 1.905 1.4224)
					(thickness 0.1524)
				)
				(justify left)
			)
		)
		(fp_text user "B2"
			(at -4.534662 -0.56388 270)
			(unlocked yes)
			(layer "B.SilkS")
			(effects
				(font
					(size 0.7874 0.5842)
					(thickness 0.1524)
				)
				(justify left mirror)
			)
		)
		(fp_text user "B82"
			(at -4.462526 85.889592 270)
			(unlocked yes)
			(layer "B.SilkS")
			(effects
				(font
					(size 0.7874 0.5842)
					(thickness 0.1524)
				)
				(justify left mirror)
			)
		)
		(fp_text user "B81"
			(at -3.170174 84.489544 270)
			(unlocked yes)
			(layer "B.SilkS")
			(effects
				(font
					(size 0.7874 0.5842)
					(thickness 0.1524)
				)
				(justify left mirror)
			)
		)
		(fp_text user "B1"
			(at -2.408174 -0.867156 270)
			(unlocked yes)
			(layer "B.SilkS")
			(effects
				(font
					(size 0.7874 0.5842)
					(thickness 0.1524)
				)
				(justify left mirror)
			)
		)
		(fp_text user "A1"
			(at 0.091694 -0.867156 270)
			(unlocked yes)
			(layer "B.SilkS")
			(effects
				(font
					(size 0.7874 0.5842)
					(thickness 0.1524)
				)
				(justify left mirror)
			)
		)
		(fp_text user "A81"
			(at 0.663194 84.489544 270)
			(unlocked yes)
			(layer "B.SilkS")
			(effects
				(font
					(size 0.7874 0.5842)
					(thickness 0.1524)
				)
				(justify left mirror)
			)
		)
		(fp_text user "A2"
			(at 1.981962 -0.213106 270)
			(unlocked yes)
			(layer "B.SilkS")
			(effects
				(font
					(size 0.7874 0.5842)
					(thickness 0.1524)
				)
				(justify left mirror)
			)
		)
		(fp_text user "A82"
			(at 2.091944 86.013544 270)
			(unlocked yes)
			(layer "B.SilkS")
			(effects
				(font
					(size 0.7874 0.5842)
					(thickness 0.1524)
				)
				(justify left mirror)
			)
		)
		(fp_text user "PRESS  FIT"
			(at 8.267954 35.40633 270)
			(unlocked yes)
			(layer "B.SilkS")
			(effects
				(font
					(size 1.6002 1.1938)
					(thickness 0.000001)
				)
				(justify left mirror)
			)
		)
		(pad "" np_thru_hole circle
			(at -1.249934 11.649964 270)
			(size 2.413 2.413)
			(drill 2.413)
			(layers "*.Cu" "*.Mask")
			(clearance 0.381)
			(thermal_gap 0.381)
		)
		(pad "" np_thru_hole circle
			(at -1.249934 84.799932 270)
			(size 2.413 2.413)
			(drill 2.413)
			(layers "*.Cu" "*.Mask")
			(clearance 0.381)
			(thermal_gap 0.381)
		)
		(pad "A1" thru_hole rect
			(at 0 0 270)
			(size 1.016 1.016)
			(drill 0.7112)
			(layers "*.Cu" "*.Mask")
			(remove_unused_layers no)
			(net "GND")
			(clearance 0.1016)
			(thermal_gap 0.1016)
			(padstack
				(mode front_inner_back)
				(layer "Inner"
					(shape circle)
					(size 1.016 1.016)
					(clearance 0.1016)
				)
				(layer "B.Cu"
					(shape rect)
					(size 1.016 1.016)
					(clearance 0.1016)
				)
			)
		)
		(pad "A2" thru_hole circle
			(at 1.999996 0.999998 270)
			(size 1.016 1.016)
			(drill 0.7112)
			(layers "*.Cu" "*.Mask")
			(remove_unused_layers no)
			(net "T5_BLAD3_EN")
			(clearance 0.1016)
			(thermal_gap 0.1016)
		)
		(pad "A3" thru_hole circle
			(at 0 1.999996 270)
			(size 1.016 1.016)
			(drill 0.7112)
			(layers "*.Cu" "*.Mask")
			(remove_unused_layers no)
			(net "TP_T5_BLAD4_EN")
			(clearance 0.1016)
			(thermal_gap 0.1016)
		)
		(pad "A4" thru_hole circle
			(at 1.999996 2.999994 270)
			(size 1.016 1.016)
			(drill 0.7112)
			(layers "*.Cu" "*.Mask")
			(remove_unused_layers no)
			(net "GND")
			(clearance 0.1016)
			(thermal_gap 0.1016)
		)
		(pad "A5" thru_hole circle
			(at 0 3.999992 270)
			(size 1.016 1.016)
			(drill 0.7112)
			(layers "*.Cu" "*.Mask")
			(remove_unused_layers no)
			(net "T5_BLAD1_RXD")
			(clearance 0.1016)
			(thermal_gap 0.1016)
		)
		(pad "A6" thru_hole circle
			(at 1.999996 4.99999 270)
			(size 1.016 1.016)
			(drill 0.7112)
			(layers "*.Cu" "*.Mask")
			(remove_unused_layers no)
			(net "T5_BLAD1_TXD")
			(clearance 0.1016)
			(thermal_gap 0.1016)
		)
		(pad "A7" thru_hole circle
			(at 0 5.999988 270)
			(size 1.016 1.016)
			(drill 0.7112)
			(layers "*.Cu" "*.Mask")
			(remove_unused_layers no)
			(net "GND")
			(clearance 0.1016)
			(thermal_gap 0.1016)
		)
		(pad "A8" thru_hole circle
			(at 1.999996 6.999986 270)
			(size 1.016 1.016)
			(drill 0.7112)
			(layers "*.Cu" "*.Mask")
			(remove_unused_layers no)
			(net "T5_BLAD2_RXD")
			(clearance 0.1016)
			(thermal_gap 0.1016)
		)
		(pad "A9" thru_hole circle
			(at 0 7.999984 270)
			(size 1.016 1.016)
			(drill 0.7112)
			(layers "*.Cu" "*.Mask")
			(remove_unused_layers no)
			(net "T5_BLAD2_TXD")
			(clearance 0.1016)
			(thermal_gap 0.1016)
		)
		(pad "A10" thru_hole circle
			(at 1.999996 8.999982 270)
			(size 1.016 1.016)
			(drill 0.7112)
			(layers "*.Cu" "*.Mask")
			(remove_unused_layers no)
			(net "T5_BLAD3_RXD")
			(clearance 0.1016)
			(thermal_gap 0.1016)
		)
		(pad "A11" thru_hole circle
			(at 0 9.99998 270)
			(size 1.016 1.016)
			(drill 0.7112)
			(layers "*.Cu" "*.Mask")
			(remove_unused_layers no)
			(net "T5_BLAD3_TXD")
			(clearance 0.1016)
			(thermal_gap 0.1016)
		)
		(pad "A12" thru_hole circle
			(at 1.999996 12.999974 270)
			(size 1.016 1.016)
			(drill 0.7112)
			(layers "*.Cu" "*.Mask")
			(remove_unused_layers no)
			(net "T5_BLAD4_RXD")
			(clearance 0.1016)
			(thermal_gap 0.1016)
		)
		(pad "A13" thru_hole circle
			(at 0 13.999972 270)
			(size 1.016 1.016)
			(drill 0.7112)
			(layers "*.Cu" "*.Mask")
			(remove_unused_layers no)
			(net "T5_BLAD4_TXD")
			(clearance 0.1016)
			(thermal_gap 0.1016)
		)
		(pad "A14" thru_hole circle
			(at 1.999996 14.99997 270)
			(size 1.016 1.016)
			(drill 0.7112)
			(layers "*.Cu" "*.Mask")
			(remove_unused_layers no)
			(net "GND")
			(clearance 0.1016)
			(thermal_gap 0.1016)
		)
		(pad "A15" thru_hole circle
			(at 0 15.999968 270)
			(size 1.016 1.016)
			(drill 0.7112)
			(layers "*.Cu" "*.Mask")
			(remove_unused_layers no)
			(net "T3_BLAD1_EN")
			(clearance 0.1016)
			(thermal_gap 0.1016)
		)
		(pad "A16" thru_hole circle
			(at 1.999996 16.999966 270)
			(size 1.016 1.016)
			(drill 0.7112)
			(layers "*.Cu" "*.Mask")
			(remove_unused_layers no)
			(net "TP_T3_BLAD2_EN")
			(clearance 0.1016)
			(thermal_gap 0.1016)
		)
		(pad "A17" thru_hole circle
			(at 0 17.999964 270)
			(size 1.016 1.016)
			(drill 0.7112)
			(layers "*.Cu" "*.Mask")
			(remove_unused_layers no)
			(net "T3_BLAD3_EN")
			(clearance 0.1016)
			(thermal_gap 0.1016)
		)
		(pad "A18" thru_hole circle
			(at 1.999996 18.999962 270)
			(size 1.016 1.016)
			(drill 0.7112)
			(layers "*.Cu" "*.Mask")
			(remove_unused_layers no)
			(net "TP_T3_BLAD4_EN")
			(clearance 0.1016)
			(thermal_gap 0.1016)
		)
		(pad "A19" thru_hole circle
			(at 0 19.99996 270)
			(size 1.016 1.016)
			(drill 0.7112)
			(layers "*.Cu" "*.Mask")
			(remove_unused_layers no)
			(net "GND")
			(clearance 0.1016)
			(thermal_gap 0.1016)
		)
		(pad "A20" thru_hole circle
			(at 1.999996 20.999958 270)
			(size 1.016 1.016)
			(drill 0.7112)
			(layers "*.Cu" "*.Mask")
			(remove_unused_layers no)
			(net "T3_BLAD1_RXD")
			(clearance 0.1016)
			(thermal_gap 0.1016)
		)
		(pad "A21" thru_hole circle
			(at 0 21.999956 270)
			(size 1.016 1.016)
			(drill 0.7112)
			(layers "*.Cu" "*.Mask")
			(remove_unused_layers no)
			(net "T3_BLAD1_TXD")
			(clearance 0.1016)
			(thermal_gap 0.1016)
		)
		(pad "A22" thru_hole circle
			(at 1.999996 22.999954 270)
			(size 1.016 1.016)
			(drill 0.7112)
			(layers "*.Cu" "*.Mask")
			(remove_unused_layers no)
			(net "T3_BLAD2_RXD")
			(clearance 0.1016)
			(thermal_gap 0.1016)
		)
		(pad "A23" thru_hole circle
			(at 0 23.999952 270)
			(size 1.016 1.016)
			(drill 0.7112)
			(layers "*.Cu" "*.Mask")
			(remove_unused_layers no)
			(net "T3_BLAD2_TXD")
			(clearance 0.1016)
			(thermal_gap 0.1016)
		)
		(pad "A24" thru_hole circle
			(at 1.999996 24.99995 270)
			(size 1.016 1.016)
			(drill 0.7112)
			(layers "*.Cu" "*.Mask")
			(remove_unused_layers no)
			(net "GND")
			(clearance 0.1016)
			(thermal_gap 0.1016)
		)
		(pad "A25" thru_hole circle
			(at 0 25.999948 270)
			(size 1.016 1.016)
			(drill 0.7112)
			(layers "*.Cu" "*.Mask")
			(remove_unused_layers no)
			(net "T3_BLAD3_RXD")
			(clearance 0.1016)
			(thermal_gap 0.1016)
		)
		(pad "A26" thru_hole circle
			(at 1.999996 26.999946 270)
			(size 1.016 1.016)
			(drill 0.7112)
			(layers "*.Cu" "*.Mask")
			(remove_unused_layers no)
			(net "T3_BLAD3_TXD")
			(clearance 0.1016)
			(thermal_gap 0.1016)
		)
		(pad "A27" thru_hole circle
			(at 0 27.999944 270)
			(size 1.016 1.016)
			(drill 0.7112)
			(layers "*.Cu" "*.Mask")
			(remove_unused_layers no)
			(net "T3_BLAD4_RXD")
			(clearance 0.1016)
			(thermal_gap 0.1016)
		)
		(pad "A28" thru_hole circle
			(at 1.999996 28.999942 270)
			(size 1.016 1.016)
			(drill 0.7112)
			(layers "*.Cu" "*.Mask")
			(remove_unused_layers no)
			(net "T3_BLAD4_TXD")
			(clearance 0.1016)
			(thermal_gap 0.1016)
		)
		(pad "A29" thru_hole circle
			(at 0 29.99994 270)
			(size 1.016 1.016)
			(drill 0.7112)
			(layers "*.Cu" "*.Mask")
			(remove_unused_layers no)
			(net "GND")
			(clearance 0.1016)
			(thermal_gap 0.1016)
		)
		(pad "A30" thru_hole circle
			(at 1.999996 30.999938 270)
			(size 1.016 1.016)
			(drill 0.7112)
			(layers "*.Cu" "*.Mask")
			(remove_unused_layers no)
			(net "T1_BLAD1_EN")
			(clearance 0.1016)
			(thermal_gap 0.1016)
		)
		(pad "A31" thru_hole circle
			(at 0 31.999936 270)
			(size 1.016 1.016)
			(drill 0.7112)
			(layers "*.Cu" "*.Mask")
			(remove_unused_layers no)
			(net "T1_BLAD2_EN")
			(clearance 0.1016)
			(thermal_gap 0.1016)
		)
		(pad "A32" thru_hole circle
			(at 1.999996 32.999934 270)
			(size 1.016 1.016)
			(drill 0.7112)
			(layers "*.Cu" "*.Mask")
			(remove_unused_layers no)
			(net "T1_BLAD3_EN")
			(clearance 0.1016)
			(thermal_gap 0.1016)
		)
		(pad "A33" thru_hole circle
			(at 0 33.999932 270)
			(size 1.016 1.016)
			(drill 0.7112)
			(layers "*.Cu" "*.Mask")
			(remove_unused_layers no)
			(net "TP_T1_BLAD4_EN")
			(clearance 0.1016)
			(thermal_gap 0.1016)
		)
		(pad "A34" thru_hole circle
			(at 1.999996 34.99993 270)
			(size 1.016 1.016)
			(drill 0.7112)
			(layers "*.Cu" "*.Mask")
			(remove_unused_layers no)
			(net "GND")
			(clearance 0.1016)
			(thermal_gap 0.1016)
		)
		(pad "A35" thru_hole circle
			(at 0 35.999928 270)
			(size 1.016 1.016)
			(drill 0.7112)
			(layers "*.Cu" "*.Mask")
			(remove_unused_layers no)
			(net "T1_BLAD2_RXD")
			(clearance 0.1016)
			(thermal_gap 0.1016)
		)
		(pad "A36" thru_hole circle
			(at 1.999996 36.999926 270)
			(size 1.016 1.016)
			(drill 0.7112)
			(layers "*.Cu" "*.Mask")
			(remove_unused_layers no)
			(net "T1_BLAD2_TXD")
			(clearance 0.1016)
			(thermal_gap 0.1016)
		)
		(pad "A37" thru_hole circle
			(at 0 37.999924 270)
			(size 1.016 1.016)
			(drill 0.7112)
			(layers "*.Cu" "*.Mask")
			(remove_unused_layers no)
			(net "T1_BLAD3_RXD")
			(clearance 0.1016)
			(thermal_gap 0.1016)
		)
		(pad "A38" thru_hole circle
			(at 1.999996 38.999922 270)
			(size 1.016 1.016)
			(drill 0.7112)
			(layers "*.Cu" "*.Mask")
			(remove_unused_layers no)
			(net "T1_BLAD3_TXD")
			(clearance 0.1016)
			(thermal_gap 0.1016)
		)
		(pad "A39" thru_hole circle
			(at 0 39.99992 270)
			(size 1.016 1.016)
			(drill 0.7112)
			(layers "*.Cu" "*.Mask")
			(remove_unused_layers no)
			(net "GND")
			(clearance 0.1016)
			(thermal_gap 0.1016)
		)
		(pad "A40" thru_hole circle
			(at 1.999996 40.999918 270)
			(size 1.016 1.016)
			(drill 0.7112)
			(layers "*.Cu" "*.Mask")
			(remove_unused_layers no)
			(net "T1_BLAD4_RXD")
			(clearance 0.1016)
			(thermal_gap 0.1016)
		)
		(pad "A41" thru_hole circle
			(at 0 41.999916 270)
			(size 1.016 1.016)
			(drill 0.7112)
			(layers "*.Cu" "*.Mask")
			(remove_unused_layers no)
			(net "T1_BLAD4_TXD")
			(clearance 0.1016)
			(thermal_gap 0.1016)
		)
		(pad "A42" thru_hole circle
			(at 1.999996 42.999914 270)
			(size 1.016 1.016)
			(drill 0.7112)
			(layers "*.Cu" "*.Mask")
			(remove_unused_layers no)
			(net "T1_BLAD1_RXD")
			(clearance 0.1016)
			(thermal_gap 0.1016)
		)
		(pad "A43" thru_hole circle
			(at 0 43.999912 270)
			(size 1.016 1.016)
			(drill 0.7112)
			(layers "*.Cu" "*.Mask")
			(remove_unused_layers no)
			(net "T1_BLAD1_TXD")
			(clearance 0.1016)
			(thermal_gap 0.1016)
		)
		(pad "A44" thru_hole circle
			(at 1.999996 44.99991 270)
			(size 1.016 1.016)
			(drill 0.7112)
			(layers "*.Cu" "*.Mask")
			(remove_unused_layers no)
			(net "GND")
			(clearance 0.1016)
			(thermal_gap 0.1016)
		)
		(pad "A45" thru_hole circle
			(at 0 45.999908 270)
			(size 1.016 1.016)
			(drill 0.7112)
			(layers "*.Cu" "*.Mask")
			(remove_unused_layers no)
			(net "PSU1_DC_OK")
			(clearance 0.1016)
			(thermal_gap 0.1016)
		)
		(pad "A46" thru_hole circle
			(at 1.999996 46.999906 270)
			(size 1.016 1.016)
			(drill 0.7112)
			(layers "*.Cu" "*.Mask")
			(remove_unused_layers no)
			(net "PSU2_DC_OK")
			(clearance 0.1016)
			(thermal_gap 0.1016)
		)
		(pad "A47" thru_hole circle
			(at 0 47.999904 270)
			(size 1.016 1.016)
			(drill 0.7112)
			(layers "*.Cu" "*.Mask")
			(remove_unused_layers no)
			(net "PSU3_DC_OK")
			(clearance 0.1016)
			(thermal_gap 0.1016)
		)
		(pad "A48" thru_hole circle
			(at 1.999996 48.999902 270)
			(size 1.016 1.016)
			(drill 0.7112)
			(layers "*.Cu" "*.Mask")
			(remove_unused_layers no)
			(net "PSU4_DC_OK")
			(clearance 0.1016)
			(thermal_gap 0.1016)
		)
		(pad "A49" thru_hole circle
			(at 0 49.9999 270)
			(size 1.016 1.016)
			(drill 0.7112)
			(layers "*.Cu" "*.Mask")
			(remove_unused_layers no)
			(net "PSU5_DC_OK")
			(clearance 0.1016)
			(thermal_gap 0.1016)
		)
		(pad "A50" thru_hole circle
			(at 1.999996 50.999898 270)
			(size 1.016 1.016)
			(drill 0.7112)
			(layers "*.Cu" "*.Mask")
			(remove_unused_layers no)
			(net "PSU6_DC_OK")
			(clearance 0.1016)
			(thermal_gap 0.1016)
		)
		(pad "A51" thru_hole circle
			(at 0 51.999896 270)
			(size 1.016 1.016)
			(drill 0.7112)
			(layers "*.Cu" "*.Mask")
			(remove_unused_layers no)
			(net "GND")
			(clearance 0.1016)
			(thermal_gap 0.1016)
		)
		(pad "A52" thru_hole circle
			(at 1.999996 52.999894 270)
			(size 1.016 1.016)
			(drill 0.7112)
			(layers "*.Cu" "*.Mask")
			(remove_unused_layers no)
			(net "UART_RTS_P6_L_N")
			(clearance 0.1016)
			(thermal_gap 0.1016)
		)
		(pad "A53" thru_hole circle
			(at 0 53.999892 270)
			(size 1.016 1.016)
			(drill 0.7112)
			(layers "*.Cu" "*.Mask")
			(remove_unused_layers no)
			(net "UART_DSR_P6_L_N")
			(clearance 0.1016)
			(thermal_gap 0.1016)
		)
		(pad "A54" thru_hole circle
			(at 1.999996 54.99989 270)
			(size 1.016 1.016)
			(drill 0.7112)
			(layers "*.Cu" "*.Mask")
			(remove_unused_layers no)
			(net "UART_RX_P6_L")
			(clearance 0.1016)
			(thermal_gap 0.1016)
		)
		(pad "A55" thru_hole circle
			(at 0 55.999888 270)
			(size 1.016 1.016)
			(drill 0.7112)
			(layers "*.Cu" "*.Mask")
			(remove_unused_layers no)
			(net "UART_TX_P6_L")
			(clearance 0.1016)
			(thermal_gap 0.1016)
		)
		(pad "A56" thru_hole circle
			(at 1.999996 56.999886 270)
			(size 1.016 1.016)
			(drill 0.7112)
			(layers "*.Cu" "*.Mask")
			(remove_unused_layers no)
			(net "UART_DTR_P6_L_N")
			(clearance 0.1016)
			(thermal_gap 0.1016)
		)
		(pad "A57" thru_hole circle
			(at 0 57.999884 270)
			(size 1.016 1.016)
			(drill 0.7112)
			(layers "*.Cu" "*.Mask")
			(remove_unused_layers no)
			(net "UART_CTS_P6_L_N")
			(clearance 0.1016)
			(thermal_gap 0.1016)
		)
		(pad "A58" thru_hole circle
			(at 1.999996 59.000136 270)
			(size 1.016 1.016)
			(drill 0.7112)
			(layers "*.Cu" "*.Mask")
			(remove_unused_layers no)
			(net "UART_RI_P6_L_N")
			(clearance 0.1016)
			(thermal_gap 0.1016)
		)
		(pad "A59" thru_hole circle
			(at 0 59.99988 270)
			(size 1.016 1.016)
			(drill 0.7112)
			(layers "*.Cu" "*.Mask")
			(remove_unused_layers no)
			(net "GND")
			(clearance 0.1016)
			(thermal_gap 0.1016)
		)
		(pad "A60" thru_hole circle
			(at 1.999996 61.000132 270)
			(size 1.016 1.016)
			(drill 0.7112)
			(layers "*.Cu" "*.Mask")
			(remove_unused_layers no)
			(net "UART_RTS_P2_L_N")
			(clearance 0.1016)
			(thermal_gap 0.1016)
		)
		(pad "A61" thru_hole circle
			(at 0 61.999876 270)
			(size 1.016 1.016)
			(drill 0.7112)
			(layers "*.Cu" "*.Mask")
			(remove_unused_layers no)
			(net "UART_DSR_P2_L_N")
			(clearance 0.1016)
			(thermal_gap 0.1016)
		)
		(pad "A62" thru_hole circle
			(at 1.999996 63.000128 270)
			(size 1.016 1.016)
			(drill 0.7112)
			(layers "*.Cu" "*.Mask")
			(remove_unused_layers no)
			(net "UART_RX_P2_L")
			(clearance 0.1016)
			(thermal_gap 0.1016)
		)
		(pad "A63" thru_hole circle
			(at 0 63.999872 270)
			(size 1.016 1.016)
			(drill 0.7112)
			(layers "*.Cu" "*.Mask")
			(remove_unused_layers no)
			(net "UART_TX_P2_L")
			(clearance 0.1016)
			(thermal_gap 0.1016)
		)
		(pad "A64" thru_hole circle
			(at 1.999996 65.000124 270)
			(size 1.016 1.016)
			(drill 0.7112)
			(layers "*.Cu" "*.Mask")
			(remove_unused_layers no)
			(net "UART_DTR_P2_L_N")
			(clearance 0.1016)
			(thermal_gap 0.1016)
		)
		(pad "A65" thru_hole circle
			(at 0 65.999868 270)
			(size 1.016 1.016)
			(drill 0.7112)
			(layers "*.Cu" "*.Mask")
			(remove_unused_layers no)
			(net "UART_CTS_P2_L_N")
			(clearance 0.1016)
			(thermal_gap 0.1016)
		)
		(pad "A66" thru_hole circle
			(at 1.999996 67.00012 270)
			(size 1.016 1.016)
			(drill 0.7112)
			(layers "*.Cu" "*.Mask")
			(remove_unused_layers no)
			(net "GND")
			(clearance 0.1016)
			(thermal_gap 0.1016)
		)
		(pad "A67" thru_hole circle
			(at 0 67.999864 270)
			(size 1.016 1.016)
			(drill 0.7112)
			(layers "*.Cu" "*.Mask")
			(remove_unused_layers no)
			(net "Net_431")
			(clearance 0.1016)
			(thermal_gap 0.1016)
		)
		(pad "A68" thru_hole circle
			(at 1.999996 69.000116 270)
			(size 1.016 1.016)
			(drill 0.7112)
			(layers "*.Cu" "*.Mask")
			(remove_unused_layers no)
			(net "Net_435")
			(clearance 0.1016)
			(thermal_gap 0.1016)
		)
		(pad "A69" thru_hole circle
			(at 0 70.000114 270)
			(size 1.016 1.016)
			(drill 0.7112)
			(layers "*.Cu" "*.Mask")
			(remove_unused_layers no)
			(net "Net_434")
			(clearance 0.1016)
			(thermal_gap 0.1016)
		)
		(pad "A70" thru_hole circle
			(at 1.999996 71.000112 270)
			(size 1.016 1.016)
			(drill 0.7112)
			(layers "*.Cu" "*.Mask")
			(remove_unused_layers no)
			(net "GND61")
			(clearance 0.1016)
			(thermal_gap 0.1016)
		)
		(pad "A71" thru_hole circle
			(at 0 72.00011 270)
			(size 1.016 1.016)
			(drill 0.7112)
			(layers "*.Cu" "*.Mask")
			(remove_unused_layers no)
			(net "GND")
			(clearance 0.1016)
			(thermal_gap 0.1016)
		)
		(pad "A72" thru_hole circle
			(at 1.999996 73.000108 270)
			(size 1.016 1.016)
			(drill 0.7112)
			(layers "*.Cu" "*.Mask")
			(remove_unused_layers no)
			(net "LAN1_P1_P")
			(clearance 0.1016)
			(thermal_gap 0.1016)
		)
		(pad "A73" thru_hole circle
			(at 0 74.000106 270)
			(size 1.016 1.016)
			(drill 0.7112)
			(layers "*.Cu" "*.Mask")
			(remove_unused_layers no)
			(net "LAN1_P1_N")
			(clearance 0.1016)
			(thermal_gap 0.1016)
		)
		(pad "A74" thru_hole circle
			(at 1.999996 75.000104 270)
			(size 1.016 1.016)
			(drill 0.7112)
			(layers "*.Cu" "*.Mask")
			(remove_unused_layers no)
			(net "GND")
			(clearance 0.1016)
			(thermal_gap 0.1016)
		)
		(pad "A75" thru_hole circle
			(at 0 76.000102 270)
			(size 1.016 1.016)
			(drill 0.7112)
			(layers "*.Cu" "*.Mask")
			(remove_unused_layers no)
			(net "LAN1_P2_P")
			(clearance 0.1016)
			(thermal_gap 0.1016)
		)
		(pad "A76" thru_hole circle
			(at 1.999996 77.0001 270)
			(size 1.016 1.016)
			(drill 0.7112)
			(layers "*.Cu" "*.Mask")
			(remove_unused_layers no)
			(net "LAN1_P2_N")
			(clearance 0.1016)
			(thermal_gap 0.1016)
		)
		(pad "A77" thru_hole circle
			(at 0 78.000098 270)
			(size 1.016 1.016)
			(drill 0.7112)
			(layers "*.Cu" "*.Mask")
			(remove_unused_layers no)
			(net "GND")
			(clearance 0.1016)
			(thermal_gap 0.1016)
		)
		(pad "A78" thru_hole circle
			(at 1.999996 79.000096 270)
			(size 1.016 1.016)
			(drill 0.7112)
			(layers "*.Cu" "*.Mask")
			(remove_unused_layers no)
			(net "P12V")
			(clearance 0.1016)
			(thermal_gap 0.1016)
		)
		(pad "A79" thru_hole circle
			(at 0 80.000094 270)
			(size 1.016 1.016)
			(drill 0.7112)
			(layers "*.Cu" "*.Mask")
			(remove_unused_layers no)
			(net "P12V")
			(clearance 0.1016)
			(thermal_gap 0.1016)
		)
		(pad "A80" thru_hole circle
			(at 1.999996 81.000092 270)
			(size 1.016 1.016)
			(drill 0.7112)
			(layers "*.Cu" "*.Mask")
			(remove_unused_layers no)
			(net "P12V")
			(clearance 0.1016)
			(thermal_gap 0.1016)
		)
		(pad "A81" thru_hole circle
			(at 0 82.00009 270)
			(size 1.016 1.016)
			(drill 0.7112)
			(layers "*.Cu" "*.Mask")
			(remove_unused_layers no)
			(net "P12V")
			(clearance 0.1016)
			(thermal_gap 0.1016)
		)
		(pad "A82" thru_hole circle
			(at 1.999996 83.000088 270)
			(size 1.016 1.016)
			(drill 0.7112)
			(layers "*.Cu" "*.Mask")
			(remove_unused_layers no)
			(net "P12V")
			(clearance 0.1016)
			(thermal_gap 0.1016)
		)
		(pad "B1" thru_hole circle
			(at -2.499868 0 270)
			(size 1.016 1.016)
			(drill 0.7112)
			(layers "*.Cu" "*.Mask")
			(remove_unused_layers no)
			(net "GND")
			(clearance 0.1016)
			(thermal_gap 0.1016)
		)
		(pad "B2" thru_hole circle
			(at -4.499864 0.999998 270)
			(size 1.016 1.016)
			(drill 0.7112)
			(layers "*.Cu" "*.Mask")
			(remove_unused_layers no)
			(net "T6_BLAD2_RXD")
			(clearance 0.1016)
			(thermal_gap 0.1016)
		)
		(pad "B3" thru_hole circle
			(at -2.499868 1.999996 270)
			(size 1.016 1.016)
			(drill 0.7112)
			(layers "*.Cu" "*.Mask")
			(remove_unused_layers no)
			(net "T6_BLAD2_TXD")
			(clearance 0.1016)
			(thermal_gap 0.1016)
		)
		(pad "B4" thru_hole circle
			(at -4.499864 2.999994 270)
			(size 1.016 1.016)
			(drill 0.7112)
			(layers "*.Cu" "*.Mask")
			(remove_unused_layers no)
			(net "GND")
			(clearance 0.1016)
			(thermal_gap 0.1016)
		)
		(pad "B5" thru_hole circle
			(at -2.499868 3.999992 270)
			(size 1.016 1.016)
			(drill 0.7112)
			(layers "*.Cu" "*.Mask")
			(remove_unused_layers no)
			(net "T6_BLAD3_RXD")
			(clearance 0.1016)
			(thermal_gap 0.1016)
		)
		(pad "B6" thru_hole circle
			(at -4.499864 4.99999 270)
			(size 1.016 1.016)
			(drill 0.7112)
			(layers "*.Cu" "*.Mask")
			(remove_unused_layers no)
			(net "T6_BLAD3_TXD")
			(clearance 0.1016)
			(thermal_gap 0.1016)
		)
		(pad "B7" thru_hole circle
			(at -2.499868 5.999988 270)
			(size 1.016 1.016)
			(drill 0.7112)
			(layers "*.Cu" "*.Mask")
			(remove_unused_layers no)
			(net "T6_BLAD4_RXD")
			(clearance 0.1016)
			(thermal_gap 0.1016)
		)
		(pad "B8" thru_hole circle
			(at -4.499864 6.999986 270)
			(size 1.016 1.016)
			(drill 0.7112)
			(layers "*.Cu" "*.Mask")
			(remove_unused_layers no)
			(net "T6_BLAD4_TXD")
			(clearance 0.1016)
			(thermal_gap 0.1016)
		)
		(pad "B9" thru_hole circle
			(at -2.499868 7.999984 270)
			(size 1.016 1.016)
			(drill 0.7112)
			(layers "*.Cu" "*.Mask")
			(remove_unused_layers no)
			(net "GND")
			(clearance 0.1016)
			(thermal_gap 0.1016)
		)
		(pad "B10" thru_hole circle
			(at -4.499864 8.999982 270)
			(size 1.016 1.016)
			(drill 0.7112)
			(layers "*.Cu" "*.Mask")
			(remove_unused_layers no)
			(net "I2C_PSU2_SCL")
			(clearance 0.1016)
			(thermal_gap 0.1016)
		)
		(pad "B11" thru_hole circle
			(at -2.499868 9.99998 270)
			(size 1.016 1.016)
			(drill 0.7112)
			(layers "*.Cu" "*.Mask")
			(remove_unused_layers no)
			(net "I2C_PSU2_SDA")
			(clearance 0.1016)
			(thermal_gap 0.1016)
		)
		(pad "B12" thru_hole circle
			(at -4.499864 12.999974 270)
			(size 1.016 1.016)
			(drill 0.7112)
			(layers "*.Cu" "*.Mask")
			(remove_unused_layers no)
			(net "T4_BLAD1_EN")
			(clearance 0.1016)
			(thermal_gap 0.1016)
		)
		(pad "B13" thru_hole circle
			(at -2.499868 13.999972 270)
			(size 1.016 1.016)
			(drill 0.7112)
			(layers "*.Cu" "*.Mask")
			(remove_unused_layers no)
			(net "TP_T4_BLAD2_EN")
			(clearance 0.1016)
			(thermal_gap 0.1016)
		)
		(pad "B14" thru_hole circle
			(at -4.499864 14.99997 270)
			(size 1.016 1.016)
			(drill 0.7112)
			(layers "*.Cu" "*.Mask")
			(remove_unused_layers no)
			(net "T4_BLAD3_EN")
			(clearance 0.1016)
			(thermal_gap 0.1016)
		)
		(pad "B15" thru_hole circle
			(at -2.499868 15.999968 270)
			(size 1.016 1.016)
			(drill 0.7112)
			(layers "*.Cu" "*.Mask")
			(remove_unused_layers no)
			(net "TP_T4_BLAD4_EN")
			(clearance 0.1016)
			(thermal_gap 0.1016)
		)
		(pad "B16" thru_hole circle
			(at -4.499864 16.999966 270)
			(size 1.016 1.016)
			(drill 0.7112)
			(layers "*.Cu" "*.Mask")
			(remove_unused_layers no)
			(net "GND")
			(clearance 0.1016)
			(thermal_gap 0.1016)
		)
		(pad "B17" thru_hole circle
			(at -2.499868 17.999964 270)
			(size 1.016 1.016)
			(drill 0.7112)
			(layers "*.Cu" "*.Mask")
			(remove_unused_layers no)
			(net "T4_BLAD1_RXD")
			(clearance 0.1016)
			(thermal_gap 0.1016)
		)
		(pad "B18" thru_hole circle
			(at -4.499864 18.999962 270)
			(size 1.016 1.016)
			(drill 0.7112)
			(layers "*.Cu" "*.Mask")
			(remove_unused_layers no)
			(net "T4_BLAD1_TXD")
			(clearance 0.1016)
			(thermal_gap 0.1016)
		)
		(pad "B19" thru_hole circle
			(at -2.499868 19.99996 270)
			(size 1.016 1.016)
			(drill 0.7112)
			(layers "*.Cu" "*.Mask")
			(remove_unused_layers no)
			(net "T4_BLAD2_RXD")
			(clearance 0.1016)
			(thermal_gap 0.1016)
		)
		(pad "B20" thru_hole circle
			(at -4.499864 20.999958 270)
			(size 1.016 1.016)
			(drill 0.7112)
			(layers "*.Cu" "*.Mask")
			(remove_unused_layers no)
			(net "T4_BLAD2_TXD")
			(clearance 0.1016)
			(thermal_gap 0.1016)
		)
		(pad "B21" thru_hole circle
			(at -2.499868 21.999956 270)
			(size 1.016 1.016)
			(drill 0.7112)
			(layers "*.Cu" "*.Mask")
			(remove_unused_layers no)
			(net "GND")
			(clearance 0.1016)
			(thermal_gap 0.1016)
		)
		(pad "B22" thru_hole circle
			(at -4.499864 22.999954 270)
			(size 1.016 1.016)
			(drill 0.7112)
			(layers "*.Cu" "*.Mask")
			(remove_unused_layers no)
			(net "T4_BLAD3_RXD")
			(clearance 0.1016)
			(thermal_gap 0.1016)
		)
		(pad "B23" thru_hole circle
			(at -2.499868 23.999952 270)
			(size 1.016 1.016)
			(drill 0.7112)
			(layers "*.Cu" "*.Mask")
			(remove_unused_layers no)
			(net "T4_BLAD3_TXD")
			(clearance 0.1016)
			(thermal_gap 0.1016)
		)
		(pad "B24" thru_hole circle
			(at -4.499864 24.99995 270)
			(size 1.016 1.016)
			(drill 0.7112)
			(layers "*.Cu" "*.Mask")
			(remove_unused_layers no)
			(net "T4_BLAD4_RXD")
			(clearance 0.1016)
			(thermal_gap 0.1016)
		)
		(pad "B25" thru_hole circle
			(at -2.499868 25.999948 270)
			(size 1.016 1.016)
			(drill 0.7112)
			(layers "*.Cu" "*.Mask")
			(remove_unused_layers no)
			(net "T4_BLAD4_TXD")
			(clearance 0.1016)
			(thermal_gap 0.1016)
		)
		(pad "B26" thru_hole circle
			(at -4.499864 26.999946 270)
			(size 1.016 1.016)
			(drill 0.7112)
			(layers "*.Cu" "*.Mask")
			(remove_unused_layers no)
			(net "GND")
			(clearance 0.1016)
			(thermal_gap 0.1016)
		)
		(pad "B27" thru_hole circle
			(at -2.499868 27.999944 270)
			(size 1.016 1.016)
			(drill 0.7112)
			(layers "*.Cu" "*.Mask")
			(remove_unused_layers no)
			(net "T2_BLAD1_EN")
			(clearance 0.1016)
			(thermal_gap 0.1016)
		)
		(pad "B28" thru_hole circle
			(at -4.499864 28.999942 270)
			(size 1.016 1.016)
			(drill 0.7112)
			(layers "*.Cu" "*.Mask")
			(remove_unused_layers no)
			(net "TP_T2_BLAD2_EN")
			(clearance 0.1016)
			(thermal_gap 0.1016)
		)
		(pad "B29" thru_hole circle
			(at -2.499868 29.99994 270)
			(size 1.016 1.016)
			(drill 0.7112)
			(layers "*.Cu" "*.Mask")
			(remove_unused_layers no)
			(net "T2_BLAD3_EN")
			(clearance 0.1016)
			(thermal_gap 0.1016)
		)
		(pad "B30" thru_hole circle
			(at -4.499864 30.999938 270)
			(size 1.016 1.016)
			(drill 0.7112)
			(layers "*.Cu" "*.Mask")
			(remove_unused_layers no)
			(net "TP_T2_BLAD4_EN")
			(clearance 0.1016)
			(thermal_gap 0.1016)
		)
		(pad "B31" thru_hole circle
			(at -2.499868 31.999936 270)
			(size 1.016 1.016)
			(drill 0.7112)
			(layers "*.Cu" "*.Mask")
			(remove_unused_layers no)
			(net "GND")
			(clearance 0.1016)
			(thermal_gap 0.1016)
		)
		(pad "B32" thru_hole circle
			(at -4.499864 32.999934 270)
			(size 1.016 1.016)
			(drill 0.7112)
			(layers "*.Cu" "*.Mask")
			(remove_unused_layers no)
			(net "T2_BLAD1_RXD")
			(clearance 0.1016)
			(thermal_gap 0.1016)
		)
		(pad "B33" thru_hole circle
			(at -2.499868 33.999932 270)
			(size 1.016 1.016)
			(drill 0.7112)
			(layers "*.Cu" "*.Mask")
			(remove_unused_layers no)
			(net "T2_BLAD1_TXD")
			(clearance 0.1016)
			(thermal_gap 0.1016)
		)
		(pad "B34" thru_hole circle
			(at -4.499864 34.99993 270)
			(size 1.016 1.016)
			(drill 0.7112)
			(layers "*.Cu" "*.Mask")
			(remove_unused_layers no)
			(net "T2_BLAD2_RXD")
			(clearance 0.1016)
			(thermal_gap 0.1016)
		)
		(pad "B35" thru_hole circle
			(at -2.499868 35.999928 270)
			(size 1.016 1.016)
			(drill 0.7112)
			(layers "*.Cu" "*.Mask")
			(remove_unused_layers no)
			(net "T2_BLAD2_TXD")
			(clearance 0.1016)
			(thermal_gap 0.1016)
		)
		(pad "B36" thru_hole circle
			(at -4.499864 36.999926 270)
			(size 1.016 1.016)
			(drill 0.7112)
			(layers "*.Cu" "*.Mask")
			(remove_unused_layers no)
			(net "GND")
			(clearance 0.1016)
			(thermal_gap 0.1016)
		)
		(pad "B37" thru_hole circle
			(at -2.499868 37.999924 270)
			(size 1.016 1.016)
			(drill 0.7112)
			(layers "*.Cu" "*.Mask")
			(remove_unused_layers no)
			(net "T2_BLAD3_RXD")
			(clearance 0.1016)
			(thermal_gap 0.1016)
		)
		(pad "B38" thru_hole circle
			(at -4.499864 38.999922 270)
			(size 1.016 1.016)
			(drill 0.7112)
			(layers "*.Cu" "*.Mask")
			(remove_unused_layers no)
			(net "T2_BLAD3_TXD")
			(clearance 0.1016)
			(thermal_gap 0.1016)
		)
		(pad "B39" thru_hole circle
			(at -2.499868 39.99992 270)
			(size 1.016 1.016)
			(drill 0.7112)
			(layers "*.Cu" "*.Mask")
			(remove_unused_layers no)
			(net "T2_BLAD4_RXD")
			(clearance 0.1016)
			(thermal_gap 0.1016)
		)
		(pad "B40" thru_hole circle
			(at -4.499864 40.999918 270)
			(size 1.016 1.016)
			(drill 0.7112)
			(layers "*.Cu" "*.Mask")
			(remove_unused_layers no)
			(net "T2_BLAD4_TXD")
			(clearance 0.1016)
			(thermal_gap 0.1016)
		)
		(pad "B41" thru_hole circle
			(at -2.499868 41.999916 270)
			(size 1.016 1.016)
			(drill 0.7112)
			(layers "*.Cu" "*.Mask")
			(remove_unused_layers no)
			(net "GND")
			(clearance 0.1016)
			(thermal_gap 0.1016)
		)
		(pad "B42" thru_hole circle
			(at -4.499864 42.999914 270)
			(size 1.016 1.016)
			(drill 0.7112)
			(layers "*.Cu" "*.Mask")
			(remove_unused_layers no)
			(net "I2C_PSU1_SCL")
			(clearance 0.1016)
			(thermal_gap 0.1016)
		)
		(pad "B43" thru_hole circle
			(at -2.499868 43.999912 270)
			(size 1.016 1.016)
			(drill 0.7112)
			(layers "*.Cu" "*.Mask")
			(remove_unused_layers no)
			(net "I2C_PSU1_SDA")
			(clearance 0.1016)
			(thermal_gap 0.1016)
		)
		(pad "B44" thru_hole circle
			(at -4.499864 44.99991 270)
			(size 1.016 1.016)
			(drill 0.7112)
			(layers "*.Cu" "*.Mask")
			(remove_unused_layers no)
			(net "GND")
			(clearance 0.1016)
			(thermal_gap 0.1016)
		)
		(pad "B45" thru_hole circle
			(at -2.499868 45.999908 270)
			(size 1.016 1.016)
			(drill 0.7112)
			(layers "*.Cu" "*.Mask")
			(remove_unused_layers no)
			(net "PSU1_AC_OK")
			(clearance 0.1016)
			(thermal_gap 0.1016)
		)
		(pad "B46" thru_hole circle
			(at -4.499864 46.999906 270)
			(size 1.016 1.016)
			(drill 0.7112)
			(layers "*.Cu" "*.Mask")
			(remove_unused_layers no)
			(net "PSU2_AC_OK")
			(clearance 0.1016)
			(thermal_gap 0.1016)
		)
		(pad "B47" thru_hole circle
			(at -2.499868 47.999904 270)
			(size 1.016 1.016)
			(drill 0.7112)
			(layers "*.Cu" "*.Mask")
			(remove_unused_layers no)
			(net "PSU3_AC_OK")
			(clearance 0.1016)
			(thermal_gap 0.1016)
		)
		(pad "B48" thru_hole circle
			(at -4.499864 48.999902 270)
			(size 1.016 1.016)
			(drill 0.7112)
			(layers "*.Cu" "*.Mask")
			(remove_unused_layers no)
			(net "PSU4_AC_OK")
			(clearance 0.1016)
			(thermal_gap 0.1016)
		)
		(pad "B49" thru_hole circle
			(at -2.499868 49.9999 270)
			(size 1.016 1.016)
			(drill 0.7112)
			(layers "*.Cu" "*.Mask")
			(remove_unused_layers no)
			(net "PSU5_AC_OK")
			(clearance 0.1016)
			(thermal_gap 0.1016)
		)
		(pad "B50" thru_hole circle
			(at -4.499864 50.999898 270)
			(size 1.016 1.016)
			(drill 0.7112)
			(layers "*.Cu" "*.Mask")
			(remove_unused_layers no)
			(net "PSU6_AC_OK")
			(clearance 0.1016)
			(thermal_gap 0.1016)
		)
		(pad "B51" thru_hole circle
			(at -2.499868 51.999896 270)
			(size 1.016 1.016)
			(drill 0.7112)
			(layers "*.Cu" "*.Mask")
			(remove_unused_layers no)
			(net "GND")
			(clearance 0.1016)
			(thermal_gap 0.1016)
		)
		(pad "B52" thru_hole circle
			(at -4.499864 52.999894 270)
			(size 1.016 1.016)
			(drill 0.7112)
			(layers "*.Cu" "*.Mask")
			(remove_unused_layers no)
			(net "UART_RTS_P5_L_N")
			(clearance 0.1016)
			(thermal_gap 0.1016)
		)
		(pad "B53" thru_hole circle
			(at -2.499868 53.999892 270)
			(size 1.016 1.016)
			(drill 0.7112)
			(layers "*.Cu" "*.Mask")
			(remove_unused_layers no)
			(net "UART_DSR_P5_L_N")
			(clearance 0.1016)
			(thermal_gap 0.1016)
		)
		(pad "B54" thru_hole circle
			(at -4.499864 54.99989 270)
			(size 1.016 1.016)
			(drill 0.7112)
			(layers "*.Cu" "*.Mask")
			(remove_unused_layers no)
			(net "UART_RX_P5_L")
			(clearance 0.1016)
			(thermal_gap 0.1016)
		)
		(pad "B55" thru_hole circle
			(at -2.499868 55.999888 270)
			(size 1.016 1.016)
			(drill 0.7112)
			(layers "*.Cu" "*.Mask")
			(remove_unused_layers no)
			(net "UART_TX_P5_L")
			(clearance 0.1016)
			(thermal_gap 0.1016)
		)
		(pad "B56" thru_hole circle
			(at -4.499864 56.999886 270)
			(size 1.016 1.016)
			(drill 0.7112)
			(layers "*.Cu" "*.Mask")
			(remove_unused_layers no)
			(net "UART_DTR_P5_L_N")
			(clearance 0.1016)
			(thermal_gap 0.1016)
		)
		(pad "B57" thru_hole circle
			(at -2.499868 57.999884 270)
			(size 1.016 1.016)
			(drill 0.7112)
			(layers "*.Cu" "*.Mask")
			(remove_unused_layers no)
			(net "UART_CTS_P5_L_N")
			(clearance 0.1016)
			(thermal_gap 0.1016)
		)
		(pad "B58" thru_hole circle
			(at -4.499864 59.000136 270)
			(size 1.016 1.016)
			(drill 0.7112)
			(layers "*.Cu" "*.Mask")
			(remove_unused_layers no)
			(net "UART_RI_P5_L_N")
			(clearance 0.1016)
			(thermal_gap 0.1016)
		)
		(pad "B59" thru_hole circle
			(at -2.499868 59.99988 270)
			(size 1.016 1.016)
			(drill 0.7112)
			(layers "*.Cu" "*.Mask")
			(remove_unused_layers no)
			(net "GND")
			(clearance 0.1016)
			(thermal_gap 0.1016)
		)
		(pad "B60" thru_hole circle
			(at -4.499864 61.000132 270)
			(size 1.016 1.016)
			(drill 0.7112)
			(layers "*.Cu" "*.Mask")
			(remove_unused_layers no)
			(net "UART_RTS_P1_L_N")
			(clearance 0.1016)
			(thermal_gap 0.1016)
		)
		(pad "B61" thru_hole circle
			(at -2.499868 61.999876 270)
			(size 1.016 1.016)
			(drill 0.7112)
			(layers "*.Cu" "*.Mask")
			(remove_unused_layers no)
			(net "UART_DSR_P1_L_N")
			(clearance 0.1016)
			(thermal_gap 0.1016)
		)
		(pad "B62" thru_hole circle
			(at -4.499864 63.000128 270)
			(size 1.016 1.016)
			(drill 0.7112)
			(layers "*.Cu" "*.Mask")
			(remove_unused_layers no)
			(net "UART_RX_P1_L")
			(clearance 0.1016)
			(thermal_gap 0.1016)
		)
		(pad "B63" thru_hole circle
			(at -2.499868 63.999872 270)
			(size 1.016 1.016)
			(drill 0.7112)
			(layers "*.Cu" "*.Mask")
			(remove_unused_layers no)
			(net "UART_TX_P1_L")
			(clearance 0.1016)
			(thermal_gap 0.1016)
		)
		(pad "B64" thru_hole circle
			(at -4.499864 65.000124 270)
			(size 1.016 1.016)
			(drill 0.7112)
			(layers "*.Cu" "*.Mask")
			(remove_unused_layers no)
			(net "UART_DTR_P1_L_N")
			(clearance 0.1016)
			(thermal_gap 0.1016)
		)
		(pad "B65" thru_hole circle
			(at -2.499868 65.999868 270)
			(size 1.016 1.016)
			(drill 0.7112)
			(layers "*.Cu" "*.Mask")
			(remove_unused_layers no)
			(net "UART_CTS_P1_L_N")
			(clearance 0.1016)
			(thermal_gap 0.1016)
		)
		(pad "B66" thru_hole circle
			(at -4.499864 67.00012 270)
			(size 1.016 1.016)
			(drill 0.7112)
			(layers "*.Cu" "*.Mask")
			(remove_unused_layers no)
			(net "GND")
			(clearance 0.1016)
			(thermal_gap 0.1016)
		)
		(pad "B67" thru_hole circle
			(at -2.499868 67.999864 270)
			(size 1.016 1.016)
			(drill 0.7112)
			(layers "*.Cu" "*.Mask")
			(remove_unused_layers no)
			(net "Net_433")
			(clearance 0.1016)
			(thermal_gap 0.1016)
		)
		(pad "B68" thru_hole circle
			(at -4.499864 69.000116 270)
			(size 1.016 1.016)
			(drill 0.7112)
			(layers "*.Cu" "*.Mask")
			(remove_unused_layers no)
			(net "GND28")
			(clearance 0.1016)
			(thermal_gap 0.1016)
		)
		(pad "B69" thru_hole circle
			(at -2.499868 70.000114 270)
			(size 1.016 1.016)
			(drill 0.7112)
			(layers "*.Cu" "*.Mask")
			(remove_unused_layers no)
			(net "GND29")
			(clearance 0.1016)
			(thermal_gap 0.1016)
		)
		(pad "B70" thru_hole circle
			(at -4.499864 71.000112 270)
			(size 1.016 1.016)
			(drill 0.7112)
			(layers "*.Cu" "*.Mask")
			(remove_unused_layers no)
			(net "Net_432")
			(clearance 0.1016)
			(thermal_gap 0.1016)
		)
		(pad "B71" thru_hole circle
			(at -2.499868 72.00011 270)
			(size 1.016 1.016)
			(drill 0.7112)
			(layers "*.Cu" "*.Mask")
			(remove_unused_layers no)
			(net "GND")
			(clearance 0.1016)
			(thermal_gap 0.1016)
		)
		(pad "B72" thru_hole circle
			(at -4.499864 73.000108 270)
			(size 1.016 1.016)
			(drill 0.7112)
			(layers "*.Cu" "*.Mask")
			(remove_unused_layers no)
			(net "LAN1_P3_P")
			(clearance 0.1016)
			(thermal_gap 0.1016)
		)
		(pad "B73" thru_hole circle
			(at -2.499868 74.000106 270)
			(size 1.016 1.016)
			(drill 0.7112)
			(layers "*.Cu" "*.Mask")
			(remove_unused_layers no)
			(net "LAN1_P3_N")
			(clearance 0.1016)
			(thermal_gap 0.1016)
		)
		(pad "B74" thru_hole circle
			(at -4.499864 75.000104 270)
			(size 1.016 1.016)
			(drill 0.7112)
			(layers "*.Cu" "*.Mask")
			(remove_unused_layers no)
			(net "GND")
			(clearance 0.1016)
			(thermal_gap 0.1016)
		)
		(pad "B75" thru_hole circle
			(at -2.499868 76.000102 270)
			(size 1.016 1.016)
			(drill 0.7112)
			(layers "*.Cu" "*.Mask")
			(remove_unused_layers no)
			(net "LAN1_P4_P")
			(clearance 0.1016)
			(thermal_gap 0.1016)
		)
		(pad "B76" thru_hole circle
			(at -4.499864 77.0001 270)
			(size 1.016 1.016)
			(drill 0.7112)
			(layers "*.Cu" "*.Mask")
			(remove_unused_layers no)
			(net "LAN1_P4_N")
			(clearance 0.1016)
			(thermal_gap 0.1016)
		)
		(pad "B77" thru_hole circle
			(at -2.499868 78.000098 270)
			(size 1.016 1.016)
			(drill 0.7112)
			(layers "*.Cu" "*.Mask")
			(remove_unused_layers no)
			(net "GND")
			(clearance 0.1016)
			(thermal_gap 0.1016)
		)
		(pad "B78" thru_hole circle
			(at -4.499864 79.000096 270)
			(size 1.016 1.016)
			(drill 0.7112)
			(layers "*.Cu" "*.Mask")
			(remove_unused_layers no)
			(net "CM_PWR_CTL_IN")
			(clearance 0.1016)
			(thermal_gap 0.1016)
		)
		(pad "B79" thru_hole circle
			(at -2.499868 80.000094 270)
			(size 1.016 1.016)
			(drill 0.7112)
			(layers "*.Cu" "*.Mask")
			(remove_unused_layers no)
			(net "P12V")
			(clearance 0.1016)
			(thermal_gap 0.1016)
		)
		(pad "B80" thru_hole circle
			(at -4.499864 81.000092 270)
			(size 1.016 1.016)
			(drill 0.7112)
			(layers "*.Cu" "*.Mask")
			(remove_unused_layers no)
			(net "P12V")
			(clearance 0.1016)
			(thermal_gap 0.1016)
		)
		(pad "B81" thru_hole circle
			(at -2.499868 82.00009 270)
			(size 1.016 1.016)
			(drill 0.7112)
			(layers "*.Cu" "*.Mask")
			(remove_unused_layers no)
			(net "MATE_A1")
			(clearance 0.1016)
			(thermal_gap 0.1016)
		)
		(pad "B82" thru_hole circle
			(at -4.499864 83.000088 270)
			(size 1.016 1.016)
			(drill 0.7112)
			(layers "*.Cu" "*.Mask")
			(remove_unused_layers no)
			(net "P12V")
			(clearance 0.1016)
			(thermal_gap 0.1016)
		)
		(zone
			(layers "F.Cu" "B.Cu" "In1.Cu" "In2.Cu" "In3.Cu" "In4.Cu" "In5.Cu" "In6.Cu")
			(hatch none 0.5)
			(connect_pads
				(clearance 0)
			)
			(min_thickness 0.25)
			(keepout
				(tracks allowed)
				(vias not_allowed)
				(pads allowed)
				(copperpour not_allowed)
				(footprints allowed)
			)
			(placement
				(enabled no)
				(sheetname "")
			)
			(fill
				(thermal_gap 0.5)
				(thermal_bridge_width 0.5)
				(island_removal_mode 0)
			)
			(polygon
				(pts
					(xy 1.368806 -178.104546) (xy 3.731006 -178.104546) (xy 3.731006 -175.386746) (xy 6.677406 -175.386746)
					(xy 6.677406 -178.104546) (xy 9.014206 -178.104546) (xy 9.014206 -262.254746) (xy 1.368806 -262.254746)
				)
			)
		)
		(zone
			(layers "F.Cu" "B.Cu" "In1.Cu" "In2.Cu" "In3.Cu" "In4.Cu" "In5.Cu" "In6.Cu")
			(hatch none 0.5)
			(connect_pads
				(clearance 0)
			)
			(min_thickness 0.25)
			(keepout
				(tracks not_allowed)
				(vias allowed)
				(pads allowed)
				(copperpour not_allowed)
				(footprints allowed)
			)
			(placement
				(enabled no)
				(sheetname "")
			)
			(fill
				(thermal_gap 0.5)
				(thermal_bridge_width 0.5)
				(island_removal_mode 0)
			)
			(polygon
				(pts
					(arc
						(start 3.58267 -250.020582)
						(mid 3.674142 -250.556339)
						(end 3.938016 -251.031502)
					)
					(xy 4.566412 -251.031502)
					(arc
						(start 4.566412 -251.507752)
						(mid 5.200269 -251.636551)
						(end 5.833872 -251.506482)
					)
					(xy 5.833872 -251.039376)
					(arc
						(start 6.453124 -251.039376)
						(mid 5.739145 -248.497573)
						(end 3.58267 -250.020582)
					)
				)
			)
		)
	)
	(footprint ""
		(layer "F.Cu")
		(at 27.28468 -5.10032)
		(property "Reference" "R45"
			(at -1.676146 2.569972 0)
			(unlocked yes)
			(layer "F.SilkS")
			(effects
				(font
					(size 0.7874 0.5842)
					(thickness 0.1524)
				)
				(justify left)
			)
		)
		(property "Value" ""
			(at 0 0 0)
			(layer "F.Fab")
			(effects
				(font
					(size 1.27 1.27)
				)
			)
		)
		(duplicate_pad_numbers_are_jumpers no)
		(fp_line
			(start -0.7874 -0.4064)
			(end 0.7874 -0.4064)
			(stroke
				(width 0.1524)
				(type default)
			)
			(layer "F.SilkS")
		)
		(fp_line
			(start -0.7874 0.4064)
			(end -0.7874 -0.4064)
			(stroke
				(width 0.1524)
				(type default)
			)
			(layer "F.SilkS")
		)
		(fp_line
			(start 0.7874 -0.4064)
			(end 0.7874 0.4064)
			(stroke
				(width 0.1524)
				(type default)
			)
			(layer "F.SilkS")
		)
		(fp_line
			(start 0.7874 0.4064)
			(end -0.7874 0.4064)
			(stroke
				(width 0.1524)
				(type default)
			)
			(layer "F.SilkS")
		)
		(fp_poly
			(pts
				(xy -0.508 0.2794) (xy -0.508 0.2286) (xy -0.635 0.2286) (xy -0.635 -0.254) (xy -0.5334 -0.254)
				(xy -0.5334 -0.2794) (xy 0.5334 -0.2794) (xy 0.5334 -0.254) (xy 0.635 -0.254) (xy 0.635 0.254) (xy 0.5334 0.254)
				(xy 0.5334 0.2794)
			)
			(stroke
				(width 0)
				(type default)
			)
			(fill no)
			(layer "F.CrtYd")
		)
		(pad "1" smd rect
			(at 0.40005 0)
			(size 0.4572 0.508)
			(layers "F.Cu" "F.Mask" "F.Paste")
			(net "PSU1_RESET")
		)
		(pad "2" smd rect
			(at -0.40005 0)
			(size 0.4572 0.508)
			(layers "F.Cu" "F.Mask" "F.Paste")
			(net "GND")
		)
	)
	(footprint ""
		(layer "F.Cu")
		(at 51.613054 -240.589308 180)
		(property "Reference" "CE12"
			(at -5.020056 0.183388 0)
			(unlocked yes)
			(layer "F.SilkS")
			(effects
				(font
					(size 0.7874 0.5842)
					(thickness 0.1524)
				)
				(justify left)
			)
		)
		(property "Value" ""
			(at 0 0 180)
			(layer "F.Fab")
			(effects
				(font
					(size 1.27 1.27)
				)
			)
		)
		(duplicate_pad_numbers_are_jumpers no)
		(fp_line
			(start 0 -4.2672)
			(end 0 4.2672)
			(stroke
				(width 0.1524)
				(type default)
			)
			(layer "F.SilkS")
		)
		(fp_circle
			(center 0 0)
			(end -4.2672 0)
			(stroke
				(width 0.1524)
				(type default)
			)
			(fill no)
			(layer "F.SilkS")
		)
		(fp_poly
			(pts
				(arc
					(start 0 -4.2672)
					(mid 4.2672 0)
					(end 0 4.2672)
				)
			)
			(stroke
				(width 0)
				(type default)
			)
			(fill yes)
			(layer "F.SilkS")
		)
		(fp_poly
			(pts
				(xy -2.5146 -0.762) (xy -0.9906 -0.762) (xy -0.9906 0.762) (xy -2.5146 0.762)
			)
			(stroke
				(width 0)
				(type default)
			)
			(fill no)
			(layer "B.CrtYd")
		)
		(fp_poly
			(pts
				(arc
					(start 1.7526 0.762)
					(mid 2.291415 -0.538815)
					(end 0.9906 0)
				)
				(arc
					(start 0.9906 0.0254)
					(mid 1.206345 0.546255)
					(end 1.7272 0.762)
				)
			)
			(stroke
				(width 0)
				(type default)
			)
			(fill no)
			(layer "B.CrtYd")
		)
		(fp_poly
			(pts
				(arc
					(start -4.2672 0)
					(mid 4.2672 0)
					(end -4.2672 0)
				)
			)
			(stroke
				(width 0)
				(type default)
			)
			(fill no)
			(layer "F.CrtYd")
		)
		(fp_circle
			(center 0 0)
			(end -4.2672 0)
			(stroke
				(width 0.1)
				(type default)
			)
			(fill no)
			(layer "F.Fab")
		)
		(fp_text user "+"
			(at -6.029198 -1.809242 180)
			(unlocked yes)
			(layer "F.SilkS")
			(effects
				(font
					(size 1.905 1.4224)
					(thickness 0.1524)
				)
				(justify left)
			)
		)
		(fp_text user "+"
			(at -5.6642 -0.34925 180)
			(unlocked yes)
			(layer "F.Fab")
			(effects
				(font
					(size 1.905 1.4224)
					(thickness 0.000001)
				)
				(justify left)
			)
		)
		(pad "1" thru_hole rect
			(at -1.75006 0 180)
			(size 1.397 1.397)
			(drill 0.9144)
			(layers "*.Cu" "*.Mask")
			(remove_unused_layers no)
			(net "P12V")
			(clearance 0.0127)
			(thermal_gap 0.0127)
			(padstack
				(mode front_inner_back)
				(layer "Inner"
					(shape circle)
					(size 1.397 1.397)
					(clearance 0.0127)
				)
				(layer "B.Cu"
					(shape rect)
					(size 1.397 1.397)
					(clearance 0.0127)
				)
			)
		)
		(pad "2" thru_hole circle
			(at 1.75006 0 180)
			(size 1.397 1.397)
			(drill 0.9144)
			(layers "*.Cu" "*.Mask")
			(remove_unused_layers no)
			(net "GND")
			(clearance 0.0127)
			(thermal_gap 0.0127)
		)
	)
	(footprint ""
		(layer "F.Cu")
		(at 78.397354 -18.749772 -90)
		(property "Reference" "C4"
			(at -1.75133 0.035052 90)
			(unlocked yes)
			(layer "F.SilkS")
			(effects
				(font
					(size 0.7874 0.5842)
					(thickness 0.1524)
				)
				(justify left)
			)
		)
		(property "Value" ""
			(at 0 0 270)
			(layer "F.Fab")
			(effects
				(font
					(size 1.27 1.27)
				)
			)
		)
		(duplicate_pad_numbers_are_jumpers no)
		(fp_line
			(start -0.7874 0.4064)
			(end -0.7874 -0.4064)
			(stroke
				(width 0.1524)
				(type default)
			)
			(layer "F.SilkS")
		)
		(fp_line
			(start 0.7874 0.4064)
			(end -0.7874 0.4064)
			(stroke
				(width 0.1524)
				(type default)
			)
			(layer "F.SilkS")
		)
		(fp_line
			(start 0 0.381)
			(end 0 -0.381)
			(stroke
				(width 0.1524)
				(type default)
			)
			(layer "F.SilkS")
		)
		(fp_line
			(start -0.7874 -0.4064)
			(end 0.7874 -0.4064)
			(stroke
				(width 0.1524)
				(type default)
			)
			(layer "F.SilkS")
		)
		(fp_line
			(start 0.7874 -0.4064)
			(end 0.7874 0.4064)
			(stroke
				(width 0.1524)
				(type default)
			)
			(layer "F.SilkS")
		)
		(fp_poly
			(pts
				(xy -0.5334 0.254) (xy -0.635 0.254) (xy -0.635 0.2286) (xy -0.635 -0.254) (xy -0.5334 -0.254) (xy -0.5334 -0.2794)
				(xy 0.5334 -0.2794) (xy 0.5334 -0.254) (xy 0.635 -0.254) (xy 0.635 0.254) (xy 0.5334 0.254) (xy 0.5334 0.2794)
				(xy -0.508 0.2794) (xy -0.5334 0.2794)
			)
			(stroke
				(width 0)
				(type default)
			)
			(fill no)
			(layer "F.CrtYd")
		)
		(pad "1" smd rect
			(at 0.40005 0 270)
			(size 0.4572 0.508)
			(layers "F.Cu" "F.Mask" "F.Paste")
			(net "P12V")
		)
		(pad "2" smd rect
			(at -0.40005 0 270)
			(size 0.4572 0.508)
			(layers "F.Cu" "F.Mask" "F.Paste")
			(net "GND")
		)
	)
	(footprint ""
		(layer "F.Cu")
		(at 91.399868 -464.509866)
		(property "Reference" "H19"
			(at -5.1308 -5.23113 0)
			(unlocked yes)
			(layer "F.SilkS")
			(effects
				(font
					(size 0.7874 0.5842)
					(thickness 0.1524)
				)
				(justify left)
			)
		)
		(property "Value" ""
			(at 0 0 0)
			(layer "F.Fab")
			(effects
				(font
					(size 1.27 1.27)
				)
			)
		)
		(duplicate_pad_numbers_are_jumpers no)
		(fp_circle
			(center 0 0)
			(end 4.826 0)
			(stroke
				(width 0.1524)
				(type default)
			)
			(fill no)
			(layer "F.SilkS")
		)
		(fp_circle
			(center 0 0)
			(end 4.826 0)
			(stroke
				(width 0.1524)
				(type default)
			)
			(fill no)
			(layer "B.SilkS")
		)
		(fp_poly
			(pts
				(arc
					(start 0 4.0132)
					(mid 0 -4.0132)
					(end 0 4.0132)
				)
			)
			(stroke
				(width 0)
				(type default)
			)
			(fill no)
			(layer "F.CrtYd")
		)
		(pad "" np_thru_hole circle
			(at 0 0)
			(size 8.001 8.001)
			(drill 8.001)
			(layers "*.Cu" "*.Mask")
			(clearance 0.381)
			(thermal_gap 0.381)
		)
		(zone
			(layers "F.Cu" "B.Cu" "In1.Cu" "In2.Cu" "In3.Cu" "In4.Cu" "In5.Cu" "In6.Cu")
			(hatch none 0.5)
			(connect_pads
				(clearance 0)
			)
			(min_thickness 0.25)
			(keepout
				(tracks not_allowed)
				(vias allowed)
				(pads allowed)
				(copperpour not_allowed)
				(footprints allowed)
			)
			(placement
				(enabled no)
				(sheetname "")
			)
			(fill
				(thermal_gap 0.5)
				(thermal_bridge_width 0.5)
				(island_removal_mode 0)
			)
			(polygon
				(pts
					(arc
						(start 91.399868 -459.988666)
						(mid 91.399868 -469.031066)
						(end 91.399868 -459.988666)
					)
				)
			)
		)
	)
	(footprint ""
		(layer "F.Cu")
		(at 79.898748 -508.382778 -90)
		(property "Reference" "C78"
			(at 2.76606 -0.024892 90)
			(unlocked yes)
			(layer "F.SilkS")
			(effects
				(font
					(size 0.7874 0.5842)
					(thickness 0.1524)
				)
			)
		)
		(property "Value" ""
			(at 0 0 270)
			(layer "F.Fab")
			(effects
				(font
					(size 1.27 1.27)
				)
			)
		)
		(duplicate_pad_numbers_are_jumpers no)
		(fp_line
			(start -1.2954 0.5842)
			(end -1.2954 -0.5842)
			(stroke
				(width 0.1524)
				(type default)
			)
			(layer "F.SilkS")
		)
		(fp_line
			(start 1.2954 0.5842)
			(end -1.2954 0.5842)
			(stroke
				(width 0.1524)
				(type default)
			)
			(layer "F.SilkS")
		)
		(fp_line
			(start -1.2954 -0.5842)
			(end 1.2954 -0.5842)
			(stroke
				(width 0.1524)
				(type default)
			)
			(layer "F.SilkS")
		)
		(fp_line
			(start 0 -0.5842)
			(end 0 0.5842)
			(stroke
				(width 0.1524)
				(type default)
			)
			(layer "F.SilkS")
		)
		(fp_line
			(start 1.2954 -0.5842)
			(end 1.2954 0.5842)
			(stroke
				(width 0.1524)
				(type default)
			)
			(layer "F.SilkS")
		)
		(fp_poly
			(pts
				(xy 0.8636 -0.4572) (xy 0.8636 -0.3556) (xy 1.143 -0.3556) (xy 1.143 0.3556) (xy 0.8636 0.3556)
				(xy 0.8636 0.4572) (xy -0.8636 0.4572) (xy -0.8636 0.3556) (xy -1.143 0.3556) (xy -1.143 -0.3556)
				(xy -0.8636 -0.3556) (xy -0.8636 -0.4572)
			)
			(stroke
				(width 0)
				(type default)
			)
			(fill no)
			(layer "F.CrtYd")
		)
		(fp_line
			(start -0.884936 0.504952)
			(end -0.884936 -0.504952)
			(stroke
				(width 0.1)
				(type default)
			)
			(layer "F.Fab")
		)
		(fp_line
			(start 0.884936 0.504952)
			(end -0.884936 0.504952)
			(stroke
				(width 0.1)
				(type default)
			)
			(layer "F.Fab")
		)
		(fp_line
			(start -0.884936 -0.504952)
			(end 0.884936 -0.504952)
			(stroke
				(width 0.1)
				(type default)
			)
			(layer "F.Fab")
		)
		(fp_line
			(start 0.884936 -0.504952)
			(end 0.884936 0.504952)
			(stroke
				(width 0.1)
				(type default)
			)
			(layer "F.Fab")
		)
		(pad "1" smd rect
			(at 0.7366 0)
			(size 0.7112 0.8128)
			(layers "F.Cu" "F.Mask" "F.Paste")
			(net "P12V")
		)
		(pad "2" smd rect
			(at -0.7366 0)
			(size 0.7112 0.8128)
			(layers "F.Cu" "F.Mask" "F.Paste")
			(net "GND")
		)
	)
	(footprint ""
		(layer "F.Cu")
		(at 77.999844 -78.299818)
		(property "Reference" "H14"
			(at -1.764792 -4.65709 0)
			(unlocked yes)
			(layer "F.SilkS")
			(effects
				(font
					(size 0.7874 0.5842)
					(thickness 0.1524)
				)
				(justify left)
			)
		)
		(property "Value" ""
			(at 0 0 0)
			(layer "F.Fab")
			(effects
				(font
					(size 1.27 1.27)
				)
			)
		)
		(duplicate_pad_numbers_are_jumpers no)
		(fp_circle
			(center 0 0)
			(end 3.4163 0)
			(stroke
				(width 0.1524)
				(type default)
			)
			(fill no)
			(layer "F.SilkS")
		)
		(fp_circle
			(center 0 0)
			(end 3.41884 0)
			(stroke
				(width 0.1524)
				(type default)
			)
			(fill no)
			(layer "B.SilkS")
		)
		(fp_poly
			(pts
				(arc
					(start 2.8575 0)
					(mid -2.8575 0)
					(end 2.8575 0)
				)
			)
			(stroke
				(width 0)
				(type default)
			)
			(fill no)
			(layer "B.CrtYd")
		)
		(fp_poly
			(pts
				(arc
					(start 2.8575 0)
					(mid -2.8575 0)
					(end 2.8575 0)
				)
			)
			(stroke
				(width 0)
				(type default)
			)
			(fill no)
			(layer "F.CrtYd")
		)
		(pad "" np_thru_hole circle
			(at 0 0)
			(size 5.207 5.207)
			(drill 5.207)
			(layers "*.Cu" "*.Mask")
			(clearance 0.381)
			(thermal_gap 0.381)
		)
		(zone
			(layers "F.Cu" "B.Cu" "In1.Cu" "In2.Cu" "In3.Cu" "In4.Cu" "In5.Cu" "In6.Cu")
			(hatch none 0.5)
			(connect_pads
				(clearance 0)
			)
			(min_thickness 0.25)
			(keepout
				(tracks not_allowed)
				(vias allowed)
				(pads allowed)
				(copperpour not_allowed)
				(footprints allowed)
			)
			(placement
				(enabled no)
				(sheetname "")
			)
			(fill
				(thermal_gap 0.5)
				(thermal_bridge_width 0.5)
				(island_removal_mode 0)
			)
			(polygon
				(pts
					(arc
						(start 81.111344 -78.299818)
						(mid 74.888344 -78.299818)
						(end 81.111344 -78.299818)
					)
				)
			)
		)
	)
	(footprint ""
		(layer "F.Cu")
		(at 77.43698 -393.452604 90)
		(property "Reference" "C67"
			(at 1.08458 0.350012 90)
			(unlocked yes)
			(layer "F.SilkS")
			(effects
				(font
					(size 0.7874 0.5842)
					(thickness 0.1524)
				)
				(justify left)
			)
		)
		(property "Value" ""
			(at 0 0 90)
			(layer "F.Fab")
			(effects
				(font
					(size 1.27 1.27)
				)
			)
		)
		(duplicate_pad_numbers_are_jumpers no)
		(fp_line
			(start 0.7874 -0.4064)
			(end 0.7874 0.4064)
			(stroke
				(width 0.1524)
				(type default)
			)
			(layer "F.SilkS")
		)
		(fp_line
			(start -0.7874 -0.4064)
			(end 0.7874 -0.4064)
			(stroke
				(width 0.1524)
				(type default)
			)
			(layer "F.SilkS")
		)
		(fp_line
			(start 0 0.381)
			(end 0 -0.381)
			(stroke
				(width 0.1524)
				(type default)
			)
			(layer "F.SilkS")
		)
		(fp_line
			(start 0.7874 0.4064)
			(end -0.7874 0.4064)
			(stroke
				(width 0.1524)
				(type default)
			)
			(layer "F.SilkS")
		)
		(fp_line
			(start -0.7874 0.4064)
			(end -0.7874 -0.4064)
			(stroke
				(width 0.1524)
				(type default)
			)
			(layer "F.SilkS")
		)
		(fp_poly
			(pts
				(xy -0.5334 0.254) (xy -0.635 0.254) (xy -0.635 0.2286) (xy -0.635 -0.254) (xy -0.5334 -0.254) (xy -0.5334 -0.2794)
				(xy 0.5334 -0.2794) (xy 0.5334 -0.254) (xy 0.635 -0.254) (xy 0.635 0.254) (xy 0.5334 0.254) (xy 0.5334 0.2794)
				(xy -0.508 0.2794) (xy -0.5334 0.2794)
			)
			(stroke
				(width 0)
				(type default)
			)
			(fill no)
			(layer "F.CrtYd")
		)
		(pad "1" smd rect
			(at 0.40005 0 90)
			(size 0.4572 0.508)
			(layers "F.Cu" "F.Mask" "F.Paste")
			(net "P12V")
		)
		(pad "2" smd rect
			(at -0.40005 0 90)
			(size 0.4572 0.508)
			(layers "F.Cu" "F.Mask" "F.Paste")
			(net "GND")
		)
	)
	(footprint ""
		(layer "F.Cu")
		(at 21.511514 -449.860162 180)
		(property "Reference" "C91"
			(at -0.285496 -7.5057 0)
			(unlocked yes)
			(layer "F.SilkS")
			(effects
				(font
					(size 0.7874 0.5842)
					(thickness 0.1524)
				)
				(justify left)
			)
		)
		(property "Value" ""
			(at 0 0 180)
			(layer "F.Fab")
			(effects
				(font
					(size 1.27 1.27)
				)
			)
		)
		(duplicate_pad_numbers_are_jumpers no)
		(fp_line
			(start 0.7874 0.4064)
			(end -0.7874 0.4064)
			(stroke
				(width 0.1524)
				(type default)
			)
			(layer "F.SilkS")
		)
		(fp_line
			(start 0.7874 -0.4064)
			(end 0.7874 0.4064)
			(stroke
				(width 0.1524)
				(type default)
			)
			(layer "F.SilkS")
		)
		(fp_line
			(start 0 0.381)
			(end 0 -0.381)
			(stroke
				(width 0.1524)
				(type default)
			)
			(layer "F.SilkS")
		)
		(fp_line
			(start -0.7874 0.4064)
			(end -0.7874 -0.4064)
			(stroke
				(width 0.1524)
				(type default)
			)
			(layer "F.SilkS")
		)
		(fp_line
			(start -0.7874 -0.4064)
			(end 0.7874 -0.4064)
			(stroke
				(width 0.1524)
				(type default)
			)
			(layer "F.SilkS")
		)
		(fp_poly
			(pts
				(xy -0.5334 0.254) (xy -0.635 0.254) (xy -0.635 0.2286) (xy -0.635 -0.254) (xy -0.5334 -0.254) (xy -0.5334 -0.2794)
				(xy 0.5334 -0.2794) (xy 0.5334 -0.254) (xy 0.635 -0.254) (xy 0.635 0.254) (xy 0.5334 0.254) (xy 0.5334 0.2794)
				(xy -0.508 0.2794) (xy -0.5334 0.2794)
			)
			(stroke
				(width 0)
				(type default)
			)
			(fill no)
			(layer "F.CrtYd")
		)
		(pad "1" smd rect
			(at 0.40005 0 180)
			(size 0.4572 0.508)
			(layers "F.Cu" "F.Mask" "F.Paste")
			(net "P3V3_BUF")
		)
		(pad "2" smd rect
			(at -0.40005 0 180)
			(size 0.4572 0.508)
			(layers "F.Cu" "F.Mask" "F.Paste")
			(net "GND")
		)
	)
	(footprint ""
		(layer "F.Cu")
		(at 12.784074 -330.48067 -90)
		(property "Reference" "R36"
			(at 3.685032 -0.234188 90)
			(unlocked yes)
			(layer "F.SilkS")
			(effects
				(font
					(size 0.7874 0.5842)
					(thickness 0.1524)
				)
				(justify left)
			)
		)
		(property "Value" ""
			(at 0 0 270)
			(layer "F.Fab")
			(effects
				(font
					(size 1.27 1.27)
				)
			)
		)
		(duplicate_pad_numbers_are_jumpers no)
		(fp_line
			(start -0.7874 0.4064)
			(end -0.7874 -0.4064)
			(stroke
				(width 0.1524)
				(type default)
			)
			(layer "F.SilkS")
		)
		(fp_line
			(start 0.7874 0.4064)
			(end -0.7874 0.4064)
			(stroke
				(width 0.1524)
				(type default)
			)
			(layer "F.SilkS")
		)
		(fp_line
			(start -0.7874 -0.4064)
			(end 0.7874 -0.4064)
			(stroke
				(width 0.1524)
				(type default)
			)
			(layer "F.SilkS")
		)
		(fp_line
			(start 0.7874 -0.4064)
			(end 0.7874 0.4064)
			(stroke
				(width 0.1524)
				(type default)
			)
			(layer "F.SilkS")
		)
		(fp_poly
			(pts
				(xy -0.508 0.2794) (xy -0.508 0.2286) (xy -0.635 0.2286) (xy -0.635 -0.254) (xy -0.5334 -0.254)
				(xy -0.5334 -0.2794) (xy 0.5334 -0.2794) (xy 0.5334 -0.254) (xy 0.635 -0.254) (xy 0.635 0.254) (xy 0.5334 0.254)
				(xy 0.5334 0.2794)
			)
			(stroke
				(width 0)
				(type default)
			)
			(fill no)
			(layer "F.CrtYd")
		)
		(pad "1" smd rect
			(at 0.40005 0 270)
			(size 0.4572 0.508)
			(layers "F.Cu" "F.Mask" "F.Paste")
			(net "P3V3")
		)
		(pad "2" smd rect
			(at -0.40005 0 270)
			(size 0.4572 0.508)
			(layers "F.Cu" "F.Mask" "F.Paste")
			(net "FRU_A2")
		)
	)
	(footprint ""
		(layer "F.Cu")
		(at 72.087232 -330.840588 -90)
		(property "Reference" "C50"
			(at 2.751836 -0.146304 90)
			(unlocked yes)
			(layer "F.SilkS")
			(effects
				(font
					(size 0.7874 0.5842)
					(thickness 0.1524)
				)
			)
		)
		(property "Value" ""
			(at 0 0 270)
			(layer "F.Fab")
			(effects
				(font
					(size 1.27 1.27)
				)
			)
		)
		(duplicate_pad_numbers_are_jumpers no)
		(fp_line
			(start -1.2954 0.5842)
			(end -1.2954 -0.5842)
			(stroke
				(width 0.1524)
				(type default)
			)
			(layer "F.SilkS")
		)
		(fp_line
			(start 1.2954 0.5842)
			(end -1.2954 0.5842)
			(stroke
				(width 0.1524)
				(type default)
			)
			(layer "F.SilkS")
		)
		(fp_line
			(start -1.2954 -0.5842)
			(end 1.2954 -0.5842)
			(stroke
				(width 0.1524)
				(type default)
			)
			(layer "F.SilkS")
		)
		(fp_line
			(start 0 -0.5842)
			(end 0 0.5842)
			(stroke
				(width 0.1524)
				(type default)
			)
			(layer "F.SilkS")
		)
		(fp_line
			(start 1.2954 -0.5842)
			(end 1.2954 0.5842)
			(stroke
				(width 0.1524)
				(type default)
			)
			(layer "F.SilkS")
		)
		(fp_poly
			(pts
				(xy 0.8636 -0.4572) (xy 0.8636 -0.3556) (xy 1.143 -0.3556) (xy 1.143 0.3556) (xy 0.8636 0.3556)
				(xy 0.8636 0.4572) (xy -0.8636 0.4572) (xy -0.8636 0.3556) (xy -1.143 0.3556) (xy -1.143 -0.3556)
				(xy -0.8636 -0.3556) (xy -0.8636 -0.4572)
			)
			(stroke
				(width 0)
				(type default)
			)
			(fill no)
			(layer "F.CrtYd")
		)
		(fp_line
			(start -0.884936 0.504952)
			(end -0.884936 -0.504952)
			(stroke
				(width 0.1)
				(type default)
			)
			(layer "F.Fab")
		)
		(fp_line
			(start 0.884936 0.504952)
			(end -0.884936 0.504952)
			(stroke
				(width 0.1)
				(type default)
			)
			(layer "F.Fab")
		)
		(fp_line
			(start -0.884936 -0.504952)
			(end 0.884936 -0.504952)
			(stroke
				(width 0.1)
				(type default)
			)
			(layer "F.Fab")
		)
		(fp_line
			(start 0.884936 -0.504952)
			(end 0.884936 0.504952)
			(stroke
				(width 0.1)
				(type default)
			)
			(layer "F.Fab")
		)
		(pad "1" smd rect
			(at 0.7366 0)
			(size 0.7112 0.8128)
			(layers "F.Cu" "F.Mask" "F.Paste")
			(net "P12V")
		)
		(pad "2" smd rect
			(at -0.7366 0)
			(size 0.7112 0.8128)
			(layers "F.Cu" "F.Mask" "F.Paste")
			(net "GND")
		)
	)
	(footprint ""
		(layer "F.Cu")
		(at 68.697602 -120.313958 180)
		(property "Reference" "R115"
			(at 2.566162 1.311148 0)
			(unlocked yes)
			(layer "F.SilkS")
			(effects
				(font
					(size 0.7874 0.5842)
					(thickness 0.1524)
				)
				(justify left)
			)
		)
		(property "Value" ""
			(at 0 0 180)
			(layer "F.Fab")
			(effects
				(font
					(size 1.27 1.27)
				)
			)
		)
		(duplicate_pad_numbers_are_jumpers no)
		(fp_line
			(start 0.7874 0.4064)
			(end -0.7874 0.4064)
			(stroke
				(width 0.1524)
				(type default)
			)
			(layer "F.SilkS")
		)
		(fp_line
			(start 0.7874 -0.4064)
			(end 0.7874 0.4064)
			(stroke
				(width 0.1524)
				(type default)
			)
			(layer "F.SilkS")
		)
		(fp_line
			(start -0.7874 0.4064)
			(end -0.7874 -0.4064)
			(stroke
				(width 0.1524)
				(type default)
			)
			(layer "F.SilkS")
		)
		(fp_line
			(start -0.7874 -0.4064)
			(end 0.7874 -0.4064)
			(stroke
				(width 0.1524)
				(type default)
			)
			(layer "F.SilkS")
		)
		(fp_poly
			(pts
				(xy -0.508 0.2794) (xy -0.508 0.2286) (xy -0.635 0.2286) (xy -0.635 -0.254) (xy -0.5334 -0.254)
				(xy -0.5334 -0.2794) (xy 0.5334 -0.2794) (xy 0.5334 -0.254) (xy 0.635 -0.254) (xy 0.635 0.254) (xy 0.5334 0.254)
				(xy 0.5334 0.2794)
			)
			(stroke
				(width 0)
				(type default)
			)
			(fill no)
			(layer "F.CrtYd")
		)
		(pad "1" smd rect
			(at 0.40005 0 180)
			(size 0.4572 0.508)
			(layers "F.Cu" "F.Mask" "F.Paste")
			(net "PSU2_REMOTE_R2_P")
		)
		(pad "2" smd rect
			(at -0.40005 0 180)
			(size 0.4572 0.508)
			(layers "F.Cu" "F.Mask" "F.Paste")
			(net "P12V")
		)
	)
	(footprint ""
		(layer "F.Cu")
		(at 74.345292 -285.966154 -90)
		(property "Reference" "C45"
			(at 0.870204 -4.132834 90)
			(unlocked yes)
			(layer "F.SilkS")
			(effects
				(font
					(size 0.7874 0.5842)
					(thickness 0.1524)
				)
				(justify left)
			)
		)
		(property "Value" ""
			(at 0 0 270)
			(layer "F.Fab")
			(effects
				(font
					(size 1.27 1.27)
				)
			)
		)
		(duplicate_pad_numbers_are_jumpers no)
		(fp_line
			(start -0.7874 0.4064)
			(end -0.7874 -0.4064)
			(stroke
				(width 0.1524)
				(type default)
			)
			(layer "F.SilkS")
		)
		(fp_line
			(start 0.7874 0.4064)
			(end -0.7874 0.4064)
			(stroke
				(width 0.1524)
				(type default)
			)
			(layer "F.SilkS")
		)
		(fp_line
			(start 0 0.381)
			(end 0 -0.381)
			(stroke
				(width 0.1524)
				(type default)
			)
			(layer "F.SilkS")
		)
		(fp_line
			(start -0.7874 -0.4064)
			(end 0.7874 -0.4064)
			(stroke
				(width 0.1524)
				(type default)
			)
			(layer "F.SilkS")
		)
		(fp_line
			(start 0.7874 -0.4064)
			(end 0.7874 0.4064)
			(stroke
				(width 0.1524)
				(type default)
			)
			(layer "F.SilkS")
		)
		(fp_poly
			(pts
				(xy -0.5334 0.254) (xy -0.635 0.254) (xy -0.635 0.2286) (xy -0.635 -0.254) (xy -0.5334 -0.254) (xy -0.5334 -0.2794)
				(xy 0.5334 -0.2794) (xy 0.5334 -0.254) (xy 0.635 -0.254) (xy 0.635 0.254) (xy 0.5334 0.254) (xy 0.5334 0.2794)
				(xy -0.508 0.2794) (xy -0.5334 0.2794)
			)
			(stroke
				(width 0)
				(type default)
			)
			(fill no)
			(layer "F.CrtYd")
		)
		(pad "1" smd rect
			(at 0.40005 0 270)
			(size 0.4572 0.508)
			(layers "F.Cu" "F.Mask" "F.Paste")
			(net "P12V")
		)
		(pad "2" smd rect
			(at -0.40005 0 270)
			(size 0.4572 0.508)
			(layers "F.Cu" "F.Mask" "F.Paste")
			(net "GND")
		)
	)
	(footprint ""
		(layer "F.Cu")
		(at 25.804876 -369.095274)
		(property "Reference" "R138"
			(at -3.886962 -0.631952 0)
			(unlocked yes)
			(layer "F.SilkS")
			(effects
				(font
					(size 0.7874 0.5842)
					(thickness 0.1524)
				)
				(justify left)
			)
		)
		(property "Value" ""
			(at 0 0 0)
			(layer "F.Fab")
			(effects
				(font
					(size 1.27 1.27)
				)
			)
		)
		(duplicate_pad_numbers_are_jumpers no)
		(fp_line
			(start -0.7874 -0.4064)
			(end 0.7874 -0.4064)
			(stroke
				(width 0.1524)
				(type default)
			)
			(layer "F.SilkS")
		)
		(fp_line
			(start -0.7874 0.4064)
			(end -0.7874 -0.4064)
			(stroke
				(width 0.1524)
				(type default)
			)
			(layer "F.SilkS")
		)
		(fp_line
			(start 0.7874 -0.4064)
			(end 0.7874 0.4064)
			(stroke
				(width 0.1524)
				(type default)
			)
			(layer "F.SilkS")
		)
		(fp_line
			(start 0.7874 0.4064)
			(end -0.7874 0.4064)
			(stroke
				(width 0.1524)
				(type default)
			)
			(layer "F.SilkS")
		)
		(fp_poly
			(pts
				(xy -0.508 0.2794) (xy -0.508 0.2286) (xy -0.635 0.2286) (xy -0.635 -0.254) (xy -0.5334 -0.254)
				(xy -0.5334 -0.2794) (xy 0.5334 -0.2794) (xy 0.5334 -0.254) (xy 0.635 -0.254) (xy 0.635 0.254) (xy 0.5334 0.254)
				(xy 0.5334 0.2794)
			)
			(stroke
				(width 0)
				(type default)
			)
			(fill no)
			(layer "F.CrtYd")
		)
		(pad "1" smd rect
			(at 0.40005 0)
			(size 0.4572 0.508)
			(layers "F.Cu" "F.Mask" "F.Paste")
			(net "PSU5_CSAHRE")
		)
		(pad "2" smd rect
			(at -0.40005 0)
			(size 0.4572 0.508)
			(layers "F.Cu" "F.Mask" "F.Paste")
			(net "PSU_CSAHRE")
		)
	)
	(footprint ""
		(layer "F.Cu")
		(at 39.85641 -103.52405 180)
		(property "Reference" "R11"
			(at -1.627124 0.025908 0)
			(unlocked yes)
			(layer "F.SilkS")
			(effects
				(font
					(size 0.7874 0.5842)
					(thickness 0.1524)
				)
				(justify left)
			)
		)
		(property "Value" ""
			(at 0 0 180)
			(layer "F.Fab")
			(effects
				(font
					(size 1.27 1.27)
				)
			)
		)
		(duplicate_pad_numbers_are_jumpers no)
		(fp_line
			(start 0.7874 0.4064)
			(end -0.7874 0.4064)
			(stroke
				(width 0.1524)
				(type default)
			)
			(layer "F.SilkS")
		)
		(fp_line
			(start 0.7874 -0.4064)
			(end 0.7874 0.4064)
			(stroke
				(width 0.1524)
				(type default)
			)
			(layer "F.SilkS")
		)
		(fp_line
			(start -0.7874 0.4064)
			(end -0.7874 -0.4064)
			(stroke
				(width 0.1524)
				(type default)
			)
			(layer "F.SilkS")
		)
		(fp_line
			(start -0.7874 -0.4064)
			(end 0.7874 -0.4064)
			(stroke
				(width 0.1524)
				(type default)
			)
			(layer "F.SilkS")
		)
		(fp_poly
			(pts
				(xy -0.508 0.2794) (xy -0.508 0.2286) (xy -0.635 0.2286) (xy -0.635 -0.254) (xy -0.5334 -0.254)
				(xy -0.5334 -0.2794) (xy 0.5334 -0.2794) (xy 0.5334 -0.254) (xy 0.635 -0.254) (xy 0.635 0.254) (xy 0.5334 0.254)
				(xy 0.5334 0.2794)
			)
			(stroke
				(width 0)
				(type default)
			)
			(fill no)
			(layer "F.CrtYd")
		)
		(pad "1" smd rect
			(at 0.40005 0 180)
			(size 0.4572 0.508)
			(layers "F.Cu" "F.Mask" "F.Paste")
			(net "PSU2_RETURN")
		)
		(pad "2" smd rect
			(at -0.40005 0 180)
			(size 0.4572 0.508)
			(layers "F.Cu" "F.Mask" "F.Paste")
			(net "GND")
		)
	)
	(footprint ""
		(layer "F.Cu")
		(at 23.58644 -177.804572 90)
		(property "Reference" "R161"
			(at -1.085342 -4.405884 90)
			(unlocked yes)
			(layer "F.SilkS")
			(effects
				(font
					(size 0.7874 0.5842)
					(thickness 0.1524)
				)
				(justify left)
			)
		)
		(property "Value" ""
			(at 0 0 90)
			(layer "F.Fab")
			(effects
				(font
					(size 1.27 1.27)
				)
			)
		)
		(duplicate_pad_numbers_are_jumpers no)
		(fp_line
			(start 0.7874 -0.4064)
			(end 0.7874 0.4064)
			(stroke
				(width 0.1524)
				(type default)
			)
			(layer "F.SilkS")
		)
		(fp_line
			(start -0.7874 -0.4064)
			(end 0.7874 -0.4064)
			(stroke
				(width 0.1524)
				(type default)
			)
			(layer "F.SilkS")
		)
		(fp_line
			(start 0.7874 0.4064)
			(end -0.7874 0.4064)
			(stroke
				(width 0.1524)
				(type default)
			)
			(layer "F.SilkS")
		)
		(fp_line
			(start -0.7874 0.4064)
			(end -0.7874 -0.4064)
			(stroke
				(width 0.1524)
				(type default)
			)
			(layer "F.SilkS")
		)
		(fp_poly
			(pts
				(xy -0.508 0.2794) (xy -0.508 0.2286) (xy -0.635 0.2286) (xy -0.635 -0.254) (xy -0.5334 -0.254)
				(xy -0.5334 -0.2794) (xy 0.5334 -0.2794) (xy 0.5334 -0.254) (xy 0.635 -0.254) (xy 0.635 0.254) (xy 0.5334 0.254)
				(xy 0.5334 0.2794)
			)
			(stroke
				(width 0)
				(type default)
			)
			(fill no)
			(layer "F.CrtYd")
		)
		(pad "1" smd rect
			(at 0.40005 0 90)
			(size 0.4572 0.508)
			(layers "F.Cu" "F.Mask" "F.Paste")
			(net "N42263600")
		)
		(pad "2" smd rect
			(at -0.40005 0 90)
			(size 0.4572 0.508)
			(layers "F.Cu" "F.Mask" "F.Paste")
			(net "PHLOSS")
		)
	)
	(footprint ""
		(layer "F.Cu")
		(at 46.430692 -238.246666 180)
		(property "Reference" "R88"
			(at 4.272788 0.078232 0)
			(unlocked yes)
			(layer "F.SilkS")
			(effects
				(font
					(size 0.7874 0.5842)
					(thickness 0.1524)
				)
				(justify left)
			)
		)
		(property "Value" ""
			(at 0 0 180)
			(layer "F.Fab")
			(effects
				(font
					(size 1.27 1.27)
				)
			)
		)
		(duplicate_pad_numbers_are_jumpers no)
		(fp_line
			(start 0.7874 0.4064)
			(end -0.7874 0.4064)
			(stroke
				(width 0.1524)
				(type default)
			)
			(layer "F.SilkS")
		)
		(fp_line
			(start 0.7874 -0.4064)
			(end 0.7874 0.4064)
			(stroke
				(width 0.1524)
				(type default)
			)
			(layer "F.SilkS")
		)
		(fp_line
			(start -0.7874 0.4064)
			(end -0.7874 -0.4064)
			(stroke
				(width 0.1524)
				(type default)
			)
			(layer "F.SilkS")
		)
		(fp_line
			(start -0.7874 -0.4064)
			(end 0.7874 -0.4064)
			(stroke
				(width 0.1524)
				(type default)
			)
			(layer "F.SilkS")
		)
		(fp_poly
			(pts
				(xy -0.508 0.2794) (xy -0.508 0.2286) (xy -0.635 0.2286) (xy -0.635 -0.254) (xy -0.5334 -0.254)
				(xy -0.5334 -0.2794) (xy 0.5334 -0.2794) (xy 0.5334 -0.254) (xy 0.635 -0.254) (xy 0.635 0.254) (xy 0.5334 0.254)
				(xy 0.5334 0.2794)
			)
			(stroke
				(width 0)
				(type default)
			)
			(fill no)
			(layer "F.CrtYd")
		)
		(pad "1" smd rect
			(at 0.40005 0 180)
			(size 0.4572 0.508)
			(layers "F.Cu" "F.Mask" "F.Paste")
			(net "PSU1_REMOTE_R_P")
		)
		(pad "2" smd rect
			(at -0.40005 0 180)
			(size 0.4572 0.508)
			(layers "F.Cu" "F.Mask" "F.Paste")
			(net "P12V")
		)
	)
	(footprint ""
		(layer "F.Cu")
		(at 82.499962 -508.115824 -90)
		(property "Reference" "C80"
			(at 3.578606 0.06604 90)
			(unlocked yes)
			(layer "F.SilkS")
			(effects
				(font
					(size 0.7874 0.5842)
					(thickness 0.1524)
				)
				(justify left)
			)
		)
		(property "Value" ""
			(at 0 0 270)
			(layer "F.Fab")
			(effects
				(font
					(size 1.27 1.27)
				)
			)
		)
		(duplicate_pad_numbers_are_jumpers no)
		(fp_line
			(start -0.7874 0.4064)
			(end -0.7874 -0.4064)
			(stroke
				(width 0.1524)
				(type default)
			)
			(layer "F.SilkS")
		)
		(fp_line
			(start 0.7874 0.4064)
			(end -0.7874 0.4064)
			(stroke
				(width 0.1524)
				(type default)
			)
			(layer "F.SilkS")
		)
		(fp_line
			(start 0 0.381)
			(end 0 -0.381)
			(stroke
				(width 0.1524)
				(type default)
			)
			(layer "F.SilkS")
		)
		(fp_line
			(start -0.7874 -0.4064)
			(end 0.7874 -0.4064)
			(stroke
				(width 0.1524)
				(type default)
			)
			(layer "F.SilkS")
		)
		(fp_line
			(start 0.7874 -0.4064)
			(end 0.7874 0.4064)
			(stroke
				(width 0.1524)
				(type default)
			)
			(layer "F.SilkS")
		)
		(fp_poly
			(pts
				(xy -0.5334 0.254) (xy -0.635 0.254) (xy -0.635 0.2286) (xy -0.635 -0.254) (xy -0.5334 -0.254) (xy -0.5334 -0.2794)
				(xy 0.5334 -0.2794) (xy 0.5334 -0.254) (xy 0.635 -0.254) (xy 0.635 0.254) (xy 0.5334 0.254) (xy 0.5334 0.2794)
				(xy -0.508 0.2794) (xy -0.5334 0.2794)
			)
			(stroke
				(width 0)
				(type default)
			)
			(fill no)
			(layer "F.CrtYd")
		)
		(pad "1" smd rect
			(at 0.40005 0 270)
			(size 0.4572 0.508)
			(layers "F.Cu" "F.Mask" "F.Paste")
			(net "P12V")
		)
		(pad "2" smd rect
			(at -0.40005 0 270)
			(size 0.4572 0.508)
			(layers "F.Cu" "F.Mask" "F.Paste")
			(net "GND")
		)
	)
	(footprint ""
		(layer "F.Cu")
		(at 39.849552 -17.30502 180)
		(property "Reference" "R12"
			(at -1.74498 -0.093472 0)
			(unlocked yes)
			(layer "F.SilkS")
			(effects
				(font
					(size 0.7874 0.5842)
					(thickness 0.1524)
				)
				(justify left)
			)
		)
		(property "Value" ""
			(at 0 0 180)
			(layer "F.Fab")
			(effects
				(font
					(size 1.27 1.27)
				)
			)
		)
		(duplicate_pad_numbers_are_jumpers no)
		(fp_line
			(start 0.7874 0.4064)
			(end -0.7874 0.4064)
			(stroke
				(width 0.1524)
				(type default)
			)
			(layer "F.SilkS")
		)
		(fp_line
			(start 0.7874 -0.4064)
			(end 0.7874 0.4064)
			(stroke
				(width 0.1524)
				(type default)
			)
			(layer "F.SilkS")
		)
		(fp_line
			(start -0.7874 0.4064)
			(end -0.7874 -0.4064)
			(stroke
				(width 0.1524)
				(type default)
			)
			(layer "F.SilkS")
		)
		(fp_line
			(start -0.7874 -0.4064)
			(end 0.7874 -0.4064)
			(stroke
				(width 0.1524)
				(type default)
			)
			(layer "F.SilkS")
		)
		(fp_poly
			(pts
				(xy -0.508 0.2794) (xy -0.508 0.2286) (xy -0.635 0.2286) (xy -0.635 -0.254) (xy -0.5334 -0.254)
				(xy -0.5334 -0.2794) (xy 0.5334 -0.2794) (xy 0.5334 -0.254) (xy 0.635 -0.254) (xy 0.635 0.254) (xy 0.5334 0.254)
				(xy 0.5334 0.2794)
			)
			(stroke
				(width 0)
				(type default)
			)
			(fill no)
			(layer "F.CrtYd")
		)
		(pad "1" smd rect
			(at 0.40005 0 180)
			(size 0.4572 0.508)
			(layers "F.Cu" "F.Mask" "F.Paste")
			(net "PSU1_AD0")
		)
		(pad "2" smd rect
			(at -0.40005 0 180)
			(size 0.4572 0.508)
			(layers "F.Cu" "F.Mask" "F.Paste")
			(net "GND")
		)
	)
	(footprint ""
		(layer "F.Cu")
		(at 16.599916 -473.69984)
		(property "Reference" "H8"
			(at -6.4516 -7.127748 0)
			(unlocked yes)
			(layer "F.SilkS")
			(effects
				(font
					(size 0.7874 0.5842)
					(thickness 0.1524)
				)
				(justify left)
			)
		)
		(property "Value" ""
			(at 0 0 0)
			(layer "F.Fab")
			(effects
				(font
					(size 1.27 1.27)
				)
			)
		)
		(duplicate_pad_numbers_are_jumpers no)
		(fp_circle
			(center 0 0)
			(end 7.999984 0)
			(stroke
				(width 0.1524)
				(type default)
			)
			(fill no)
			(layer "F.SilkS")
		)
		(fp_circle
			(center 0 0)
			(end 14.7066 0)
			(stroke
				(width 0.1524)
				(type default)
			)
			(fill no)
			(layer "B.SilkS")
		)
		(fp_poly
			(pts
				(arc
					(start 0 5.0038)
					(mid 0 -5.0038)
					(end 0 5.0038)
				)
			)
			(stroke
				(width 0)
				(type default)
			)
			(fill no)
			(layer "F.CrtYd")
		)
		(pad "" np_thru_hole circle
			(at 0 0)
			(size 4.0132 4.0132)
			(drill 4.0132)
			(layers "*.Cu" "*.Mask")
			(clearance 0.381)
			(thermal_gap 0.381)
		)
		(pad "2" thru_hole circle
			(at 0 -3.50012)
			(size 0.762 0.762)
			(drill 0.5588)
			(layers "*.Cu" "*.Mask")
			(remove_unused_layers no)
			(net "GND")
			(clearance 0.1524)
			(thermal_gap 0.1524)
		)
		(pad "3" thru_hole circle
			(at -2.500122 -2.500122)
			(size 0.762 0.762)
			(drill 0.5588)
			(layers "*.Cu" "*.Mask")
			(remove_unused_layers no)
			(net "GND")
			(clearance 0.1524)
			(thermal_gap 0.1524)
		)
		(pad "4" thru_hole circle
			(at -3.50012 0)
			(size 0.762 0.762)
			(drill 0.5588)
			(layers "*.Cu" "*.Mask")
			(remove_unused_layers no)
			(net "GND")
			(clearance 0.1524)
			(thermal_gap 0.1524)
		)
		(pad "5" thru_hole circle
			(at -2.500122 2.500122)
			(size 0.762 0.762)
			(drill 0.5588)
			(layers "*.Cu" "*.Mask")
			(remove_unused_layers no)
			(net "GND")
			(clearance 0.1524)
			(thermal_gap 0.1524)
		)
		(pad "6" thru_hole circle
			(at 0 3.50012)
			(size 0.762 0.762)
			(drill 0.5588)
			(layers "*.Cu" "*.Mask")
			(remove_unused_layers no)
			(net "GND")
			(clearance 0.1524)
			(thermal_gap 0.1524)
		)
		(pad "7" thru_hole circle
			(at 2.500122 2.500122)
			(size 0.762 0.762)
			(drill 0.5588)
			(layers "*.Cu" "*.Mask")
			(remove_unused_layers no)
			(net "GND")
			(clearance 0.1524)
			(thermal_gap 0.1524)
		)
		(pad "8" thru_hole circle
			(at 3.50012 0)
			(size 0.762 0.762)
			(drill 0.5588)
			(layers "*.Cu" "*.Mask")
			(remove_unused_layers no)
			(net "GND")
			(clearance 0.1524)
			(thermal_gap 0.1524)
		)
		(pad "9" thru_hole circle
			(at 2.500122 -2.500122)
			(size 0.762 0.762)
			(drill 0.5588)
			(layers "*.Cu" "*.Mask")
			(remove_unused_layers no)
			(net "GND")
			(clearance 0.1524)
			(thermal_gap 0.1524)
		)
		(zone
			(layer "F.Cu")
			(hatch none 0.5)
			(connect_pads
				(clearance 0)
			)
			(min_thickness 0.25)
			(keepout
				(tracks not_allowed)
				(vias allowed)
				(pads allowed)
				(copperpour not_allowed)
				(footprints allowed)
			)
			(placement
				(enabled no)
				(sheetname "")
			)
			(fill
				(thermal_gap 0.5)
				(thermal_bridge_width 0.5)
				(island_removal_mode 0)
			)
			(polygon
				(pts
					(arc
						(start 16.599916 -481.70084)
						(mid 8.598916 -473.69984)
						(end 16.599916 -465.69884)
					)
					(arc
						(start 16.599916 -465.69884)
						(mid 18.035016 -467.13394)
						(end 16.599916 -468.56904)
					)
					(arc
						(start 16.599916 -468.56904)
						(mid 11.469116 -473.69984)
						(end 16.599916 -478.83064)
					)
					(arc
						(start 16.599916 -478.83064)
						(mid 18.035016 -480.26574)
						(end 16.599916 -481.70084)
					)
				)
			)
		)
		(zone
			(layer "F.Cu")
			(hatch none 0.5)
			(connect_pads
				(clearance 0)
			)
			(min_thickness 0.25)
			(keepout
				(tracks not_allowed)
				(vias allowed)
				(pads allowed)
				(copperpour not_allowed)
				(footprints allowed)
			)
			(placement
				(enabled no)
				(sheetname "")
			)
			(fill
				(thermal_gap 0.5)
				(thermal_bridge_width 0.5)
				(island_removal_mode 0)
			)
			(polygon
				(pts
					(arc
						(start 16.599916 -481.70084)
						(mid 24.600916 -473.69984)
						(end 16.599916 -465.69884)
					)
					(arc
						(start 16.599916 -465.69884)
						(mid 15.164816 -467.13394)
						(end 16.599916 -468.56904)
					)
					(arc
						(start 16.599916 -468.56904)
						(mid 21.730716 -473.69984)
						(end 16.599916 -478.83064)
					)
					(arc
						(start 16.599916 -478.83064)
						(mid 15.164816 -480.26574)
						(end 16.599916 -481.70084)
					)
				)
			)
		)
		(zone
			(layers "F.Cu" "B.Cu" "In1.Cu" "In2.Cu" "In3.Cu" "In4.Cu" "In5.Cu" "In6.Cu")
			(hatch none 0.5)
			(connect_pads
				(clearance 0)
			)
			(min_thickness 0.25)
			(keepout
				(tracks not_allowed)
				(vias allowed)
				(pads allowed)
				(copperpour not_allowed)
				(footprints allowed)
			)
			(placement
				(enabled no)
				(sheetname "")
			)
			(fill
				(thermal_gap 0.5)
				(thermal_bridge_width 0.5)
				(island_removal_mode 0)
			)
			(polygon
				(pts
					(arc
						(start 16.599916 -471.18778)
						(mid 16.599916 -476.2119)
						(end 16.599916 -471.18778)
					)
				)
			)
		)
	)
	(footprint ""
		(layer "F.Cu")
		(at 77.999844 -430.150016)
		(property "Reference" "H3"
			(at -7.733284 -6.395466 0)
			(unlocked yes)
			(layer "F.SilkS")
			(effects
				(font
					(size 0.7874 0.5842)
					(thickness 0.1524)
				)
				(justify left)
			)
		)
		(property "Value" ""
			(at 0 0 0)
			(layer "F.Fab")
			(effects
				(font
					(size 1.27 1.27)
				)
			)
		)
		(duplicate_pad_numbers_are_jumpers no)
		(fp_circle
			(center 0 0)
			(end 7.999984 0)
			(stroke
				(width 0.1524)
				(type default)
			)
			(fill no)
			(layer "F.SilkS")
		)
		(fp_arc
			(start -4.620006 -13.962126)
			(mid 8.612183 -11.921174)
			(end 14.7066 0)
			(stroke
				(width 0.1524)
				(type default)
			)
			(layer "B.SilkS")
		)
		(fp_arc
			(start 14.7066 0)
			(mid -8.042606 12.311424)
			(end -5.908802 -13.467334)
			(stroke
				(width 0.1524)
				(type default)
			)
			(layer "B.SilkS")
		)
		(fp_poly
			(pts
				(arc
					(start 5.0038 0)
					(mid -5.0038 0)
					(end 5.0038 0)
				)
			)
			(stroke
				(width 0)
				(type default)
			)
			(fill no)
			(layer "F.CrtYd")
		)
		(pad "" np_thru_hole circle
			(at 0 0)
			(size 4.0132 4.0132)
			(drill 4.0132)
			(layers "*.Cu" "*.Mask")
			(clearance 0.381)
			(thermal_gap 0.381)
		)
		(pad "2" thru_hole circle
			(at 0 -3.50012)
			(size 0.762 0.762)
			(drill 0.5588)
			(layers "*.Cu" "*.Mask")
			(remove_unused_layers no)
			(net "GND")
			(clearance 0.1524)
			(thermal_gap 0.1524)
		)
		(pad "3" thru_hole circle
			(at -2.500122 -2.500122)
			(size 0.762 0.762)
			(drill 0.5588)
			(layers "*.Cu" "*.Mask")
			(remove_unused_layers no)
			(net "GND")
			(clearance 0.1524)
			(thermal_gap 0.1524)
		)
		(pad "4" thru_hole circle
			(at -3.50012 0)
			(size 0.762 0.762)
			(drill 0.5588)
			(layers "*.Cu" "*.Mask")
			(remove_unused_layers no)
			(net "GND")
			(clearance 0.1524)
			(thermal_gap 0.1524)
		)
		(pad "5" thru_hole circle
			(at -2.500122 2.500122)
			(size 0.762 0.762)
			(drill 0.5588)
			(layers "*.Cu" "*.Mask")
			(remove_unused_layers no)
			(net "GND")
			(clearance 0.1524)
			(thermal_gap 0.1524)
		)
		(pad "6" thru_hole circle
			(at 0 3.50012)
			(size 0.762 0.762)
			(drill 0.5588)
			(layers "*.Cu" "*.Mask")
			(remove_unused_layers no)
			(net "GND")
			(clearance 0.1524)
			(thermal_gap 0.1524)
		)
		(pad "7" thru_hole circle
			(at 2.500122 2.500122)
			(size 0.762 0.762)
			(drill 0.5588)
			(layers "*.Cu" "*.Mask")
			(remove_unused_layers no)
			(net "GND")
			(clearance 0.1524)
			(thermal_gap 0.1524)
		)
		(pad "8" thru_hole circle
			(at 3.50012 0)
			(size 0.762 0.762)
			(drill 0.5588)
			(layers "*.Cu" "*.Mask")
			(remove_unused_layers no)
			(net "GND")
			(clearance 0.1524)
			(thermal_gap 0.1524)
		)
		(pad "9" thru_hole circle
			(at 2.500122 -2.500122)
			(size 0.762 0.762)
			(drill 0.5588)
			(layers "*.Cu" "*.Mask")
			(remove_unused_layers no)
			(net "GND")
			(clearance 0.1524)
			(thermal_gap 0.1524)
		)
		(zone
			(layer "F.Cu")
			(hatch none 0.5)
			(connect_pads
				(clearance 0)
			)
			(min_thickness 0.25)
			(keepout
				(tracks not_allowed)
				(vias allowed)
				(pads allowed)
				(copperpour not_allowed)
				(footprints allowed)
			)
			(placement
				(enabled no)
				(sheetname "")
			)
			(fill
				(thermal_gap 0.5)
				(thermal_bridge_width 0.5)
				(island_removal_mode 0)
			)
			(polygon
				(pts
					(arc
						(start 77.999844 -438.151016)
						(mid 69.998844 -430.150016)
						(end 77.999844 -422.149016)
					)
					(arc
						(start 77.999844 -422.149016)
						(mid 79.434944 -423.584116)
						(end 77.999844 -425.019216)
					)
					(arc
						(start 77.999844 -425.019216)
						(mid 72.869044 -430.150016)
						(end 77.999844 -435.280816)
					)
					(arc
						(start 77.999844 -435.280816)
						(mid 79.434944 -436.715916)
						(end 77.999844 -438.151016)
					)
				)
			)
		)
		(zone
			(layer "F.Cu")
			(hatch none 0.5)
			(connect_pads
				(clearance 0)
			)
			(min_thickness 0.25)
			(keepout
				(tracks not_allowed)
				(vias allowed)
				(pads allowed)
				(copperpour not_allowed)
				(footprints allowed)
			)
			(placement
				(enabled no)
				(sheetname "")
			)
			(fill
				(thermal_gap 0.5)
				(thermal_bridge_width 0.5)
				(island_removal_mode 0)
			)
			(polygon
				(pts
					(arc
						(start 77.999844 -438.151016)
						(mid 86.000844 -430.150016)
						(end 77.999844 -422.149016)
					)
					(arc
						(start 77.999844 -422.149016)
						(mid 76.564744 -423.584116)
						(end 77.999844 -425.019216)
					)
					(arc
						(start 77.999844 -425.019216)
						(mid 83.130644 -430.150016)
						(end 77.999844 -435.280816)
					)
					(arc
						(start 77.999844 -435.280816)
						(mid 76.564744 -436.715916)
						(end 77.999844 -438.151016)
					)
				)
			)
		)
		(zone
			(layers "F.Cu" "B.Cu" "In1.Cu" "In2.Cu" "In3.Cu" "In4.Cu" "In5.Cu" "In6.Cu")
			(hatch none 0.5)
			(connect_pads
				(clearance 0)
			)
			(min_thickness 0.25)
			(keepout
				(tracks not_allowed)
				(vias allowed)
				(pads allowed)
				(copperpour not_allowed)
				(footprints allowed)
			)
			(placement
				(enabled no)
				(sheetname "")
			)
			(fill
				(thermal_gap 0.5)
				(thermal_bridge_width 0.5)
				(island_removal_mode 0)
			)
			(polygon
				(pts
					(arc
						(start 80.511904 -430.150016)
						(mid 75.487784 -430.150016)
						(end 80.511904 -430.150016)
					)
				)
			)
		)
	)
	(footprint ""
		(layer "F.Cu")
		(at 5.780024 -517.049766)
		(property "Reference" "J32"
			(at -1.9304 -3.978148 0)
			(unlocked yes)
			(layer "F.SilkS")
			(effects
				(font
					(size 0.7874 0.5842)
					(thickness 0.1524)
				)
				(justify left)
			)
		)
		(property "Value" ""
			(at 0 0 0)
			(layer "F.Fab")
			(effects
				(font
					(size 1.27 1.27)
				)
			)
		)
		(duplicate_pad_numbers_are_jumpers no)
		(fp_line
			(start -3.10007 0.199898)
			(end -3.10007 2.800096)
			(stroke
				(width 0.1524)
				(type default)
			)
			(layer "F.SilkS")
		)
		(fp_line
			(start -3.10007 2.800096)
			(end -1.89992 2.800096)
			(stroke
				(width 0.1524)
				(type default)
			)
			(layer "F.SilkS")
		)
		(fp_line
			(start -1.89992 -3.325114)
			(end -1.89992 0.199898)
			(stroke
				(width 0.1524)
				(type default)
			)
			(layer "F.SilkS")
		)
		(fp_line
			(start -1.89992 0.199898)
			(end -3.10007 0.199898)
			(stroke
				(width 0.1524)
				(type default)
			)
			(layer "F.SilkS")
		)
		(fp_line
			(start -1.89992 2.800096)
			(end -1.89992 6.325108)
			(stroke
				(width 0.1524)
				(type default)
			)
			(layer "F.SilkS")
		)
		(fp_line
			(start -1.89992 6.325108)
			(end 1.016 6.325108)
			(stroke
				(width 0.1524)
				(type default)
			)
			(layer "F.SilkS")
		)
		(fp_line
			(start 1.016 -3.325114)
			(end -1.89992 -3.325114)
			(stroke
				(width 0.1524)
				(type default)
			)
			(layer "F.SilkS")
		)
		(fp_line
			(start 2.469896 5.133594)
			(end 2.469896 -2.130806)
			(stroke
				(width 0.1524)
				(type default)
			)
			(layer "F.SilkS")
		)
		(fp_poly
			(pts
				(xy 0.8509 0.8509) (xy -0.8509 0.8509) (xy -0.8509 -0.8509) (xy 0.8509 -0.8509)
			)
			(stroke
				(width 0)
				(type default)
			)
			(fill no)
			(layer "B.CrtYd")
		)
		(fp_poly
			(pts
				(arc
					(start 0.8509 2.999994)
					(mid -0.8509 2.999994)
					(end 0.8509 2.999994)
				)
			)
			(stroke
				(width 0)
				(type default)
			)
			(fill no)
			(layer "B.CrtYd")
		)
		(fp_poly
			(pts
				(arc
					(start 2.874518 -2.999994)
					(mid 1.045718 -2.999994)
					(end 2.874518 -2.999994)
				)
			)
			(stroke
				(width 0)
				(type default)
			)
			(fill no)
			(layer "B.CrtYd")
		)
		(fp_poly
			(pts
				(arc
					(start 2.874518 5.999988)
					(mid 1.045718 5.999988)
					(end 2.874518 5.999988)
				)
			)
			(stroke
				(width 0)
				(type default)
			)
			(fill no)
			(layer "B.CrtYd")
		)
		(fp_poly
			(pts
				(xy 2.469896 5.233924) (xy 2.469896 -2.233676) (xy 2.8956 -2.233676) (xy 2.8956 -3.935476) (xy 1.0922 -3.935476)
				(xy 1.0922 -3.325114) (xy -1.89992 -3.325114) (xy -1.89992 0.199898) (xy -3.10007 0.199898) (xy -3.10007 2.800096)
				(xy -1.89992 2.800096) (xy -1.89992 6.325108) (xy 1.0922 6.325108) (xy 1.0922 6.935724) (xy 2.8956 6.935724)
				(xy 2.8956 5.233924)
			)
			(stroke
				(width 0)
				(type default)
			)
			(fill no)
			(layer "F.CrtYd")
		)
		(fp_line
			(start -3.10007 0.199898)
			(end -3.10007 2.800096)
			(stroke
				(width 0.1)
				(type default)
			)
			(layer "F.Fab")
		)
		(fp_line
			(start -3.10007 2.800096)
			(end -1.89992 2.800096)
			(stroke
				(width 0.1)
				(type default)
			)
			(layer "F.Fab")
		)
		(fp_line
			(start -1.89992 -3.325114)
			(end -1.89992 0.199898)
			(stroke
				(width 0.1)
				(type default)
			)
			(layer "F.Fab")
		)
		(fp_line
			(start -1.89992 0.199898)
			(end -3.10007 0.199898)
			(stroke
				(width 0.1)
				(type default)
			)
			(layer "F.Fab")
		)
		(fp_line
			(start -1.89992 2.800096)
			(end -1.89992 6.325108)
			(stroke
				(width 0.1)
				(type default)
			)
			(layer "F.Fab")
		)
		(fp_line
			(start -1.89992 6.325108)
			(end 2.469896 6.325108)
			(stroke
				(width 0.1)
				(type default)
			)
			(layer "F.Fab")
		)
		(fp_line
			(start 2.469896 -3.325114)
			(end -1.89992 -3.325114)
			(stroke
				(width 0.1)
				(type default)
			)
			(layer "F.Fab")
		)
		(fp_line
			(start 2.469896 6.325108)
			(end 2.469896 -3.325114)
			(stroke
				(width 0.1)
				(type default)
			)
			(layer "F.Fab")
		)
		(pad "" np_thru_hole circle
			(at 1.960118 -2.999994 90)
			(size 1.3208 1.3208)
			(drill 1.3208)
			(layers "*.Cu" "*.Mask")
			(clearance 0.381)
			(thermal_gap 0.381)
		)
		(pad "" np_thru_hole circle
			(at 1.960118 5.999988 90)
			(size 1.3208 1.3208)
			(drill 1.3208)
			(layers "*.Cu" "*.Mask")
			(clearance 0.381)
			(thermal_gap 0.381)
		)
		(pad "1" thru_hole rect
			(at 0 0 90)
			(size 1.6002 1.6002)
			(drill 1.0922)
			(layers "*.Cu" "*.Mask")
			(remove_unused_layers no)
			(net "POWER_SW1_PWR_CTR_12V")
			(clearance 0)
			(padstack
				(mode front_inner_back)
				(layer "Inner"
					(shape circle)
					(size 1.6002 1.6002)
					(clearance 0)
				)
				(layer "B.Cu"
					(shape rect)
					(size 1.6002 1.6002)
					(clearance 0)
				)
			)
		)
		(pad "2" thru_hole circle
			(at 0 2.999994 90)
			(size 1.6002 1.6002)
			(drill 1.0922)
			(layers "*.Cu" "*.Mask")
			(remove_unused_layers no)
			(net "GND")
			(clearance 0)
		)
		(zone
			(layers "F.Cu" "B.Cu" "In1.Cu" "In2.Cu" "In3.Cu" "In4.Cu" "In5.Cu" "In6.Cu")
			(hatch none 0.5)
			(connect_pads
				(clearance 0)
			)
			(min_thickness 0.25)
			(keepout
				(tracks not_allowed)
				(vias allowed)
				(pads allowed)
				(copperpour not_allowed)
				(footprints allowed)
			)
			(placement
				(enabled no)
				(sheetname "")
			)
			(fill
				(thermal_gap 0.5)
				(thermal_bridge_width 0.5)
				(island_removal_mode 0)
			)
			(polygon
				(pts
					(arc
						(start 8.806942 -520.04976)
						(mid 6.673342 -520.04976)
						(end 8.806942 -520.04976)
					)
				)
			)
		)
		(zone
			(layers "F.Cu" "B.Cu" "In1.Cu" "In2.Cu" "In3.Cu" "In4.Cu" "In5.Cu" "In6.Cu")
			(hatch none 0.5)
			(connect_pads
				(clearance 0)
			)
			(min_thickness 0.25)
			(keepout
				(tracks not_allowed)
				(vias allowed)
				(pads allowed)
				(copperpour not_allowed)
				(footprints allowed)
			)
			(placement
				(enabled no)
				(sheetname "")
			)
			(fill
				(thermal_gap 0.5)
				(thermal_bridge_width 0.5)
				(island_removal_mode 0)
			)
			(polygon
				(pts
					(arc
						(start 8.806942 -511.049778)
						(mid 6.673342 -511.049778)
						(end 8.806942 -511.049778)
					)
				)
			)
		)
	)
	(footprint ""
		(layer "F.Cu")
		(at 14.034516 -140.843 -90)
		(property "Reference" "J29"
			(at -5.54101 6.072378 0)
			(unlocked yes)
			(layer "F.SilkS")
			(effects
				(font
					(size 0.7874 0.5842)
					(thickness 0.1524)
				)
				(justify left)
			)
		)
		(property "Value" ""
			(at 0 0 270)
			(layer "F.Fab")
			(effects
				(font
					(size 1.27 1.27)
				)
			)
		)
		(duplicate_pad_numbers_are_jumpers no)
		(fp_line
			(start -3.754882 12.899898)
			(end -3.754882 3.7846)
			(stroke
				(width 0.1524)
				(type default)
			)
			(layer "F.SilkS")
		)
		(fp_line
			(start 12.644882 12.899898)
			(end -3.754882 12.899898)
			(stroke
				(width 0.1524)
				(type default)
			)
			(layer "F.SilkS")
		)
		(fp_line
			(start 12.644882 3.7846)
			(end 12.644882 12.899898)
			(stroke
				(width 0.1524)
				(type default)
			)
			(layer "F.SilkS")
		)
		(fp_line
			(start -3.754882 1.2192)
			(end -3.754882 -3.800094)
			(stroke
				(width 0.1524)
				(type default)
			)
			(layer "F.SilkS")
		)
		(fp_line
			(start -3.754882 -3.800094)
			(end 12.644882 -3.800094)
			(stroke
				(width 0.1524)
				(type default)
			)
			(layer "F.SilkS")
		)
		(fp_line
			(start 12.644882 -3.800094)
			(end 12.644882 1.2192)
			(stroke
				(width 0.1524)
				(type default)
			)
			(layer "F.SilkS")
		)
		(fp_poly
			(pts
				(xy -4.125214 0) (xy -5.806186 0.840486) (xy -5.806186 -0.840486)
			)
			(stroke
				(width 0)
				(type default)
			)
			(fill yes)
			(layer "F.SilkS")
		)
		(fp_poly
			(pts
				(xy -2.591562 11.176) (xy 1.370838 11.176) (xy 1.370838 9.7282) (xy -2.591562 9.7282)
			)
			(stroke
				(width 0)
				(type default)
			)
			(fill no)
			(layer "B.CrtYd")
		)
		(fp_poly
			(pts
				(xy 7.5184 11.176) (xy 11.4808 11.176) (xy 11.4808 9.7282) (xy 7.5184 9.7282)
			)
			(stroke
				(width 0)
				(type default)
			)
			(fill no)
			(layer "B.CrtYd")
		)
		(fp_poly
			(pts
				(xy 9.627362 -3.256026) (xy 9.627362 -1.808226) (xy 8.357362 -1.808226) (xy 8.357362 0.731774) (xy -0.735838 0.731774)
				(xy -0.735838 -0.741426) (xy 0.534162 -0.741426) (xy 0.534162 -3.256026)
			)
			(stroke
				(width 0)
				(type default)
			)
			(fill no)
			(layer "B.CrtYd")
		)
		(fp_poly
			(pts
				(arc
					(start 12.320016 1.268222)
					(mid 12.320016 3.732022)
					(end 12.320016 1.268222)
				)
			)
			(stroke
				(width 0)
				(type default)
			)
			(fill no)
			(layer "B.CrtYd")
		)
		(fp_poly
			(pts
				(arc
					(start -3.430016 1.267968)
					(mid -3.430016 3.732276)
					(end -3.430016 1.267968)
				)
			)
			(stroke
				(width 0)
				(type default)
			)
			(fill no)
			(layer "B.CrtYd")
		)
		(fp_poly
			(pts
				(arc
					(start -1.27 4.4958)
					(mid -1.27 8.2042)
					(end -1.27 4.4958)
				)
			)
			(stroke
				(width 0)
				(type default)
			)
			(fill no)
			(layer "B.CrtYd")
		)
		(fp_poly
			(pts
				(arc
					(start 10.16 4.4958)
					(mid 10.16 8.2042)
					(end 10.16 4.4958)
				)
			)
			(stroke
				(width 0)
				(type default)
			)
			(fill no)
			(layer "B.CrtYd")
		)
		(fp_poly
			(pts
				(xy -3.754882 12.899898)
				(arc
					(start -3.754882 3.688334)
					(mid -4.662083 2.499901)
					(end -3.754882 1.311656)
				)
				(xy -3.754882 -3.800094) (xy 12.644882 -3.800094)
				(arc
					(start 12.644882 1.311656)
					(mid 13.551838 2.499901)
					(end 12.644882 3.688334)
				)
				(xy 12.644882 12.899898)
			)
			(stroke
				(width 0)
				(type default)
			)
			(fill no)
			(layer "F.CrtYd")
		)
		(fp_line
			(start -3.754882 12.899898)
			(end -3.754882 -3.800094)
			(stroke
				(width 0.1)
				(type default)
			)
			(layer "F.Fab")
		)
		(fp_line
			(start 12.644882 12.899898)
			(end -3.754882 12.899898)
			(stroke
				(width 0.1)
				(type default)
			)
			(layer "F.Fab")
		)
		(fp_line
			(start -3.754882 -3.800094)
			(end 12.644882 -3.800094)
			(stroke
				(width 0.1)
				(type default)
			)
			(layer "F.Fab")
		)
		(fp_line
			(start 12.644882 -3.800094)
			(end 12.644882 12.899898)
			(stroke
				(width 0.1)
				(type default)
			)
			(layer "F.Fab")
		)
		(fp_poly
			(pts
				(xy -4.125214 0) (xy -5.806186 0.840486) (xy -5.806186 -0.840486)
			)
			(stroke
				(width 0)
				(type default)
			)
			(fill yes)
			(layer "F.Fab")
		)
		(fp_text user "7"
			(at 13.536168 0.140208 0)
			(unlocked yes)
			(layer "F.SilkS")
			(effects
				(font
					(size 0.7874 0.5842)
					(thickness 0.1524)
				)
			)
		)
		(fp_text user "1"
			(at -4.496054 -0.829564 0)
			(unlocked yes)
			(layer "F.SilkS")
			(effects
				(font
					(size 0.7874 0.5842)
					(thickness 0.1524)
				)
			)
		)
		(fp_text user "8"
			(at 13.458952 -2.92354 0)
			(unlocked yes)
			(layer "F.SilkS")
			(effects
				(font
					(size 0.7874 0.5842)
					(thickness 0.1524)
				)
			)
		)
		(fp_text user "2"
			(at -4.559808 -3.01117 0)
			(unlocked yes)
			(layer "F.SilkS")
			(effects
				(font
					(size 0.7874 0.5842)
					(thickness 0.1524)
				)
			)
		)
		(fp_text user "7"
			(at 9.144762 0.002794 0)
			(unlocked yes)
			(layer "B.SilkS")
			(effects
				(font
					(size 0.7874 0.5842)
					(thickness 0.1524)
				)
				(justify mirror)
			)
		)
		(fp_text user "1"
			(at -1.343152 -0.034544 0)
			(unlocked yes)
			(layer "B.SilkS")
			(effects
				(font
					(size 0.7874 0.5842)
					(thickness 0.1524)
				)
				(justify mirror)
			)
		)
		(fp_text user "8"
			(at 10.402062 -2.562606 0)
			(unlocked yes)
			(layer "B.SilkS")
			(effects
				(font
					(size 0.7874 0.5842)
					(thickness 0.1524)
				)
				(justify mirror)
			)
		)
		(fp_text user "2"
			(at -0.225552 -2.612644 0)
			(unlocked yes)
			(layer "B.SilkS")
			(effects
				(font
					(size 0.7874 0.5842)
					(thickness 0.1524)
				)
				(justify mirror)
			)
		)
		(fp_text user "7"
			(at 8.8646 0.085852 270)
			(unlocked yes)
			(layer "B.Fab")
			(effects
				(font
					(size 0.7874 0.5842)
					(thickness 0.000001)
				)
				(justify mirror)
			)
		)
		(fp_text user "1"
			(at -1.1811 -0.053848 270)
			(unlocked yes)
			(layer "B.Fab")
			(effects
				(font
					(size 0.7874 0.5842)
					(thickness 0.000001)
				)
				(justify mirror)
			)
		)
		(fp_text user "8"
			(at 10.1219 -2.479548 270)
			(unlocked yes)
			(layer "B.Fab")
			(effects
				(font
					(size 0.7874 0.5842)
					(thickness 0.000001)
				)
				(justify mirror)
			)
		)
		(fp_text user "2"
			(at -0.0635 -2.631948 270)
			(unlocked yes)
			(layer "B.Fab")
			(effects
				(font
					(size 0.7874 0.5842)
					(thickness 0.000001)
				)
				(justify mirror)
			)
		)
		(fp_text user "7"
			(at 13.2334 -0.079248 270)
			(unlocked yes)
			(layer "F.Fab")
			(effects
				(font
					(size 0.7874 0.5842)
					(thickness 0.000001)
				)
			)
		)
		(fp_text user "1"
			(at -4.4323 -1.019048 270)
			(unlocked yes)
			(layer "F.Fab")
			(effects
				(font
					(size 0.7874 0.5842)
					(thickness 0.000001)
				)
			)
		)
		(fp_text user "2"
			(at -4.4704 -2.581148 270)
			(unlocked yes)
			(layer "F.Fab")
			(effects
				(font
					(size 0.7874 0.5842)
					(thickness 0.000001)
				)
			)
		)
		(fp_text user "8"
			(at 13.2715 -2.593848 270)
			(unlocked yes)
			(layer "F.Fab")
			(effects
				(font
					(size 0.7874 0.5842)
					(thickness 0.000001)
				)
			)
		)
		(pad "" np_thru_hole circle
			(at -1.27 6.35 270)
			(size 3.2004 3.2004)
			(drill 3.2004)
			(layers "*.Cu" "*.Mask")
			(clearance 0.381)
			(thermal_gap 0.381)
		)
		(pad "" np_thru_hole circle
			(at 10.16 6.35 270)
			(size 3.2004 3.2004)
			(drill 3.2004)
			(layers "*.Cu" "*.Mask")
			(clearance 0.381)
			(thermal_gap 0.381)
		)
		(pad "1" thru_hole rect
			(at 0 0 270)
			(size 1.3208 1.3208)
			(drill 0.9144)
			(layers "*.Cu" "*.Mask")
			(remove_unused_layers no)
			(net "LAN1_P1_P")
			(clearance 0.0508)
			(thermal_gap 0.0508)
			(padstack
				(mode front_inner_back)
				(layer "Inner"
					(shape circle)
					(size 1.3208 1.3208)
					(clearance 0.0508)
				)
				(layer "B.Cu"
					(shape rect)
					(size 1.3208 1.3208)
					(clearance 0.0508)
				)
			)
		)
		(pad "2" thru_hole circle
			(at 1.27 -2.54 270)
			(size 1.3208 1.3208)
			(drill 0.9144)
			(layers "*.Cu" "*.Mask")
			(remove_unused_layers no)
			(net "LAN1_P1_N")
			(clearance 0.0508)
			(thermal_gap 0.0508)
		)
		(pad "3" thru_hole circle
			(at 2.54 0 270)
			(size 1.3208 1.3208)
			(drill 0.9144)
			(layers "*.Cu" "*.Mask")
			(remove_unused_layers no)
			(net "LAN1_P2_P")
			(clearance 0.0508)
			(thermal_gap 0.0508)
		)
		(pad "4" thru_hole circle
			(at 3.81 -2.54 270)
			(size 1.3208 1.3208)
			(drill 0.9144)
			(layers "*.Cu" "*.Mask")
			(remove_unused_layers no)
			(net "LAN1_P3_P")
			(clearance 0.0508)
			(thermal_gap 0.0508)
		)
		(pad "5" thru_hole circle
			(at 5.08 0 270)
			(size 1.3208 1.3208)
			(drill 0.9144)
			(layers "*.Cu" "*.Mask")
			(remove_unused_layers no)
			(net "LAN1_P3_N")
			(clearance 0.0508)
			(thermal_gap 0.0508)
		)
		(pad "6" thru_hole circle
			(at 6.35 -2.54 270)
			(size 1.3208 1.3208)
			(drill 0.9144)
			(layers "*.Cu" "*.Mask")
			(remove_unused_layers no)
			(net "LAN1_P2_N")
			(clearance 0.0508)
			(thermal_gap 0.0508)
		)
		(pad "7" thru_hole circle
			(at 7.62 0 270)
			(size 1.3208 1.3208)
			(drill 0.9144)
			(layers "*.Cu" "*.Mask")
			(remove_unused_layers no)
			(net "LAN1_P4_P")
			(clearance 0.0508)
			(thermal_gap 0.0508)
		)
		(pad "8" thru_hole circle
			(at 8.89 -2.54 270)
			(size 1.3208 1.3208)
			(drill 0.9144)
			(layers "*.Cu" "*.Mask")
			(remove_unused_layers no)
			(net "LAN1_P4_N")
			(clearance 0.0508)
			(thermal_gap 0.0508)
		)
		(pad "9" thru_hole circle
			(at -1.854962 10.459974 270)
			(size 1.3208 1.3208)
			(drill 0.9144)
			(layers "*.Cu" "*.Mask")
			(remove_unused_layers no)
			(net "N42126764")
			(clearance 0.0508)
			(thermal_gap 0.0508)
		)
		(pad "10" thru_hole circle
			(at 0.635 10.459974 270)
			(size 1.3208 1.3208)
			(drill 0.9144)
			(layers "*.Cu" "*.Mask")
			(remove_unused_layers no)
			(net "N42126673")
			(clearance 0.0508)
			(thermal_gap 0.0508)
		)
		(pad "11" thru_hole circle
			(at 8.255 10.459974 270)
			(size 1.3208 1.3208)
			(drill 0.9144)
			(layers "*.Cu" "*.Mask")
			(remove_unused_layers no)
			(net "Net_446")
			(clearance 0.0508)
			(thermal_gap 0.0508)
		)
		(pad "12" thru_hole circle
			(at 10.744962 10.459974 270)
			(size 1.3208 1.3208)
			(drill 0.9144)
			(layers "*.Cu" "*.Mask")
			(remove_unused_layers no)
			(net "N42130542")
			(clearance 0.0508)
			(thermal_gap 0.0508)
		)
		(pad "G1" thru_hole circle
			(at -3.430016 2.500122 270)
			(size 2.3622 2.3622)
			(drill 1.6002)
			(layers "*.Cu" "*.Mask")
			(remove_unused_layers no)
			(net "GND")
			(clearance -0.127)
		)
		(pad "G2" thru_hole circle
			(at 12.320016 2.500122 270)
			(size 2.3622 2.3622)
			(drill 1.6002)
			(layers "*.Cu" "*.Mask")
			(remove_unused_layers no)
			(net "GND")
			(clearance -0.127)
		)
		(zone
			(layers "F.Cu" "B.Cu" "In1.Cu" "In2.Cu" "In3.Cu" "In4.Cu" "In5.Cu" "In6.Cu")
			(hatch none 0.5)
			(connect_pads
				(clearance 0)
			)
			(min_thickness 0.25)
			(keepout
				(tracks not_allowed)
				(vias allowed)
				(pads allowed)
				(copperpour not_allowed)
				(footprints allowed)
			)
			(placement
				(enabled no)
				(sheetname "")
			)
			(fill
				(thermal_gap 0.5)
				(thermal_bridge_width 0.5)
				(island_removal_mode 0)
			)
			(polygon
				(pts
					(arc
						(start 9.691116 -142.113)
						(mid 5.677916 -142.113)
						(end 9.691116 -142.113)
					)
				)
			)
		)
		(zone
			(layers "F.Cu" "B.Cu" "In1.Cu" "In2.Cu" "In3.Cu" "In4.Cu" "In5.Cu" "In6.Cu")
			(hatch none 0.5)
			(connect_pads
				(clearance 0)
			)
			(min_thickness 0.25)
			(keepout
				(tracks not_allowed)
				(vias allowed)
				(pads allowed)
				(copperpour not_allowed)
				(footprints allowed)
			)
			(placement
				(enabled no)
				(sheetname "")
			)
			(fill
				(thermal_gap 0.5)
				(thermal_bridge_width 0.5)
				(island_removal_mode 0)
			)
			(polygon
				(pts
					(arc
						(start 9.691116 -130.683)
						(mid 5.677916 -130.683)
						(end 9.691116 -130.683)
					)
				)
			)
		)
	)
	(footprint ""
		(layer "F.Cu")
		(at 50.217324 -173.13783 180)
		(property "Reference" "CE9"
			(at 0.06858 -5.780024 0)
			(unlocked yes)
			(layer "F.SilkS")
			(effects
				(font
					(size 0.7874 0.5842)
					(thickness 0.1524)
				)
				(justify left)
			)
		)
		(property "Value" ""
			(at 0 0 180)
			(layer "F.Fab")
			(effects
				(font
					(size 1.27 1.27)
				)
			)
		)
		(duplicate_pad_numbers_are_jumpers no)
		(fp_line
			(start 0 -4.2672)
			(end 0 4.2672)
			(stroke
				(width 0.1524)
				(type default)
			)
			(layer "F.SilkS")
		)
		(fp_circle
			(center 0 0)
			(end -4.2672 0)
			(stroke
				(width 0.1524)
				(type default)
			)
			(fill no)
			(layer "F.SilkS")
		)
		(fp_poly
			(pts
				(arc
					(start 0 -4.2672)
					(mid 4.2672 0)
					(end 0 4.2672)
				)
			)
			(stroke
				(width 0)
				(type default)
			)
			(fill yes)
			(layer "F.SilkS")
		)
		(fp_poly
			(pts
				(xy -2.5146 -0.762) (xy -0.9906 -0.762) (xy -0.9906 0.762) (xy -2.5146 0.762)
			)
			(stroke
				(width 0)
				(type default)
			)
			(fill no)
			(layer "B.CrtYd")
		)
		(fp_poly
			(pts
				(arc
					(start 1.7526 0.762)
					(mid 2.291415 -0.538815)
					(end 0.9906 0)
				)
				(arc
					(start 0.9906 0.0254)
					(mid 1.206345 0.546255)
					(end 1.7272 0.762)
				)
			)
			(stroke
				(width 0)
				(type default)
			)
			(fill no)
			(layer "B.CrtYd")
		)
		(fp_poly
			(pts
				(arc
					(start -4.2672 0)
					(mid 4.2672 0)
					(end -4.2672 0)
				)
			)
			(stroke
				(width 0)
				(type default)
			)
			(fill no)
			(layer "F.CrtYd")
		)
		(fp_circle
			(center 0 0)
			(end -4.2672 0)
			(stroke
				(width 0.1)
				(type default)
			)
			(fill no)
			(layer "F.Fab")
		)
		(fp_text user "+"
			(at -6.482842 0.822706 180)
			(unlocked yes)
			(layer "F.SilkS")
			(effects
				(font
					(size 1.905 1.4224)
					(thickness 0.1524)
				)
				(justify left)
			)
		)
		(fp_text user "+"
			(at -5.6642 -0.34925 180)
			(unlocked yes)
			(layer "F.Fab")
			(effects
				(font
					(size 1.905 1.4224)
					(thickness 0.000001)
				)
				(justify left)
			)
		)
		(pad "1" thru_hole rect
			(at -1.75006 0 180)
			(size 1.397 1.397)
			(drill 0.9144)
			(layers "*.Cu" "*.Mask")
			(remove_unused_layers no)
			(net "P12V")
			(clearance 0.0127)
			(thermal_gap 0.0127)
			(padstack
				(mode front_inner_back)
				(layer "Inner"
					(shape circle)
					(size 1.397 1.397)
					(clearance 0.0127)
				)
				(layer "B.Cu"
					(shape rect)
					(size 1.397 1.397)
					(clearance 0.0127)
				)
			)
		)
		(pad "2" thru_hole circle
			(at 1.75006 0 180)
			(size 1.397 1.397)
			(drill 0.9144)
			(layers "*.Cu" "*.Mask")
			(remove_unused_layers no)
			(net "GND")
			(clearance 0.0127)
			(thermal_gap 0.0127)
		)
	)
	(footprint ""
		(layer "F.Cu")
		(at 40.157654 -14.412976 180)
		(property "Reference" "R9"
			(at 0.747014 1.214628 0)
			(unlocked yes)
			(layer "F.SilkS")
			(effects
				(font
					(size 0.7874 0.5842)
					(thickness 0.1524)
				)
				(justify left)
			)
		)
		(property "Value" ""
			(at 0 0 180)
			(layer "F.Fab")
			(effects
				(font
					(size 1.27 1.27)
				)
			)
		)
		(duplicate_pad_numbers_are_jumpers no)
		(fp_line
			(start 0.7874 0.4064)
			(end -0.7874 0.4064)
			(stroke
				(width 0.1524)
				(type default)
			)
			(layer "F.SilkS")
		)
		(fp_line
			(start 0.7874 -0.4064)
			(end 0.7874 0.4064)
			(stroke
				(width 0.1524)
				(type default)
			)
			(layer "F.SilkS")
		)
		(fp_line
			(start -0.7874 0.4064)
			(end -0.7874 -0.4064)
			(stroke
				(width 0.1524)
				(type default)
			)
			(layer "F.SilkS")
		)
		(fp_line
			(start -0.7874 -0.4064)
			(end 0.7874 -0.4064)
			(stroke
				(width 0.1524)
				(type default)
			)
			(layer "F.SilkS")
		)
		(fp_poly
			(pts
				(xy -0.508 0.2794) (xy -0.508 0.2286) (xy -0.635 0.2286) (xy -0.635 -0.254) (xy -0.5334 -0.254)
				(xy -0.5334 -0.2794) (xy 0.5334 -0.2794) (xy 0.5334 -0.254) (xy 0.635 -0.254) (xy 0.635 0.254) (xy 0.5334 0.254)
				(xy 0.5334 0.2794)
			)
			(stroke
				(width 0)
				(type default)
			)
			(fill no)
			(layer "F.CrtYd")
		)
		(pad "1" smd rect
			(at 0.40005 0 180)
			(size 0.4572 0.508)
			(layers "F.Cu" "F.Mask" "F.Paste")
			(net "PSU1_RETURN")
		)
		(pad "2" smd rect
			(at -0.40005 0 180)
			(size 0.4572 0.508)
			(layers "F.Cu" "F.Mask" "F.Paste")
			(net "GND")
		)
	)
	(footprint ""
		(layer "F.Cu")
		(at 26.226008 -449.713858)
		(property "Reference" "R84"
			(at -2.92227 0.534924 0)
			(unlocked yes)
			(layer "F.SilkS")
			(effects
				(font
					(size 0.7874 0.5842)
					(thickness 0.1524)
				)
				(justify left)
			)
		)
		(property "Value" ""
			(at 0 0 0)
			(layer "F.Fab")
			(effects
				(font
					(size 1.27 1.27)
				)
			)
		)
		(duplicate_pad_numbers_are_jumpers no)
		(fp_line
			(start -0.7874 -0.4064)
			(end 0.7874 -0.4064)
			(stroke
				(width 0.1524)
				(type default)
			)
			(layer "F.SilkS")
		)
		(fp_line
			(start -0.7874 0.4064)
			(end -0.7874 -0.4064)
			(stroke
				(width 0.1524)
				(type default)
			)
			(layer "F.SilkS")
		)
		(fp_line
			(start 0.7874 -0.4064)
			(end 0.7874 0.4064)
			(stroke
				(width 0.1524)
				(type default)
			)
			(layer "F.SilkS")
		)
		(fp_line
			(start 0.7874 0.4064)
			(end -0.7874 0.4064)
			(stroke
				(width 0.1524)
				(type default)
			)
			(layer "F.SilkS")
		)
		(fp_poly
			(pts
				(xy -0.508 0.2794) (xy -0.508 0.2286) (xy -0.635 0.2286) (xy -0.635 -0.254) (xy -0.5334 -0.254)
				(xy -0.5334 -0.2794) (xy 0.5334 -0.2794) (xy 0.5334 -0.254) (xy 0.635 -0.254) (xy 0.635 0.254) (xy 0.5334 0.254)
				(xy 0.5334 0.2794)
			)
			(stroke
				(width 0)
				(type default)
			)
			(fill no)
			(layer "F.CrtYd")
		)
		(pad "1" smd rect
			(at 0.40005 0)
			(size 0.4572 0.508)
			(layers "F.Cu" "F.Mask" "F.Paste")
			(net "PSU6_RESET")
		)
		(pad "2" smd rect
			(at -0.40005 0)
			(size 0.4572 0.508)
			(layers "F.Cu" "F.Mask" "F.Paste")
			(net "P12V_STBY")
		)
	)
	(footprint ""
		(layer "F.Cu")
		(at 71.871332 -286.474154 -90)
		(property "Reference" "C43"
			(at 0.298704 -4.020312 90)
			(unlocked yes)
			(layer "F.SilkS")
			(effects
				(font
					(size 0.7874 0.5842)
					(thickness 0.1524)
				)
			)
		)
		(property "Value" ""
			(at 0 0 270)
			(layer "F.Fab")
			(effects
				(font
					(size 1.27 1.27)
				)
			)
		)
		(duplicate_pad_numbers_are_jumpers no)
		(fp_line
			(start -1.2954 0.5842)
			(end -1.2954 -0.5842)
			(stroke
				(width 0.1524)
				(type default)
			)
			(layer "F.SilkS")
		)
		(fp_line
			(start 1.2954 0.5842)
			(end -1.2954 0.5842)
			(stroke
				(width 0.1524)
				(type default)
			)
			(layer "F.SilkS")
		)
		(fp_line
			(start -1.2954 -0.5842)
			(end 1.2954 -0.5842)
			(stroke
				(width 0.1524)
				(type default)
			)
			(layer "F.SilkS")
		)
		(fp_line
			(start 0 -0.5842)
			(end 0 0.5842)
			(stroke
				(width 0.1524)
				(type default)
			)
			(layer "F.SilkS")
		)
		(fp_line
			(start 1.2954 -0.5842)
			(end 1.2954 0.5842)
			(stroke
				(width 0.1524)
				(type default)
			)
			(layer "F.SilkS")
		)
		(fp_poly
			(pts
				(xy 0.8636 -0.4572) (xy 0.8636 -0.3556) (xy 1.143 -0.3556) (xy 1.143 0.3556) (xy 0.8636 0.3556)
				(xy 0.8636 0.4572) (xy -0.8636 0.4572) (xy -0.8636 0.3556) (xy -1.143 0.3556) (xy -1.143 -0.3556)
				(xy -0.8636 -0.3556) (xy -0.8636 -0.4572)
			)
			(stroke
				(width 0)
				(type default)
			)
			(fill no)
			(layer "F.CrtYd")
		)
		(fp_line
			(start -0.884936 0.504952)
			(end -0.884936 -0.504952)
			(stroke
				(width 0.1)
				(type default)
			)
			(layer "F.Fab")
		)
		(fp_line
			(start 0.884936 0.504952)
			(end -0.884936 0.504952)
			(stroke
				(width 0.1)
				(type default)
			)
			(layer "F.Fab")
		)
		(fp_line
			(start -0.884936 -0.504952)
			(end 0.884936 -0.504952)
			(stroke
				(width 0.1)
				(type default)
			)
			(layer "F.Fab")
		)
		(fp_line
			(start 0.884936 -0.504952)
			(end 0.884936 0.504952)
			(stroke
				(width 0.1)
				(type default)
			)
			(layer "F.Fab")
		)
		(pad "1" smd rect
			(at 0.7366 0)
			(size 0.7112 0.8128)
			(layers "F.Cu" "F.Mask" "F.Paste")
			(net "P12V")
		)
		(pad "2" smd rect
			(at -0.7366 0)
			(size 0.7112 0.8128)
			(layers "F.Cu" "F.Mask" "F.Paste")
			(net "GND")
		)
	)
	(footprint ""
		(layer "F.Cu")
		(at 26.103834 -189.265306 180)
		(property "Reference" "R51"
			(at 4.040632 -0.318516 0)
			(unlocked yes)
			(layer "F.SilkS")
			(effects
				(font
					(size 0.7874 0.5842)
					(thickness 0.1524)
				)
				(justify left)
			)
		)
		(property "Value" ""
			(at 0 0 180)
			(layer "F.Fab")
			(effects
				(font
					(size 1.27 1.27)
				)
			)
		)
		(duplicate_pad_numbers_are_jumpers no)
		(fp_line
			(start 0.7874 0.4064)
			(end -0.7874 0.4064)
			(stroke
				(width 0.1524)
				(type default)
			)
			(layer "F.SilkS")
		)
		(fp_line
			(start 0.7874 -0.4064)
			(end 0.7874 0.4064)
			(stroke
				(width 0.1524)
				(type default)
			)
			(layer "F.SilkS")
		)
		(fp_line
			(start -0.7874 0.4064)
			(end -0.7874 -0.4064)
			(stroke
				(width 0.1524)
				(type default)
			)
			(layer "F.SilkS")
		)
		(fp_line
			(start -0.7874 -0.4064)
			(end 0.7874 -0.4064)
			(stroke
				(width 0.1524)
				(type default)
			)
			(layer "F.SilkS")
		)
		(fp_poly
			(pts
				(xy -0.508 0.2794) (xy -0.508 0.2286) (xy -0.635 0.2286) (xy -0.635 -0.254) (xy -0.5334 -0.254)
				(xy -0.5334 -0.2794) (xy 0.5334 -0.2794) (xy 0.5334 -0.254) (xy 0.635 -0.254) (xy 0.635 0.254) (xy 0.5334 0.254)
				(xy 0.5334 0.2794)
			)
			(stroke
				(width 0)
				(type default)
			)
			(fill no)
			(layer "F.CrtYd")
		)
		(pad "1" smd rect
			(at 0.40005 0 180)
			(size 0.4572 0.508)
			(layers "F.Cu" "F.Mask" "F.Paste")
			(net "GND")
		)
		(pad "2" smd rect
			(at -0.40005 0 180)
			(size 0.4572 0.508)
			(layers "F.Cu" "F.Mask" "F.Paste")
			(net "PSU3_PS_ON_N")
		)
	)
	(footprint ""
		(layer "F.Cu")
		(at 50.54981 -507.67742 180)
		(property "Reference" "CE23"
			(at 2.73939 5.49021 0)
			(unlocked yes)
			(layer "F.SilkS")
			(effects
				(font
					(size 0.7874 0.5842)
					(thickness 0.1524)
				)
				(justify left)
			)
		)
		(property "Value" ""
			(at 0 0 180)
			(layer "F.Fab")
			(effects
				(font
					(size 1.27 1.27)
				)
			)
		)
		(duplicate_pad_numbers_are_jumpers no)
		(fp_line
			(start 0 -4.2672)
			(end 0 4.2672)
			(stroke
				(width 0.1524)
				(type default)
			)
			(layer "F.SilkS")
		)
		(fp_circle
			(center 0 0)
			(end -4.2672 0)
			(stroke
				(width 0.1524)
				(type default)
			)
			(fill no)
			(layer "F.SilkS")
		)
		(fp_poly
			(pts
				(arc
					(start 0 -4.2672)
					(mid 4.2672 0)
					(end 0 4.2672)
				)
			)
			(stroke
				(width 0)
				(type default)
			)
			(fill yes)
			(layer "F.SilkS")
		)
		(fp_poly
			(pts
				(xy -2.5146 -0.762) (xy -0.9906 -0.762) (xy -0.9906 0.762) (xy -2.5146 0.762)
			)
			(stroke
				(width 0)
				(type default)
			)
			(fill no)
			(layer "B.CrtYd")
		)
		(fp_poly
			(pts
				(arc
					(start 1.7526 0.762)
					(mid 2.291415 -0.538815)
					(end 0.9906 0)
				)
				(arc
					(start 0.9906 0.0254)
					(mid 1.206345 0.546255)
					(end 1.7272 0.762)
				)
			)
			(stroke
				(width 0)
				(type default)
			)
			(fill no)
			(layer "B.CrtYd")
		)
		(fp_poly
			(pts
				(arc
					(start -4.2672 0)
					(mid 4.2672 0)
					(end -4.2672 0)
				)
			)
			(stroke
				(width 0)
				(type default)
			)
			(fill no)
			(layer "F.CrtYd")
		)
		(fp_circle
			(center 0 0)
			(end -4.2672 0)
			(stroke
				(width 0.1)
				(type default)
			)
			(fill no)
			(layer "F.Fab")
		)
		(fp_text user "+"
			(at -5.619496 -0.34925 180)
			(unlocked yes)
			(layer "F.SilkS")
			(effects
				(font
					(size 1.905 1.4224)
					(thickness 0.1524)
				)
				(justify left)
			)
		)
		(fp_text user "+"
			(at -5.6642 -0.34925 180)
			(unlocked yes)
			(layer "F.Fab")
			(effects
				(font
					(size 1.905 1.4224)
					(thickness 0.000001)
				)
				(justify left)
			)
		)
		(pad "1" thru_hole rect
			(at -1.75006 0 180)
			(size 1.397 1.397)
			(drill 0.9144)
			(layers "*.Cu" "*.Mask")
			(remove_unused_layers no)
			(net "P12V")
			(clearance 0.0127)
			(thermal_gap 0.0127)
			(padstack
				(mode front_inner_back)
				(layer "Inner"
					(shape circle)
					(size 1.397 1.397)
					(clearance 0.0127)
				)
				(layer "B.Cu"
					(shape rect)
					(size 1.397 1.397)
					(clearance 0.0127)
				)
			)
		)
		(pad "2" thru_hole circle
			(at 1.75006 0 180)
			(size 1.397 1.397)
			(drill 0.9144)
			(layers "*.Cu" "*.Mask")
			(remove_unused_layers no)
			(net "GND")
			(clearance 0.0127)
			(thermal_gap 0.0127)
		)
	)
	(footprint ""
		(layer "F.Cu")
		(at 26.226008 -452.257668)
		(property "Reference" "R83"
			(at -3.522472 -0.815594 0)
			(unlocked yes)
			(layer "F.SilkS")
			(effects
				(font
					(size 0.7874 0.5842)
					(thickness 0.1524)
				)
				(justify left)
			)
		)
		(property "Value" ""
			(at 0 0 0)
			(layer "F.Fab")
			(effects
				(font
					(size 1.27 1.27)
				)
			)
		)
		(duplicate_pad_numbers_are_jumpers no)
		(fp_line
			(start -0.7874 -0.4064)
			(end 0.7874 -0.4064)
			(stroke
				(width 0.1524)
				(type default)
			)
			(layer "F.SilkS")
		)
		(fp_line
			(start -0.7874 0.4064)
			(end -0.7874 -0.4064)
			(stroke
				(width 0.1524)
				(type default)
			)
			(layer "F.SilkS")
		)
		(fp_line
			(start 0.7874 -0.4064)
			(end 0.7874 0.4064)
			(stroke
				(width 0.1524)
				(type default)
			)
			(layer "F.SilkS")
		)
		(fp_line
			(start 0.7874 0.4064)
			(end -0.7874 0.4064)
			(stroke
				(width 0.1524)
				(type default)
			)
			(layer "F.SilkS")
		)
		(fp_poly
			(pts
				(xy -0.508 0.2794) (xy -0.508 0.2286) (xy -0.635 0.2286) (xy -0.635 -0.254) (xy -0.5334 -0.254)
				(xy -0.5334 -0.2794) (xy 0.5334 -0.2794) (xy 0.5334 -0.254) (xy 0.635 -0.254) (xy 0.635 0.254) (xy 0.5334 0.254)
				(xy 0.5334 0.2794)
			)
			(stroke
				(width 0)
				(type default)
			)
			(fill no)
			(layer "F.CrtYd")
		)
		(pad "1" smd rect
			(at 0.40005 0)
			(size 0.4572 0.508)
			(layers "F.Cu" "F.Mask" "F.Paste")
			(net "PSU6_PS_KILL")
		)
		(pad "2" smd rect
			(at -0.40005 0)
			(size 0.4572 0.508)
			(layers "F.Cu" "F.Mask" "F.Paste")
			(net "GND")
		)
	)
	(footprint ""
		(layer "F.Cu")
		(at 66.823844 -38.821106 90)
		(property "Reference" "C14"
			(at 1.08712 -0.021082 90)
			(unlocked yes)
			(layer "F.SilkS")
			(effects
				(font
					(size 0.7874 0.5842)
					(thickness 0.1524)
				)
				(justify left)
			)
		)
		(property "Value" ""
			(at 0 0 90)
			(layer "F.Fab")
			(effects
				(font
					(size 1.27 1.27)
				)
			)
		)
		(duplicate_pad_numbers_are_jumpers no)
		(fp_line
			(start 0.7874 -0.4064)
			(end 0.7874 0.4064)
			(stroke
				(width 0.1524)
				(type default)
			)
			(layer "F.SilkS")
		)
		(fp_line
			(start -0.7874 -0.4064)
			(end 0.7874 -0.4064)
			(stroke
				(width 0.1524)
				(type default)
			)
			(layer "F.SilkS")
		)
		(fp_line
			(start 0 0.381)
			(end 0 -0.381)
			(stroke
				(width 0.1524)
				(type default)
			)
			(layer "F.SilkS")
		)
		(fp_line
			(start 0.7874 0.4064)
			(end -0.7874 0.4064)
			(stroke
				(width 0.1524)
				(type default)
			)
			(layer "F.SilkS")
		)
		(fp_line
			(start -0.7874 0.4064)
			(end -0.7874 -0.4064)
			(stroke
				(width 0.1524)
				(type default)
			)
			(layer "F.SilkS")
		)
		(fp_poly
			(pts
				(xy -0.5334 0.254) (xy -0.635 0.254) (xy -0.635 0.2286) (xy -0.635 -0.254) (xy -0.5334 -0.254) (xy -0.5334 -0.2794)
				(xy 0.5334 -0.2794) (xy 0.5334 -0.254) (xy 0.635 -0.254) (xy 0.635 0.254) (xy 0.5334 0.254) (xy 0.5334 0.2794)
				(xy -0.508 0.2794) (xy -0.5334 0.2794)
			)
			(stroke
				(width 0)
				(type default)
			)
			(fill no)
			(layer "F.CrtYd")
		)
		(pad "1" smd rect
			(at 0.40005 0 90)
			(size 0.4572 0.508)
			(layers "F.Cu" "F.Mask" "F.Paste")
			(net "P12V")
		)
		(pad "2" smd rect
			(at -0.40005 0 90)
			(size 0.4572 0.508)
			(layers "F.Cu" "F.Mask" "F.Paste")
			(net "GND")
		)
	)
	(footprint ""
		(layer "F.Cu")
		(at 26.068274 -181.847998)
		(property "Reference" "R73"
			(at -3.997198 0.128524 0)
			(unlocked yes)
			(layer "F.SilkS")
			(effects
				(font
					(size 0.7874 0.5842)
					(thickness 0.1524)
				)
				(justify left)
			)
		)
		(property "Value" ""
			(at 0 0 0)
			(layer "F.Fab")
			(effects
				(font
					(size 1.27 1.27)
				)
			)
		)
		(duplicate_pad_numbers_are_jumpers no)
		(fp_line
			(start -0.7874 -0.4064)
			(end 0.7874 -0.4064)
			(stroke
				(width 0.1524)
				(type default)
			)
			(layer "F.SilkS")
		)
		(fp_line
			(start -0.7874 0.4064)
			(end -0.7874 -0.4064)
			(stroke
				(width 0.1524)
				(type default)
			)
			(layer "F.SilkS")
		)
		(fp_line
			(start 0.7874 -0.4064)
			(end 0.7874 0.4064)
			(stroke
				(width 0.1524)
				(type default)
			)
			(layer "F.SilkS")
		)
		(fp_line
			(start 0.7874 0.4064)
			(end -0.7874 0.4064)
			(stroke
				(width 0.1524)
				(type default)
			)
			(layer "F.SilkS")
		)
		(fp_poly
			(pts
				(xy -0.508 0.2794) (xy -0.508 0.2286) (xy -0.635 0.2286) (xy -0.635 -0.254) (xy -0.5334 -0.254)
				(xy -0.5334 -0.2794) (xy 0.5334 -0.2794) (xy 0.5334 -0.254) (xy 0.635 -0.254) (xy 0.635 0.254) (xy 0.5334 0.254)
				(xy 0.5334 0.2794)
			)
			(stroke
				(width 0)
				(type default)
			)
			(fill no)
			(layer "F.CrtYd")
		)
		(pad "1" smd rect
			(at 0.40005 0)
			(size 0.4572 0.508)
			(layers "F.Cu" "F.Mask" "F.Paste")
			(net "PSU3_RESET")
		)
		(pad "2" smd rect
			(at -0.40005 0)
			(size 0.4572 0.508)
			(layers "F.Cu" "F.Mask" "F.Paste")
			(net "GND")
		)
	)
	(footprint ""
		(layer "B.Cu")
		(at 93.307916 -80.871314)
		(property "Reference" "U4"
			(at 4.759198 0.010414 0)
			(unlocked yes)
			(layer "B.SilkS")
			(effects
				(font
					(size 0.7874 0.5842)
					(thickness 0.1524)
				)
				(justify left mirror)
			)
		)
		(property "Value" ""
			(at 0 0 0)
			(layer "B.Fab")
			(effects
				(font
					(size 1.27 1.27)
				)
				(justify mirror)
			)
		)
		(duplicate_pad_numbers_are_jumpers no)
		(fp_line
			(start -2.5527 -2.0066)
			(end -2.5527 2.0066)
			(stroke
				(width 0.1524)
				(type default)
			)
			(layer "B.SilkS")
		)
		(fp_line
			(start -2.5527 2.0066)
			(end 2.5527 2.0066)
			(stroke
				(width 0.1524)
				(type default)
			)
			(layer "B.SilkS")
		)
		(fp_line
			(start 1.9812 0)
			(end 2.5527 -0.5715)
			(stroke
				(width 0.1524)
				(type default)
			)
			(layer "B.SilkS")
		)
		(fp_line
			(start 2.5527 -2.0066)
			(end -2.5527 -2.0066)
			(stroke
				(width 0.1524)
				(type default)
			)
			(layer "B.SilkS")
		)
		(fp_line
			(start 2.5527 -0.5715)
			(end 2.5527 -2.0066)
			(stroke
				(width 0.1524)
				(type default)
			)
			(layer "B.SilkS")
		)
		(fp_line
			(start 2.5527 0.5715)
			(end 1.9812 0)
			(stroke
				(width 0.1524)
				(type default)
			)
			(layer "B.SilkS")
		)
		(fp_line
			(start 2.5527 2.0066)
			(end 2.5527 0.5715)
			(stroke
				(width 0.1524)
				(type default)
			)
			(layer "B.SilkS")
		)
		(fp_circle
			(center 2.032 1.524)
			(end 2.286 1.524)
			(stroke
				(width 0.1524)
				(type default)
			)
			(fill no)
			(layer "B.SilkS")
		)
		(fp_rect
			(start 2.5527 3.6703)
			(end -2.5527 -3.6703)
			(stroke
				(width 0)
				(type default)
			)
			(fill no)
			(layer "B.CrtYd")
		)
		(fp_line
			(start -2.549906 -2.249932)
			(end -2.549906 2.249932)
			(stroke
				(width 0.1)
				(type default)
			)
			(layer "B.Fab")
		)
		(fp_line
			(start -2.549906 2.249932)
			(end 2.549906 2.249932)
			(stroke
				(width 0.1)
				(type default)
			)
			(layer "B.Fab")
		)
		(fp_line
			(start 2.549906 -2.249932)
			(end -2.549906 -2.249932)
			(stroke
				(width 0.1)
				(type default)
			)
			(layer "B.Fab")
		)
		(fp_line
			(start 2.549906 2.249932)
			(end 2.549906 -2.249932)
			(stroke
				(width 0.1)
				(type default)
			)
			(layer "B.Fab")
		)
		(pad "1" smd rect
			(at 1.949958 2.921 180)
			(size 0.3556 1.4986)
			(layers "B.Cu" "B.Mask" "B.Paste")
			(net "PSU_ALERT_N")
		)
		(pad "2" smd rect
			(at 1.299972 2.921 180)
			(size 0.3556 1.4986)
			(layers "B.Cu" "B.Mask" "B.Paste")
			(net "B1_PSU_ALERT_N")
		)
		(pad "3" smd rect
			(at 0.649986 2.921 180)
			(size 0.3556 1.4986)
			(layers "B.Cu" "B.Mask" "B.Paste")
			(net "PSU_ALERT_N")
		)
		(pad "4" smd rect
			(at 0 2.921 180)
			(size 0.3556 1.4986)
			(layers "B.Cu" "B.Mask" "B.Paste")
			(net "B2_PSU_ALERT_N")
		)
		(pad "5" smd rect
			(at -0.649986 2.921 180)
			(size 0.3556 1.4986)
			(layers "B.Cu" "B.Mask" "B.Paste")
			(net "PSU_ALERT_N")
		)
		(pad "6" smd rect
			(at -1.299972 2.921 180)
			(size 0.3556 1.4986)
			(layers "B.Cu" "B.Mask" "B.Paste")
			(net "B3_PSU_ALERT_N")
		)
		(pad "7" smd rect
			(at -1.949958 2.921 180)
			(size 0.3556 1.4986)
			(layers "B.Cu" "B.Mask" "B.Paste")
			(net "GND")
		)
		(pad "8" smd rect
			(at -1.949958 -2.921 180)
			(size 0.3556 1.4986)
			(layers "B.Cu" "B.Mask" "B.Paste")
			(net "B4_PSU_ALERT_N")
		)
		(pad "9" smd rect
			(at -1.299972 -2.921 180)
			(size 0.3556 1.4986)
			(layers "B.Cu" "B.Mask" "B.Paste")
			(net "PSU_ALERT_N")
		)
		(pad "10" smd rect
			(at -0.649986 -2.921 180)
			(size 0.3556 1.4986)
			(layers "B.Cu" "B.Mask" "B.Paste")
			(net "B5_PSU_ALERT_N")
		)
		(pad "11" smd rect
			(at 0 -2.921 180)
			(size 0.3556 1.4986)
			(layers "B.Cu" "B.Mask" "B.Paste")
			(net "PSU_ALERT_N")
		)
		(pad "12" smd rect
			(at 0.649986 -2.921 180)
			(size 0.3556 1.4986)
			(layers "B.Cu" "B.Mask" "B.Paste")
			(net "B6_PSU_ALERT_N")
		)
		(pad "13" smd rect
			(at 1.299972 -2.921 180)
			(size 0.3556 1.4986)
			(layers "B.Cu" "B.Mask" "B.Paste")
			(net "PSU_ALERT_N")
		)
		(pad "14" smd rect
			(at 1.949958 -2.921 180)
			(size 0.3556 1.4986)
			(layers "B.Cu" "B.Mask" "B.Paste")
			(net "P3V3_BUF")
		)
	)
	(footprint ""
		(layer "B.Cu")
		(at 91.865958 -169.795444)
		(property "Reference" "U5"
			(at 4.088384 0.502412 0)
			(unlocked yes)
			(layer "B.SilkS")
			(effects
				(font
					(size 0.7874 0.5842)
					(thickness 0.1524)
				)
				(justify left mirror)
			)
		)
		(property "Value" ""
			(at 0 0 0)
			(layer "B.Fab")
			(effects
				(font
					(size 1.27 1.27)
				)
				(justify mirror)
			)
		)
		(duplicate_pad_numbers_are_jumpers no)
		(fp_line
			(start -2.5527 -2.0066)
			(end -2.5527 2.0066)
			(stroke
				(width 0.1524)
				(type default)
			)
			(layer "B.SilkS")
		)
		(fp_line
			(start -2.5527 2.0066)
			(end 2.5527 2.0066)
			(stroke
				(width 0.1524)
				(type default)
			)
			(layer "B.SilkS")
		)
		(fp_line
			(start 1.9812 0)
			(end 2.5527 -0.5715)
			(stroke
				(width 0.1524)
				(type default)
			)
			(layer "B.SilkS")
		)
		(fp_line
			(start 2.5527 -2.0066)
			(end -2.5527 -2.0066)
			(stroke
				(width 0.1524)
				(type default)
			)
			(layer "B.SilkS")
		)
		(fp_line
			(start 2.5527 -0.5715)
			(end 2.5527 -2.0066)
			(stroke
				(width 0.1524)
				(type default)
			)
			(layer "B.SilkS")
		)
		(fp_line
			(start 2.5527 0.5715)
			(end 1.9812 0)
			(stroke
				(width 0.1524)
				(type default)
			)
			(layer "B.SilkS")
		)
		(fp_line
			(start 2.5527 2.0066)
			(end 2.5527 0.5715)
			(stroke
				(width 0.1524)
				(type default)
			)
			(layer "B.SilkS")
		)
		(fp_circle
			(center 2.032 1.524)
			(end 2.286 1.524)
			(stroke
				(width 0.1524)
				(type default)
			)
			(fill no)
			(layer "B.SilkS")
		)
		(fp_rect
			(start 2.5527 3.6703)
			(end -2.5527 -3.6703)
			(stroke
				(width 0)
				(type default)
			)
			(fill no)
			(layer "B.CrtYd")
		)
		(fp_line
			(start -2.549906 -2.249932)
			(end -2.549906 2.249932)
			(stroke
				(width 0.1)
				(type default)
			)
			(layer "B.Fab")
		)
		(fp_line
			(start -2.549906 2.249932)
			(end 2.549906 2.249932)
			(stroke
				(width 0.1)
				(type default)
			)
			(layer "B.Fab")
		)
		(fp_line
			(start 2.549906 -2.249932)
			(end -2.549906 -2.249932)
			(stroke
				(width 0.1)
				(type default)
			)
			(layer "B.Fab")
		)
		(fp_line
			(start 2.549906 2.249932)
			(end 2.549906 -2.249932)
			(stroke
				(width 0.1)
				(type default)
			)
			(layer "B.Fab")
		)
		(pad "1" smd rect
			(at 1.949958 2.921 180)
			(size 0.3556 1.4986)
			(layers "B.Cu" "B.Mask" "B.Paste")
			(net "PSU_ALERT_N")
		)
		(pad "2" smd rect
			(at 1.299972 2.921 180)
			(size 0.3556 1.4986)
			(layers "B.Cu" "B.Mask" "B.Paste")
			(net "B7_PSU_ALERT_N")
		)
		(pad "3" smd rect
			(at 0.649986 2.921 180)
			(size 0.3556 1.4986)
			(layers "B.Cu" "B.Mask" "B.Paste")
			(net "PSU_ALERT_N")
		)
		(pad "4" smd rect
			(at 0 2.921 180)
			(size 0.3556 1.4986)
			(layers "B.Cu" "B.Mask" "B.Paste")
			(net "B8_PSU_ALERT_N")
		)
		(pad "5" smd rect
			(at -0.649986 2.921 180)
			(size 0.3556 1.4986)
			(layers "B.Cu" "B.Mask" "B.Paste")
			(net "PSU_ALERT_N")
		)
		(pad "6" smd rect
			(at -1.299972 2.921 180)
			(size 0.3556 1.4986)
			(layers "B.Cu" "B.Mask" "B.Paste")
			(net "B9_PSU_ALERT_N")
		)
		(pad "7" smd rect
			(at -1.949958 2.921 180)
			(size 0.3556 1.4986)
			(layers "B.Cu" "B.Mask" "B.Paste")
			(net "GND")
		)
		(pad "8" smd rect
			(at -1.949958 -2.921 180)
			(size 0.3556 1.4986)
			(layers "B.Cu" "B.Mask" "B.Paste")
			(net "B10_PSU_ALERT_N")
		)
		(pad "9" smd rect
			(at -1.299972 -2.921 180)
			(size 0.3556 1.4986)
			(layers "B.Cu" "B.Mask" "B.Paste")
			(net "PSU_ALERT_N")
		)
		(pad "10" smd rect
			(at -0.649986 -2.921 180)
			(size 0.3556 1.4986)
			(layers "B.Cu" "B.Mask" "B.Paste")
			(net "B11_PSU_ALERT_N")
		)
		(pad "11" smd rect
			(at 0 -2.921 180)
			(size 0.3556 1.4986)
			(layers "B.Cu" "B.Mask" "B.Paste")
			(net "PSU_ALERT_N")
		)
		(pad "12" smd rect
			(at 0.649986 -2.921 180)
			(size 0.3556 1.4986)
			(layers "B.Cu" "B.Mask" "B.Paste")
			(net "B12_PSU_ALERT_N")
		)
		(pad "13" smd rect
			(at 1.299972 -2.921 180)
			(size 0.3556 1.4986)
			(layers "B.Cu" "B.Mask" "B.Paste")
			(net "PSU_ALERT_N")
		)
		(pad "14" smd rect
			(at 1.949958 -2.921 180)
			(size 0.3556 1.4986)
			(layers "B.Cu" "B.Mask" "B.Paste")
			(net "P3V3_BUF")
		)
	)
	(footprint ""
		(layer "B.Cu")
		(at 44.040044 -141.61008 90)
		(property "Reference" "J10"
			(at 6.161024 -4.691126 0)
			(unlocked yes)
			(layer "B.SilkS")
			(effects
				(font
					(size 0.7874 0.5842)
					(thickness 0.1524)
				)
				(justify left mirror)
			)
		)
		(property "Value" ""
			(at 0 0 90)
			(layer "B.Fab")
			(effects
				(font
					(size 1.27 1.27)
				)
				(justify mirror)
			)
		)
		(duplicate_pad_numbers_are_jumpers no)
		(fp_line
			(start 5.275072 -13.910056)
			(end -7.975092 -13.910056)
			(stroke
				(width 0.1524)
				(type default)
			)
			(layer "F.SilkS")
		)
		(fp_line
			(start -7.975092 -13.910056)
			(end -7.975092 62.170056)
			(stroke
				(width 0.1524)
				(type default)
			)
			(layer "F.SilkS")
		)
		(fp_line
			(start 5.275072 62.170056)
			(end 5.275072 -13.910056)
			(stroke
				(width 0.1524)
				(type default)
			)
			(layer "F.SilkS")
		)
		(fp_line
			(start -7.975092 62.170056)
			(end 5.275072 62.170056)
			(stroke
				(width 0.1524)
				(type default)
			)
			(layer "F.SilkS")
		)
		(fp_line
			(start 5.275072 -13.910056)
			(end -7.975092 -13.910056)
			(stroke
				(width 0.1524)
				(type default)
			)
			(layer "B.SilkS")
		)
		(fp_line
			(start -7.975092 -13.910056)
			(end -7.975092 62.170056)
			(stroke
				(width 0.1524)
				(type default)
			)
			(layer "B.SilkS")
		)
		(fp_line
			(start 2.275078 -10.910062)
			(end 2.275078 59.170062)
			(stroke
				(width 0.1524)
				(type default)
			)
			(layer "B.SilkS")
		)
		(fp_line
			(start -4.975098 -10.910062)
			(end 2.275078 -10.910062)
			(stroke
				(width 0.1524)
				(type default)
			)
			(layer "B.SilkS")
		)
		(fp_line
			(start 2.275078 59.170062)
			(end -4.975098 59.170062)
			(stroke
				(width 0.1524)
				(type default)
			)
			(layer "B.SilkS")
		)
		(fp_line
			(start -4.975098 59.170062)
			(end -4.975098 -10.910062)
			(stroke
				(width 0.1524)
				(type default)
			)
			(layer "B.SilkS")
		)
		(fp_line
			(start 5.275072 62.170056)
			(end 5.275072 -13.910056)
			(stroke
				(width 0.1524)
				(type default)
			)
			(layer "B.SilkS")
		)
		(fp_line
			(start -7.975092 62.170056)
			(end 5.275072 62.170056)
			(stroke
				(width 0.1524)
				(type default)
			)
			(layer "B.SilkS")
		)
		(fp_poly
			(pts
				(xy 4.103878 -0.759206) (xy 4.103878 0.764794) (xy 2.579878 0.002794)
			)
			(stroke
				(width 0)
				(type default)
			)
			(fill yes)
			(layer "B.SilkS")
		)
		(fp_poly
			(pts
				(xy 2.275078 -10.910062) (xy 2.275078 59.170062) (xy -4.975098 59.170062) (xy -4.975098 -10.910062)
			)
			(stroke
				(width 0)
				(type default)
			)
			(fill no)
			(layer "B.CrtYd")
		)
		(fp_poly
			(pts
				(xy 1.1938 40.9702) (xy 1.1938 48.6156) (xy -3.9116 48.6156) (xy -3.9116 40.9702) (xy -3.9116 40.9448)
				(xy 1.1938 40.9448)
			)
			(stroke
				(width 0)
				(type default)
			)
			(fill no)
			(layer "F.CrtYd")
		)
		(fp_poly
			(pts
				(xy -3.3274 -0.6604) (xy 0.635 -0.6604) (xy 0.635 38.735) (xy 0.635 38.7604) (xy -3.3274 38.7604)
				(xy -3.3528 38.7604) (xy -3.3528 -0.6604)
			)
			(stroke
				(width 0)
				(type default)
			)
			(fill no)
			(layer "F.CrtYd")
		)
		(fp_poly
			(pts
				(arc
					(start -1.35001 -1.01219)
					(mid -1.35001 -4.06781)
					(end -1.35001 -1.01219)
				)
			)
			(stroke
				(width 0)
				(type default)
			)
			(fill no)
			(layer "F.CrtYd")
		)
		(fp_poly
			(pts
				(arc
					(start 0 52.33162)
					(mid 0 49.26838)
					(end 0 52.33162)
				)
			)
			(stroke
				(width 0)
				(type default)
			)
			(fill no)
			(layer "F.CrtYd")
		)
		(fp_line
			(start 2.275078 -10.910062)
			(end 2.275078 59.170062)
			(stroke
				(width 0.1)
				(type default)
			)
			(layer "B.Fab")
		)
		(fp_line
			(start -4.975098 -10.910062)
			(end 2.275078 -10.910062)
			(stroke
				(width 0.1)
				(type default)
			)
			(layer "B.Fab")
		)
		(fp_line
			(start 2.275078 59.170062)
			(end -4.975098 59.170062)
			(stroke
				(width 0.1)
				(type default)
			)
			(layer "B.Fab")
		)
		(fp_line
			(start -4.975098 59.170062)
			(end -4.975098 -10.910062)
			(stroke
				(width 0.1)
				(type default)
			)
			(layer "B.Fab")
		)
		(fp_poly
			(pts
				(xy 4.103878 -0.759206) (xy 4.103878 0.764794) (xy 2.579878 0.002794)
			)
			(stroke
				(width 0)
				(type default)
			)
			(fill yes)
			(layer "B.Fab")
		)
		(fp_line
			(start 5.275072 -13.910056)
			(end -7.975092 -13.910056)
			(stroke
				(width 0.1)
				(type default)
			)
			(layer "F.Fab")
		)
		(fp_line
			(start -7.975092 -13.910056)
			(end -7.975092 62.170056)
			(stroke
				(width 0.1)
				(type default)
			)
			(layer "F.Fab")
		)
		(fp_line
			(start 5.275072 62.170056)
			(end 5.275072 -13.910056)
			(stroke
				(width 0.1)
				(type default)
			)
			(layer "F.Fab")
		)
		(fp_line
			(start -7.975092 62.170056)
			(end 5.275072 62.170056)
			(stroke
				(width 0.1)
				(type default)
			)
			(layer "F.Fab")
		)
		(fp_text user "P1"
			(at 6.382004 -0.705612 0)
			(unlocked yes)
			(layer "F.SilkS")
			(effects
				(font
					(size 0.7874 0.5842)
					(thickness 0.1524)
				)
			)
		)
		(fp_text user "P32"
			(at -9.324848 -0.170942 0)
			(unlocked yes)
			(layer "F.SilkS")
			(effects
				(font
					(size 0.7874 0.5842)
					(thickness 0.1524)
				)
			)
		)
		(fp_text user "PRESS-FIT"
			(at -8.95731 8.785352 0)
			(unlocked yes)
			(layer "F.SilkS")
			(effects
				(font
					(size 0.7874 0.5842)
					(thickness 0.1524)
				)
				(justify left)
			)
		)
		(fp_text user "P16"
			(at 5.980684 37.793168 0)
			(unlocked yes)
			(layer "F.SilkS")
			(effects
				(font
					(size 0.7874 0.5842)
					(thickness 0.1524)
				)
			)
		)
		(fp_text user "P17"
			(at -9.525508 40.199564 0)
			(unlocked yes)
			(layer "F.SilkS")
			(effects
				(font
					(size 0.7874 0.5842)
					(thickness 0.1524)
				)
			)
		)
		(fp_text user "S1"
			(at 6.481318 41.559734 0)
			(unlocked yes)
			(layer "F.SilkS")
			(effects
				(font
					(size 0.7874 0.5842)
					(thickness 0.1524)
				)
			)
		)
		(fp_text user "S12"
			(at -9.024366 42.906442 0)
			(unlocked yes)
			(layer "F.SilkS")
			(effects
				(font
					(size 0.7874 0.5842)
					(thickness 0.1524)
				)
			)
		)
		(fp_text user "S6"
			(at 6.10997 47.690532 0)
			(unlocked yes)
			(layer "F.SilkS")
			(effects
				(font
					(size 0.7874 0.5842)
					(thickness 0.1524)
				)
			)
		)
		(fp_text user "S7"
			(at -9.49706 48.02759 0)
			(unlocked yes)
			(layer "F.SilkS")
			(effects
				(font
					(size 0.7874 0.5842)
					(thickness 0.1524)
				)
			)
		)
		(fp_text user "P1"
			(at 3.068828 -1.487932 0)
			(unlocked yes)
			(layer "B.SilkS")
			(effects
				(font
					(size 0.7874 0.5842)
					(thickness 0.1524)
				)
				(justify mirror)
			)
		)
		(fp_text user "P32"
			(at -5.817362 -0.221234 0)
			(unlocked yes)
			(layer "B.SilkS")
			(effects
				(font
					(size 0.7874 0.5842)
					(thickness 0.1524)
				)
				(justify mirror)
			)
		)
		(fp_text user "PRESS-FIT"
			(at -6.304788 27.535632 0)
			(unlocked yes)
			(layer "B.SilkS")
			(effects
				(font
					(size 0.7874 0.5842)
					(thickness 0.1524)
				)
				(justify left mirror)
			)
		)
		(fp_text user "P17"
			(at -5.607558 37.991796 0)
			(unlocked yes)
			(layer "B.SilkS")
			(effects
				(font
					(size 0.7874 0.5842)
					(thickness 0.1524)
				)
				(justify mirror)
			)
		)
		(fp_text user "P16"
			(at 3.018282 38.07206 0)
			(unlocked yes)
			(layer "B.SilkS")
			(effects
				(font
					(size 0.7874 0.5842)
					(thickness 0.1524)
				)
				(justify mirror)
			)
		)
		(fp_text user "S12"
			(at -5.807456 41.590976 0)
			(unlocked yes)
			(layer "B.SilkS")
			(effects
				(font
					(size 0.7874 0.5842)
					(thickness 0.1524)
				)
				(justify mirror)
			)
		)
		(fp_text user "S1"
			(at 3.081274 42.08272 0)
			(unlocked yes)
			(layer "B.SilkS")
			(effects
				(font
					(size 0.7874 0.5842)
					(thickness 0.1524)
				)
				(justify mirror)
			)
		)
		(fp_text user "S7"
			(at -5.615178 45.181266 0)
			(unlocked yes)
			(layer "B.SilkS")
			(effects
				(font
					(size 0.7874 0.5842)
					(thickness 0.1524)
				)
				(justify mirror)
			)
		)
		(fp_text user "S6"
			(at 2.97307 47.326804 0)
			(unlocked yes)
			(layer "B.SilkS")
			(effects
				(font
					(size 0.7874 0.5842)
					(thickness 0.1524)
				)
				(justify mirror)
			)
		)
		(fp_text user "P1"
			(at 3.108452 -1.27 180)
			(unlocked yes)
			(layer "B.Fab")
			(effects
				(font
					(size 0.7874 0.5842)
					(thickness 0.000001)
				)
				(justify mirror)
			)
		)
		(fp_text user "P32"
			(at -5.781548 -0.0508 180)
			(unlocked yes)
			(layer "B.Fab")
			(effects
				(font
					(size 0.7874 0.5842)
					(thickness 0.000001)
				)
				(justify mirror)
			)
		)
		(fp_text user "PRESS-FIT"
			(at -6.82371 29.8831 0)
			(unlocked yes)
			(layer "B.Fab")
			(effects
				(font
					(size 1.6002 1.1938)
					(thickness 0.000001)
				)
				(justify left mirror)
			)
		)
		(fp_text user "P17"
			(at -5.72135 38.0746 180)
			(unlocked yes)
			(layer "B.Fab")
			(effects
				(font
					(size 0.7874 0.5842)
					(thickness 0.000001)
				)
				(justify mirror)
			)
		)
		(fp_text user "P16"
			(at 3.159252 38.3794 180)
			(unlocked yes)
			(layer "B.Fab")
			(effects
				(font
					(size 0.7874 0.5842)
					(thickness 0.000001)
				)
				(justify mirror)
			)
		)
		(fp_text user "S12"
			(at -5.79374 41.42232 180)
			(unlocked yes)
			(layer "B.Fab")
			(effects
				(font
					(size 0.7874 0.5842)
					(thickness 0.000001)
				)
				(justify mirror)
			)
		)
		(fp_text user "S1"
			(at 3.09626 41.656 180)
			(unlocked yes)
			(layer "B.Fab")
			(effects
				(font
					(size 0.7874 0.5842)
					(thickness 0.000001)
				)
				(justify mirror)
			)
		)
		(fp_text user "S6"
			(at 3.133852 48.0822 180)
			(unlocked yes)
			(layer "B.Fab")
			(effects
				(font
					(size 0.7874 0.5842)
					(thickness 0.000001)
				)
				(justify mirror)
			)
		)
		(fp_text user "S7"
			(at -5.781548 48.0822 180)
			(unlocked yes)
			(layer "B.Fab")
			(effects
				(font
					(size 0.7874 0.5842)
					(thickness 0.000001)
				)
				(justify mirror)
			)
		)
		(fp_text user "P32"
			(at -4.071112 -0.0762 180)
			(unlocked yes)
			(layer "F.Fab")
			(effects
				(font
					(size 0.7874 0.5842)
					(thickness 0.000001)
				)
			)
		)
		(fp_text user "P1"
			(at 1.516888 0 180)
			(unlocked yes)
			(layer "F.Fab")
			(effects
				(font
					(size 0.7874 0.5842)
					(thickness 0.000001)
				)
			)
		)
		(fp_text user "PRESS-FIT"
			(at -6.762496 16.251428 0)
			(unlocked yes)
			(layer "F.Fab")
			(effects
				(font
					(size 1.6002 1.1938)
					(thickness 0.000001)
				)
				(justify left)
			)
		)
		(fp_text user "P17"
			(at -4.366768 38.227 180)
			(unlocked yes)
			(layer "F.Fab")
			(effects
				(font
					(size 0.7874 0.5842)
					(thickness 0.000001)
				)
			)
		)
		(fp_text user "P16"
			(at 2.228088 38.354 180)
			(unlocked yes)
			(layer "F.Fab")
			(effects
				(font
					(size 0.7874 0.5842)
					(thickness 0.000001)
				)
			)
		)
		(fp_text user "S12"
			(at -4.362958 41.09212 180)
			(unlocked yes)
			(layer "F.Fab")
			(effects
				(font
					(size 0.7874 0.5842)
					(thickness 0.000001)
				)
			)
		)
		(fp_text user "S1"
			(at 2.164842 41.6306 180)
			(unlocked yes)
			(layer "F.Fab")
			(effects
				(font
					(size 0.7874 0.5842)
					(thickness 0.000001)
				)
			)
		)
		(fp_text user "S6"
			(at 1.923288 48.133 180)
			(unlocked yes)
			(layer "F.Fab")
			(effects
				(font
					(size 0.7874 0.5842)
					(thickness 0.000001)
				)
			)
		)
		(fp_text user "S7"
			(at -4.426712 48.2346 180)
			(unlocked yes)
			(layer "F.Fab")
			(effects
				(font
					(size 0.7874 0.5842)
					(thickness 0.000001)
				)
			)
		)
		(pad "" np_thru_hole circle
			(at -1.35001 -2.54)
			(size 2.5146 2.5146)
			(drill 2.5146)
			(layers "*.Cu" "*.Mask")
			(clearance 0.381)
			(thermal_gap 0.381)
		)
		(pad "" np_thru_hole circle
			(at 0 50.8)
			(size 2.5146 2.5146)
			(drill 2.5146)
			(layers "*.Cu" "*.Mask")
			(clearance 0.381)
			(thermal_gap 0.381)
		)
		(pad "P1" thru_hole rect
			(at 0 0)
			(size 1.1684 1.1684)
			(drill 0.762)
			(layers "*.Cu" "*.Mask")
			(remove_unused_layers no)
			(net "GND")
			(clearance 0.0508)
			(padstack
				(mode front_inner_back)
				(layer "Inner"
					(shape circle)
					(size 1.1684 1.1684)
					(clearance 0.0508)
				)
				(layer "B.Cu"
					(shape rect)
					(size 1.1684 1.1684)
					(thermal_gap 0.0508)
					(clearance 0.0508)
				)
			)
		)
		(pad "P2" thru_hole circle
			(at 0 2.54)
			(size 1.1684 1.1684)
			(drill 0.762)
			(layers "*.Cu" "*.Mask")
			(remove_unused_layers no)
			(net "GND")
			(clearance 0.0508)
			(thermal_gap 0.0508)
		)
		(pad "P3" thru_hole circle
			(at 0 5.08)
			(size 1.1684 1.1684)
			(drill 0.762)
			(layers "*.Cu" "*.Mask")
			(remove_unused_layers no)
			(net "GND")
			(clearance 0.0508)
			(thermal_gap 0.0508)
		)
		(pad "P4" thru_hole circle
			(at 0 7.62)
			(size 1.1684 1.1684)
			(drill 0.762)
			(layers "*.Cu" "*.Mask")
			(remove_unused_layers no)
			(net "GND")
			(clearance 0.0508)
			(thermal_gap 0.0508)
		)
		(pad "P5" thru_hole circle
			(at 0 10.16)
			(size 1.1684 1.1684)
			(drill 0.762)
			(layers "*.Cu" "*.Mask")
			(remove_unused_layers no)
			(net "GND")
			(clearance 0.0508)
			(thermal_gap 0.0508)
		)
		(pad "P6" thru_hole circle
			(at 0 12.7)
			(size 1.1684 1.1684)
			(drill 0.762)
			(layers "*.Cu" "*.Mask")
			(remove_unused_layers no)
			(net "GND")
			(clearance 0.0508)
			(thermal_gap 0.0508)
		)
		(pad "P7" thru_hole circle
			(at 0 15.24)
			(size 1.1684 1.1684)
			(drill 0.762)
			(layers "*.Cu" "*.Mask")
			(remove_unused_layers no)
			(net "GND")
			(clearance 0.0508)
			(thermal_gap 0.0508)
		)
		(pad "P8" thru_hole circle
			(at 0 17.78)
			(size 1.1684 1.1684)
			(drill 0.762)
			(layers "*.Cu" "*.Mask")
			(remove_unused_layers no)
			(net "GND")
			(clearance 0.0508)
			(thermal_gap 0.0508)
		)
		(pad "P9" thru_hole circle
			(at 0 20.32)
			(size 1.1684 1.1684)
			(drill 0.762)
			(layers "*.Cu" "*.Mask")
			(remove_unused_layers no)
			(net "P12V")
			(clearance 0.0508)
			(thermal_gap 0.0508)
		)
		(pad "P10" thru_hole circle
			(at 0 22.86)
			(size 1.1684 1.1684)
			(drill 0.762)
			(layers "*.Cu" "*.Mask")
			(remove_unused_layers no)
			(net "P12V")
			(clearance 0.0508)
			(thermal_gap 0.0508)
		)
		(pad "P11" thru_hole circle
			(at 0 25.4)
			(size 1.1684 1.1684)
			(drill 0.762)
			(layers "*.Cu" "*.Mask")
			(remove_unused_layers no)
			(net "P12V")
			(clearance 0.0508)
			(thermal_gap 0.0508)
		)
		(pad "P12" thru_hole circle
			(at 0 27.94)
			(size 1.1684 1.1684)
			(drill 0.762)
			(layers "*.Cu" "*.Mask")
			(remove_unused_layers no)
			(net "P12V")
			(clearance 0.0508)
			(thermal_gap 0.0508)
		)
		(pad "P13" thru_hole circle
			(at 0 30.48)
			(size 1.1684 1.1684)
			(drill 0.762)
			(layers "*.Cu" "*.Mask")
			(remove_unused_layers no)
			(net "P12V")
			(clearance 0.0508)
			(thermal_gap 0.0508)
		)
		(pad "P14" thru_hole circle
			(at 0 33.02)
			(size 1.1684 1.1684)
			(drill 0.762)
			(layers "*.Cu" "*.Mask")
			(remove_unused_layers no)
			(net "P12V")
			(clearance 0.0508)
			(thermal_gap 0.0508)
		)
		(pad "P15" thru_hole circle
			(at 0 35.56)
			(size 1.1684 1.1684)
			(drill 0.762)
			(layers "*.Cu" "*.Mask")
			(remove_unused_layers no)
			(net "P12V")
			(clearance 0.0508)
			(thermal_gap 0.0508)
		)
		(pad "P16" thru_hole circle
			(at 0 38.1)
			(size 1.1684 1.1684)
			(drill 0.762)
			(layers "*.Cu" "*.Mask")
			(remove_unused_layers no)
			(net "P12V")
			(clearance 0.0508)
			(thermal_gap 0.0508)
		)
		(pad "P17" thru_hole circle
			(at -2.70002 38.1)
			(size 1.1684 1.1684)
			(drill 0.762)
			(layers "*.Cu" "*.Mask")
			(remove_unused_layers no)
			(net "P12V")
			(clearance 0.0508)
			(thermal_gap 0.0508)
		)
		(pad "P18" thru_hole circle
			(at -2.70002 35.56)
			(size 1.1684 1.1684)
			(drill 0.762)
			(layers "*.Cu" "*.Mask")
			(remove_unused_layers no)
			(net "P12V")
			(clearance 0.0508)
			(thermal_gap 0.0508)
		)
		(pad "P19" thru_hole circle
			(at -2.70002 33.02)
			(size 1.1684 1.1684)
			(drill 0.762)
			(layers "*.Cu" "*.Mask")
			(remove_unused_layers no)
			(net "P12V")
			(clearance 0.0508)
			(thermal_gap 0.0508)
		)
		(pad "P20" thru_hole circle
			(at -2.70002 30.48)
			(size 1.1684 1.1684)
			(drill 0.762)
			(layers "*.Cu" "*.Mask")
			(remove_unused_layers no)
			(net "P12V")
			(clearance 0.0508)
			(thermal_gap 0.0508)
		)
		(pad "P21" thru_hole circle
			(at -2.70002 27.94)
			(size 1.1684 1.1684)
			(drill 0.762)
			(layers "*.Cu" "*.Mask")
			(remove_unused_layers no)
			(net "P12V")
			(clearance 0.0508)
			(thermal_gap 0.0508)
		)
		(pad "P22" thru_hole circle
			(at -2.70002 25.4)
			(size 1.1684 1.1684)
			(drill 0.762)
			(layers "*.Cu" "*.Mask")
			(remove_unused_layers no)
			(net "P12V")
			(clearance 0.0508)
			(thermal_gap 0.0508)
		)
		(pad "P23" thru_hole circle
			(at -2.70002 22.86)
			(size 1.1684 1.1684)
			(drill 0.762)
			(layers "*.Cu" "*.Mask")
			(remove_unused_layers no)
			(net "P12V")
			(clearance 0.0508)
			(thermal_gap 0.0508)
		)
		(pad "P24" thru_hole circle
			(at -2.70002 20.32)
			(size 1.1684 1.1684)
			(drill 0.762)
			(layers "*.Cu" "*.Mask")
			(remove_unused_layers no)
			(net "P12V")
			(clearance 0.0508)
			(thermal_gap 0.0508)
		)
		(pad "P25" thru_hole circle
			(at -2.70002 17.78)
			(size 1.1684 1.1684)
			(drill 0.762)
			(layers "*.Cu" "*.Mask")
			(remove_unused_layers no)
			(net "GND")
			(clearance 0.0508)
			(thermal_gap 0.0508)
		)
		(pad "P26" thru_hole circle
			(at -2.70002 15.24)
			(size 1.1684 1.1684)
			(drill 0.762)
			(layers "*.Cu" "*.Mask")
			(remove_unused_layers no)
			(net "GND")
			(clearance 0.0508)
			(thermal_gap 0.0508)
		)
		(pad "P27" thru_hole circle
			(at -2.70002 12.7)
			(size 1.1684 1.1684)
			(drill 0.762)
			(layers "*.Cu" "*.Mask")
			(remove_unused_layers no)
			(net "GND")
			(clearance 0.0508)
			(thermal_gap 0.0508)
		)
		(pad "P28" thru_hole circle
			(at -2.70002 10.16)
			(size 1.1684 1.1684)
			(drill 0.762)
			(layers "*.Cu" "*.Mask")
			(remove_unused_layers no)
			(net "GND")
			(clearance 0.0508)
			(thermal_gap 0.0508)
		)
		(pad "P29" thru_hole circle
			(at -2.70002 7.62)
			(size 1.1684 1.1684)
			(drill 0.762)
			(layers "*.Cu" "*.Mask")
			(remove_unused_layers no)
			(net "GND")
			(clearance 0.0508)
			(thermal_gap 0.0508)
		)
		(pad "P30" thru_hole circle
			(at -2.70002 5.08)
			(size 1.1684 1.1684)
			(drill 0.762)
			(layers "*.Cu" "*.Mask")
			(remove_unused_layers no)
			(net "GND")
			(clearance 0.0508)
			(thermal_gap 0.0508)
		)
		(pad "P31" thru_hole circle
			(at -2.70002 2.54)
			(size 1.1684 1.1684)
			(drill 0.762)
			(layers "*.Cu" "*.Mask")
			(remove_unused_layers no)
			(net "GND")
			(clearance 0.0508)
			(thermal_gap 0.0508)
		)
		(pad "P32" thru_hole circle
			(at -2.70002 0)
			(size 1.1684 1.1684)
			(drill 0.762)
			(layers "*.Cu" "*.Mask")
			(remove_unused_layers no)
			(net "GND")
			(clearance 0.0508)
			(thermal_gap 0.0508)
		)
		(pad "S1" thru_hole circle
			(at 0.55499 41.60012)
			(size 1.1684 1.1684)
			(drill 0.762)
			(layers "*.Cu" "*.Mask")
			(remove_unused_layers no)
			(net "T4_BLAD1_TXD")
			(clearance 0.0508)
			(thermal_gap 0.0508)
		)
		(pad "S2" thru_hole circle
			(at -0.71501 42.87012)
			(size 1.1684 1.1684)
			(drill 0.762)
			(layers "*.Cu" "*.Mask")
			(remove_unused_layers no)
			(net "T4_BLAD1_RXD")
			(clearance 0.0508)
			(thermal_gap 0.0508)
		)
		(pad "S3" thru_hole circle
			(at 0.55499 44.14012)
			(size 1.1684 1.1684)
			(drill 0.762)
			(layers "*.Cu" "*.Mask")
			(remove_unused_layers no)
			(net "T4_BLAD1_EN")
			(clearance 0.0508)
			(thermal_gap 0.0508)
		)
		(pad "S4" thru_hole circle
			(at -0.71501 45.41012)
			(size 1.1684 1.1684)
			(drill 0.762)
			(layers "*.Cu" "*.Mask")
			(remove_unused_layers no)
			(net "B7_PSU_ALERT_N")
			(clearance 0.0508)
			(thermal_gap 0.0508)
		)
		(pad "S5" thru_hole circle
			(at 0.55499 46.68012)
			(size 1.1684 1.1684)
			(drill 0.762)
			(layers "*.Cu" "*.Mask")
			(remove_unused_layers no)
			(net "T4_BLAD2_TXD")
			(clearance 0.0508)
			(thermal_gap 0.0508)
		)
		(pad "S6" thru_hole circle
			(at -0.71501 47.95012)
			(size 1.1684 1.1684)
			(drill 0.762)
			(layers "*.Cu" "*.Mask")
			(remove_unused_layers no)
			(net "T4_BLAD2_RXD")
			(clearance 0.0508)
			(thermal_gap 0.0508)
		)
		(pad "S7" thru_hole circle
			(at -3.25501 47.95012)
			(size 1.1684 1.1684)
			(drill 0.762)
			(layers "*.Cu" "*.Mask")
			(remove_unused_layers no)
			(net "T4_BLAD4_RXD")
			(clearance 0.0508)
			(thermal_gap 0.0508)
		)
		(pad "S8" thru_hole circle
			(at -1.98501 46.68012)
			(size 1.1684 1.1684)
			(drill 0.762)
			(layers "*.Cu" "*.Mask")
			(remove_unused_layers no)
			(net "T4_BLAD4_TXD")
			(clearance 0.0508)
			(thermal_gap 0.0508)
		)
		(pad "S9" thru_hole circle
			(at -3.25501 45.41012)
			(size 1.1684 1.1684)
			(drill 0.762)
			(layers "*.Cu" "*.Mask")
			(remove_unused_layers no)
			(net "B8_PSU_ALERT_N")
			(clearance 0.0508)
			(thermal_gap 0.0508)
		)
		(pad "S10" thru_hole circle
			(at -1.98501 44.14012)
			(size 1.1684 1.1684)
			(drill 0.762)
			(layers "*.Cu" "*.Mask")
			(remove_unused_layers no)
			(net "T4_BLAD3_EN")
			(clearance 0.0508)
			(thermal_gap 0.0508)
		)
		(pad "S11" thru_hole circle
			(at -3.25501 42.87012)
			(size 1.1684 1.1684)
			(drill 0.762)
			(layers "*.Cu" "*.Mask")
			(remove_unused_layers no)
			(net "T4_BLAD3_RXD")
			(clearance 0.0508)
			(thermal_gap 0.0508)
		)
		(pad "S12" thru_hole circle
			(at -1.98501 41.60012)
			(size 1.1684 1.1684)
			(drill 0.762)
			(layers "*.Cu" "*.Mask")
			(remove_unused_layers no)
			(net "T4_BLAD3_TXD")
			(clearance 0.0508)
			(thermal_gap 0.0508)
		)
		(zone
			(layer "F.Cu")
			(hatch none 0.5)
			(connect_pads
				(clearance 0)
			)
			(min_thickness 0.25)
			(keepout
				(tracks allowed)
				(vias not_allowed)
				(pads allowed)
				(copperpour not_allowed)
				(footprints allowed)
			)
			(placement
				(enabled no)
				(sheetname "")
			)
			(fill
				(thermal_gap 0.5)
				(thermal_bridge_width 0.5)
				(island_removal_mode 0)
			)
			(polygon
				(pts
					(xy 85.010244 -142.80388) (xy 92.655644 -142.80388) (xy 92.655644 -137.69848) (xy 85.010244 -137.69848)
					(xy 84.984844 -137.69848) (xy 84.984844 -142.80388)
				)
			)
		)
		(zone
			(layer "F.Cu")
			(hatch none 0.5)
			(connect_pads
				(clearance 0)
			)
			(min_thickness 0.25)
			(keepout
				(tracks allowed)
				(vias not_allowed)
				(pads allowed)
				(copperpour not_allowed)
				(footprints allowed)
			)
			(placement
				(enabled no)
				(sheetname "")
			)
			(fill
				(thermal_gap 0.5)
				(thermal_bridge_width 0.5)
				(island_removal_mode 0)
			)
			(polygon
				(pts
					(xy 43.379644 -138.28268) (xy 43.379644 -142.24508) (xy 82.775044 -142.24508) (xy 82.800444 -142.24508)
					(xy 82.800444 -138.28268) (xy 82.800444 -138.25728) (xy 43.379644 -138.25728)
				)
			)
		)
		(zone
			(layers "F.Cu" "B.Cu" "In1.Cu" "In2.Cu" "In3.Cu" "In4.Cu" "In5.Cu" "In6.Cu")
			(hatch none 0.5)
			(connect_pads
				(clearance 0)
			)
			(min_thickness 0.25)
			(keepout
				(tracks not_allowed)
				(vias allowed)
				(pads allowed)
				(copperpour not_allowed)
				(footprints allowed)
			)
			(placement
				(enabled no)
				(sheetname "")
			)
			(fill
				(thermal_gap 0.5)
				(thermal_bridge_width 0.5)
				(island_removal_mode 0)
			)
			(polygon
				(pts
					(arc
						(start 43.180254 -140.26007)
						(mid 39.819834 -140.26007)
						(end 43.180254 -140.26007)
					)
				)
			)
		)
		(zone
			(layers "F.Cu" "B.Cu" "In1.Cu" "In2.Cu" "In3.Cu" "In4.Cu" "In5.Cu" "In6.Cu")
			(hatch none 0.5)
			(connect_pads
				(clearance 0)
			)
			(min_thickness 0.25)
			(keepout
				(tracks not_allowed)
				(vias allowed)
				(pads allowed)
				(copperpour not_allowed)
				(footprints allowed)
			)
			(placement
				(enabled no)
				(sheetname "")
			)
			(fill
				(thermal_gap 0.5)
				(thermal_bridge_width 0.5)
				(island_removal_mode 0)
			)
			(polygon
				(pts
					(arc
						(start 96.524064 -141.61008)
						(mid 93.156024 -141.61008)
						(end 96.524064 -141.61008)
					)
				)
			)
		)
	)
	(footprint ""
		(layer "B.Cu")
		(at 44.040044 -186.06008 90)
		(property "Reference" "J11"
			(at 6.252972 -4.579366 0)
			(unlocked yes)
			(layer "B.SilkS")
			(effects
				(font
					(size 0.7874 0.5842)
					(thickness 0.1524)
				)
				(justify left mirror)
			)
		)
		(property "Value" ""
			(at 0 0 90)
			(layer "B.Fab")
			(effects
				(font
					(size 1.27 1.27)
				)
				(justify mirror)
			)
		)
		(duplicate_pad_numbers_are_jumpers no)
		(fp_line
			(start 5.275072 -13.910056)
			(end -7.975092 -13.910056)
			(stroke
				(width 0.1524)
				(type default)
			)
			(layer "F.SilkS")
		)
		(fp_line
			(start -7.975092 -13.910056)
			(end -7.975092 62.170056)
			(stroke
				(width 0.1524)
				(type default)
			)
			(layer "F.SilkS")
		)
		(fp_line
			(start 5.275072 62.170056)
			(end 5.275072 -13.910056)
			(stroke
				(width 0.1524)
				(type default)
			)
			(layer "F.SilkS")
		)
		(fp_line
			(start -7.975092 62.170056)
			(end 5.275072 62.170056)
			(stroke
				(width 0.1524)
				(type default)
			)
			(layer "F.SilkS")
		)
		(fp_line
			(start 5.275072 -13.910056)
			(end -7.975092 -13.910056)
			(stroke
				(width 0.1524)
				(type default)
			)
			(layer "B.SilkS")
		)
		(fp_line
			(start -7.975092 -13.910056)
			(end -7.975092 62.170056)
			(stroke
				(width 0.1524)
				(type default)
			)
			(layer "B.SilkS")
		)
		(fp_line
			(start 2.275078 -10.910062)
			(end 2.275078 59.170062)
			(stroke
				(width 0.1524)
				(type default)
			)
			(layer "B.SilkS")
		)
		(fp_line
			(start -4.975098 -10.910062)
			(end 2.275078 -10.910062)
			(stroke
				(width 0.1524)
				(type default)
			)
			(layer "B.SilkS")
		)
		(fp_line
			(start 2.275078 59.170062)
			(end -4.975098 59.170062)
			(stroke
				(width 0.1524)
				(type default)
			)
			(layer "B.SilkS")
		)
		(fp_line
			(start -4.975098 59.170062)
			(end -4.975098 -10.910062)
			(stroke
				(width 0.1524)
				(type default)
			)
			(layer "B.SilkS")
		)
		(fp_line
			(start 5.275072 62.170056)
			(end 5.275072 -13.910056)
			(stroke
				(width 0.1524)
				(type default)
			)
			(layer "B.SilkS")
		)
		(fp_line
			(start -7.975092 62.170056)
			(end 5.275072 62.170056)
			(stroke
				(width 0.1524)
				(type default)
			)
			(layer "B.SilkS")
		)
		(fp_poly
			(pts
				(xy 4.103878 -0.759206) (xy 4.103878 0.764794) (xy 2.579878 0.002794)
			)
			(stroke
				(width 0)
				(type default)
			)
			(fill yes)
			(layer "B.SilkS")
		)
		(fp_poly
			(pts
				(xy 2.275078 -10.910062) (xy 2.275078 59.170062) (xy -4.975098 59.170062) (xy -4.975098 -10.910062)
			)
			(stroke
				(width 0)
				(type default)
			)
			(fill no)
			(layer "B.CrtYd")
		)
		(fp_poly
			(pts
				(xy 1.1938 40.9702) (xy 1.1938 48.6156) (xy -3.9116 48.6156) (xy -3.9116 40.9702) (xy -3.9116 40.9448)
				(xy 1.1938 40.9448)
			)
			(stroke
				(width 0)
				(type default)
			)
			(fill no)
			(layer "F.CrtYd")
		)
		(fp_poly
			(pts
				(xy -3.3274 -0.6604) (xy 0.635 -0.6604) (xy 0.635 38.735) (xy 0.635 38.7604) (xy -3.3274 38.7604)
				(xy -3.3528 38.7604) (xy -3.3528 -0.6604)
			)
			(stroke
				(width 0)
				(type default)
			)
			(fill no)
			(layer "F.CrtYd")
		)
		(fp_poly
			(pts
				(arc
					(start -1.35001 -1.01219)
					(mid -1.35001 -4.06781)
					(end -1.35001 -1.01219)
				)
			)
			(stroke
				(width 0)
				(type default)
			)
			(fill no)
			(layer "F.CrtYd")
		)
		(fp_poly
			(pts
				(arc
					(start 0 52.33162)
					(mid 0 49.26838)
					(end 0 52.33162)
				)
			)
			(stroke
				(width 0)
				(type default)
			)
			(fill no)
			(layer "F.CrtYd")
		)
		(fp_line
			(start 2.275078 -10.910062)
			(end 2.275078 59.170062)
			(stroke
				(width 0.1)
				(type default)
			)
			(layer "B.Fab")
		)
		(fp_line
			(start -4.975098 -10.910062)
			(end 2.275078 -10.910062)
			(stroke
				(width 0.1)
				(type default)
			)
			(layer "B.Fab")
		)
		(fp_line
			(start 2.275078 59.170062)
			(end -4.975098 59.170062)
			(stroke
				(width 0.1)
				(type default)
			)
			(layer "B.Fab")
		)
		(fp_line
			(start -4.975098 59.170062)
			(end -4.975098 -10.910062)
			(stroke
				(width 0.1)
				(type default)
			)
			(layer "B.Fab")
		)
		(fp_poly
			(pts
				(xy 4.103878 -0.759206) (xy 4.103878 0.764794) (xy 2.579878 0.002794)
			)
			(stroke
				(width 0)
				(type default)
			)
			(fill yes)
			(layer "B.Fab")
		)
		(fp_line
			(start 5.275072 -13.910056)
			(end -7.975092 -13.910056)
			(stroke
				(width 0.1)
				(type default)
			)
			(layer "F.Fab")
		)
		(fp_line
			(start -7.975092 -13.910056)
			(end -7.975092 62.170056)
			(stroke
				(width 0.1)
				(type default)
			)
			(layer "F.Fab")
		)
		(fp_line
			(start 5.275072 62.170056)
			(end 5.275072 -13.910056)
			(stroke
				(width 0.1)
				(type default)
			)
			(layer "F.Fab")
		)
		(fp_line
			(start -7.975092 62.170056)
			(end 5.275072 62.170056)
			(stroke
				(width 0.1)
				(type default)
			)
			(layer "F.Fab")
		)
		(fp_text user "P1"
			(at 1.568704 0.009906 0)
			(unlocked yes)
			(layer "F.SilkS")
			(effects
				(font
					(size 0.7874 0.5842)
					(thickness 0.1524)
				)
			)
		)
		(fp_text user "P32"
			(at -4.080002 0.018288 0)
			(unlocked yes)
			(layer "F.SilkS")
			(effects
				(font
					(size 0.7874 0.5842)
					(thickness 0.1524)
				)
			)
		)
		(fp_text user "PRESS-FIT"
			(at -9.227566 16.405098 0)
			(unlocked yes)
			(layer "F.SilkS")
			(effects
				(font
					(size 0.7874 0.5842)
					(thickness 0.1524)
				)
				(justify left)
			)
		)
		(fp_text user "P16"
			(at 6.213348 37.464238 0)
			(unlocked yes)
			(layer "F.SilkS")
			(effects
				(font
					(size 0.7874 0.5842)
					(thickness 0.1524)
				)
			)
		)
		(fp_text user "P17"
			(at -9.541764 37.899848 0)
			(unlocked yes)
			(layer "F.SilkS")
			(effects
				(font
					(size 0.7874 0.5842)
					(thickness 0.1524)
				)
			)
		)
		(fp_text user "S12"
			(at -8.851392 40.402764 0)
			(unlocked yes)
			(layer "F.SilkS")
			(effects
				(font
					(size 0.7874 0.5842)
					(thickness 0.1524)
				)
			)
		)
		(fp_text user "S1"
			(at 6.246876 41.875456 0)
			(unlocked yes)
			(layer "F.SilkS")
			(effects
				(font
					(size 0.7874 0.5842)
					(thickness 0.1524)
				)
			)
		)
		(fp_text user "S6"
			(at 6.012942 47.5234 0)
			(unlocked yes)
			(layer "F.SilkS")
			(effects
				(font
					(size 0.7874 0.5842)
					(thickness 0.1524)
				)
			)
		)
		(fp_text user "S7"
			(at -9.227566 49.996344 0)
			(unlocked yes)
			(layer "F.SilkS")
			(effects
				(font
					(size 0.7874 0.5842)
					(thickness 0.1524)
				)
			)
		)
		(fp_text user "P1"
			(at 2.944368 -1.463802 0)
			(unlocked yes)
			(layer "B.SilkS")
			(effects
				(font
					(size 0.7874 0.5842)
					(thickness 0.1524)
				)
				(justify mirror)
			)
		)
		(fp_text user "P32"
			(at -5.975604 -0.435356 0)
			(unlocked yes)
			(layer "B.SilkS")
			(effects
				(font
					(size 0.7874 0.5842)
					(thickness 0.1524)
				)
				(justify mirror)
			)
		)
		(fp_text user "PRESS-FIT"
			(at -7.18947 29.8831 0)
			(unlocked yes)
			(layer "B.SilkS")
			(effects
				(font
					(size 0.7874 0.5842)
					(thickness 0.1524)
				)
				(justify left mirror)
			)
		)
		(fp_text user "P17"
			(at -5.899658 37.6174 0)
			(unlocked yes)
			(layer "B.SilkS")
			(effects
				(font
					(size 0.7874 0.5842)
					(thickness 0.1524)
				)
				(justify mirror)
			)
		)
		(fp_text user "P16"
			(at 3.13182 37.89172 0)
			(unlocked yes)
			(layer "B.SilkS")
			(effects
				(font
					(size 0.7874 0.5842)
					(thickness 0.1524)
				)
				(justify mirror)
			)
		)
		(fp_text user "S1"
			(at 3.024632 41.766236 0)
			(unlocked yes)
			(layer "B.SilkS")
			(effects
				(font
					(size 0.7874 0.5842)
					(thickness 0.1524)
				)
				(justify mirror)
			)
		)
		(fp_text user "S12"
			(at -5.827268 42.067988 0)
			(unlocked yes)
			(layer "B.SilkS")
			(effects
				(font
					(size 0.7874 0.5842)
					(thickness 0.1524)
				)
				(justify mirror)
			)
		)
		(fp_text user "S6"
			(at 3.123438 47.701454 0)
			(unlocked yes)
			(layer "B.SilkS")
			(effects
				(font
					(size 0.7874 0.5842)
					(thickness 0.1524)
				)
				(justify mirror)
			)
		)
		(fp_text user "S7"
			(at -5.907532 47.803816 0)
			(unlocked yes)
			(layer "B.SilkS")
			(effects
				(font
					(size 0.7874 0.5842)
					(thickness 0.1524)
				)
				(justify mirror)
			)
		)
		(fp_text user "P1"
			(at 3.108452 -1.27 180)
			(unlocked yes)
			(layer "B.Fab")
			(effects
				(font
					(size 0.7874 0.5842)
					(thickness 0.000001)
				)
				(justify mirror)
			)
		)
		(fp_text user "P32"
			(at -5.781548 -0.0508 180)
			(unlocked yes)
			(layer "B.Fab")
			(effects
				(font
					(size 0.7874 0.5842)
					(thickness 0.000001)
				)
				(justify mirror)
			)
		)
		(fp_text user "PRESS-FIT"
			(at -6.82371 29.8831 0)
			(unlocked yes)
			(layer "B.Fab")
			(effects
				(font
					(size 1.6002 1.1938)
					(thickness 0.000001)
				)
				(justify left mirror)
			)
		)
		(fp_text user "P17"
			(at -5.72135 38.0746 180)
			(unlocked yes)
			(layer "B.Fab")
			(effects
				(font
					(size 0.7874 0.5842)
					(thickness 0.000001)
				)
				(justify mirror)
			)
		)
		(fp_text user "P16"
			(at 3.159252 38.3794 180)
			(unlocked yes)
			(layer "B.Fab")
			(effects
				(font
					(size 0.7874 0.5842)
					(thickness 0.000001)
				)
				(justify mirror)
			)
		)
		(fp_text user "S12"
			(at -5.79374 41.42232 180)
			(unlocked yes)
			(layer "B.Fab")
			(effects
				(font
					(size 0.7874 0.5842)
					(thickness 0.000001)
				)
				(justify mirror)
			)
		)
		(fp_text user "S1"
			(at 3.09626 41.656 180)
			(unlocked yes)
			(layer "B.Fab")
			(effects
				(font
					(size 0.7874 0.5842)
					(thickness 0.000001)
				)
				(justify mirror)
			)
		)
		(fp_text user "S6"
			(at 3.133852 48.0822 180)
			(unlocked yes)
			(layer "B.Fab")
			(effects
				(font
					(size 0.7874 0.5842)
					(thickness 0.000001)
				)
				(justify mirror)
			)
		)
		(fp_text user "S7"
			(at -5.781548 48.0822 180)
			(unlocked yes)
			(layer "B.Fab")
			(effects
				(font
					(size 0.7874 0.5842)
					(thickness 0.000001)
				)
				(justify mirror)
			)
		)
		(fp_text user "P32"
			(at -4.071112 -0.0762 180)
			(unlocked yes)
			(layer "F.Fab")
			(effects
				(font
					(size 0.7874 0.5842)
					(thickness 0.000001)
				)
			)
		)
		(fp_text user "P1"
			(at 1.516888 0 180)
			(unlocked yes)
			(layer "F.Fab")
			(effects
				(font
					(size 0.7874 0.5842)
					(thickness 0.000001)
				)
			)
		)
		(fp_text user "PRESS-FIT"
			(at -6.762496 16.251428 0)
			(unlocked yes)
			(layer "F.Fab")
			(effects
				(font
					(size 1.6002 1.1938)
					(thickness 0.000001)
				)
				(justify left)
			)
		)
		(fp_text user "P17"
			(at -4.366768 38.227 180)
			(unlocked yes)
			(layer "F.Fab")
			(effects
				(font
					(size 0.7874 0.5842)
					(thickness 0.000001)
				)
			)
		)
		(fp_text user "P16"
			(at 2.228088 38.354 180)
			(unlocked yes)
			(layer "F.Fab")
			(effects
				(font
					(size 0.7874 0.5842)
					(thickness 0.000001)
				)
			)
		)
		(fp_text user "S12"
			(at -4.362958 41.09212 180)
			(unlocked yes)
			(layer "F.Fab")
			(effects
				(font
					(size 0.7874 0.5842)
					(thickness 0.000001)
				)
			)
		)
		(fp_text user "S1"
			(at 2.164842 41.6306 180)
			(unlocked yes)
			(layer "F.Fab")
			(effects
				(font
					(size 0.7874 0.5842)
					(thickness 0.000001)
				)
			)
		)
		(fp_text user "S6"
			(at 1.923288 48.133 180)
			(unlocked yes)
			(layer "F.Fab")
			(effects
				(font
					(size 0.7874 0.5842)
					(thickness 0.000001)
				)
			)
		)
		(fp_text user "S7"
			(at -4.426712 48.2346 180)
			(unlocked yes)
			(layer "F.Fab")
			(effects
				(font
					(size 0.7874 0.5842)
					(thickness 0.000001)
				)
			)
		)
		(pad "" np_thru_hole circle
			(at -1.35001 -2.54)
			(size 2.5146 2.5146)
			(drill 2.5146)
			(layers "*.Cu" "*.Mask")
			(clearance 0.381)
			(thermal_gap 0.381)
		)
		(pad "" np_thru_hole circle
			(at 0 50.8)
			(size 2.5146 2.5146)
			(drill 2.5146)
			(layers "*.Cu" "*.Mask")
			(clearance 0.381)
			(thermal_gap 0.381)
		)
		(pad "P1" thru_hole rect
			(at 0 0)
			(size 1.1684 1.1684)
			(drill 0.762)
			(layers "*.Cu" "*.Mask")
			(remove_unused_layers no)
			(net "GND")
			(clearance 0.0508)
			(padstack
				(mode front_inner_back)
				(layer "Inner"
					(shape circle)
					(size 1.1684 1.1684)
					(clearance 0.0508)
				)
				(layer "B.Cu"
					(shape rect)
					(size 1.1684 1.1684)
					(thermal_gap 0.0508)
					(clearance 0.0508)
				)
			)
		)
		(pad "P2" thru_hole circle
			(at 0 2.54)
			(size 1.1684 1.1684)
			(drill 0.762)
			(layers "*.Cu" "*.Mask")
			(remove_unused_layers no)
			(net "GND")
			(clearance 0.0508)
			(thermal_gap 0.0508)
		)
		(pad "P3" thru_hole circle
			(at 0 5.08)
			(size 1.1684 1.1684)
			(drill 0.762)
			(layers "*.Cu" "*.Mask")
			(remove_unused_layers no)
			(net "GND")
			(clearance 0.0508)
			(thermal_gap 0.0508)
		)
		(pad "P4" thru_hole circle
			(at 0 7.62)
			(size 1.1684 1.1684)
			(drill 0.762)
			(layers "*.Cu" "*.Mask")
			(remove_unused_layers no)
			(net "GND")
			(clearance 0.0508)
			(thermal_gap 0.0508)
		)
		(pad "P5" thru_hole circle
			(at 0 10.16)
			(size 1.1684 1.1684)
			(drill 0.762)
			(layers "*.Cu" "*.Mask")
			(remove_unused_layers no)
			(net "GND")
			(clearance 0.0508)
			(thermal_gap 0.0508)
		)
		(pad "P6" thru_hole circle
			(at 0 12.7)
			(size 1.1684 1.1684)
			(drill 0.762)
			(layers "*.Cu" "*.Mask")
			(remove_unused_layers no)
			(net "GND")
			(clearance 0.0508)
			(thermal_gap 0.0508)
		)
		(pad "P7" thru_hole circle
			(at 0 15.24)
			(size 1.1684 1.1684)
			(drill 0.762)
			(layers "*.Cu" "*.Mask")
			(remove_unused_layers no)
			(net "GND")
			(clearance 0.0508)
			(thermal_gap 0.0508)
		)
		(pad "P8" thru_hole circle
			(at 0 17.78)
			(size 1.1684 1.1684)
			(drill 0.762)
			(layers "*.Cu" "*.Mask")
			(remove_unused_layers no)
			(net "GND")
			(clearance 0.0508)
			(thermal_gap 0.0508)
		)
		(pad "P9" thru_hole circle
			(at 0 20.32)
			(size 1.1684 1.1684)
			(drill 0.762)
			(layers "*.Cu" "*.Mask")
			(remove_unused_layers no)
			(net "P12V")
			(clearance 0.0508)
			(thermal_gap 0.0508)
		)
		(pad "P10" thru_hole circle
			(at 0 22.86)
			(size 1.1684 1.1684)
			(drill 0.762)
			(layers "*.Cu" "*.Mask")
			(remove_unused_layers no)
			(net "P12V")
			(clearance 0.0508)
			(thermal_gap 0.0508)
		)
		(pad "P11" thru_hole circle
			(at 0 25.4)
			(size 1.1684 1.1684)
			(drill 0.762)
			(layers "*.Cu" "*.Mask")
			(remove_unused_layers no)
			(net "P12V")
			(clearance 0.0508)
			(thermal_gap 0.0508)
		)
		(pad "P12" thru_hole circle
			(at 0 27.94)
			(size 1.1684 1.1684)
			(drill 0.762)
			(layers "*.Cu" "*.Mask")
			(remove_unused_layers no)
			(net "P12V")
			(clearance 0.0508)
			(thermal_gap 0.0508)
		)
		(pad "P13" thru_hole circle
			(at 0 30.48)
			(size 1.1684 1.1684)
			(drill 0.762)
			(layers "*.Cu" "*.Mask")
			(remove_unused_layers no)
			(net "P12V")
			(clearance 0.0508)
			(thermal_gap 0.0508)
		)
		(pad "P14" thru_hole circle
			(at 0 33.02)
			(size 1.1684 1.1684)
			(drill 0.762)
			(layers "*.Cu" "*.Mask")
			(remove_unused_layers no)
			(net "P12V")
			(clearance 0.0508)
			(thermal_gap 0.0508)
		)
		(pad "P15" thru_hole circle
			(at 0 35.56)
			(size 1.1684 1.1684)
			(drill 0.762)
			(layers "*.Cu" "*.Mask")
			(remove_unused_layers no)
			(net "P12V")
			(clearance 0.0508)
			(thermal_gap 0.0508)
		)
		(pad "P16" thru_hole circle
			(at 0 38.1)
			(size 1.1684 1.1684)
			(drill 0.762)
			(layers "*.Cu" "*.Mask")
			(remove_unused_layers no)
			(net "P12V")
			(clearance 0.0508)
			(thermal_gap 0.0508)
		)
		(pad "P17" thru_hole circle
			(at -2.70002 38.1)
			(size 1.1684 1.1684)
			(drill 0.762)
			(layers "*.Cu" "*.Mask")
			(remove_unused_layers no)
			(net "P12V")
			(clearance 0.0508)
			(thermal_gap 0.0508)
		)
		(pad "P18" thru_hole circle
			(at -2.70002 35.56)
			(size 1.1684 1.1684)
			(drill 0.762)
			(layers "*.Cu" "*.Mask")
			(remove_unused_layers no)
			(net "P12V")
			(clearance 0.0508)
			(thermal_gap 0.0508)
		)
		(pad "P19" thru_hole circle
			(at -2.70002 33.02)
			(size 1.1684 1.1684)
			(drill 0.762)
			(layers "*.Cu" "*.Mask")
			(remove_unused_layers no)
			(net "P12V")
			(clearance 0.0508)
			(thermal_gap 0.0508)
		)
		(pad "P20" thru_hole circle
			(at -2.70002 30.48)
			(size 1.1684 1.1684)
			(drill 0.762)
			(layers "*.Cu" "*.Mask")
			(remove_unused_layers no)
			(net "P12V")
			(clearance 0.0508)
			(thermal_gap 0.0508)
		)
		(pad "P21" thru_hole circle
			(at -2.70002 27.94)
			(size 1.1684 1.1684)
			(drill 0.762)
			(layers "*.Cu" "*.Mask")
			(remove_unused_layers no)
			(net "P12V")
			(clearance 0.0508)
			(thermal_gap 0.0508)
		)
		(pad "P22" thru_hole circle
			(at -2.70002 25.4)
			(size 1.1684 1.1684)
			(drill 0.762)
			(layers "*.Cu" "*.Mask")
			(remove_unused_layers no)
			(net "P12V")
			(clearance 0.0508)
			(thermal_gap 0.0508)
		)
		(pad "P23" thru_hole circle
			(at -2.70002 22.86)
			(size 1.1684 1.1684)
			(drill 0.762)
			(layers "*.Cu" "*.Mask")
			(remove_unused_layers no)
			(net "P12V")
			(clearance 0.0508)
			(thermal_gap 0.0508)
		)
		(pad "P24" thru_hole circle
			(at -2.70002 20.32)
			(size 1.1684 1.1684)
			(drill 0.762)
			(layers "*.Cu" "*.Mask")
			(remove_unused_layers no)
			(net "P12V")
			(clearance 0.0508)
			(thermal_gap 0.0508)
		)
		(pad "P25" thru_hole circle
			(at -2.70002 17.78)
			(size 1.1684 1.1684)
			(drill 0.762)
			(layers "*.Cu" "*.Mask")
			(remove_unused_layers no)
			(net "GND")
			(clearance 0.0508)
			(thermal_gap 0.0508)
		)
		(pad "P26" thru_hole circle
			(at -2.70002 15.24)
			(size 1.1684 1.1684)
			(drill 0.762)
			(layers "*.Cu" "*.Mask")
			(remove_unused_layers no)
			(net "GND")
			(clearance 0.0508)
			(thermal_gap 0.0508)
		)
		(pad "P27" thru_hole circle
			(at -2.70002 12.7)
			(size 1.1684 1.1684)
			(drill 0.762)
			(layers "*.Cu" "*.Mask")
			(remove_unused_layers no)
			(net "GND")
			(clearance 0.0508)
			(thermal_gap 0.0508)
		)
		(pad "P28" thru_hole circle
			(at -2.70002 10.16)
			(size 1.1684 1.1684)
			(drill 0.762)
			(layers "*.Cu" "*.Mask")
			(remove_unused_layers no)
			(net "GND")
			(clearance 0.0508)
			(thermal_gap 0.0508)
		)
		(pad "P29" thru_hole circle
			(at -2.70002 7.62)
			(size 1.1684 1.1684)
			(drill 0.762)
			(layers "*.Cu" "*.Mask")
			(remove_unused_layers no)
			(net "GND")
			(clearance 0.0508)
			(thermal_gap 0.0508)
		)
		(pad "P30" thru_hole circle
			(at -2.70002 5.08)
			(size 1.1684 1.1684)
			(drill 0.762)
			(layers "*.Cu" "*.Mask")
			(remove_unused_layers no)
			(net "GND")
			(clearance 0.0508)
			(thermal_gap 0.0508)
		)
		(pad "P31" thru_hole circle
			(at -2.70002 2.54)
			(size 1.1684 1.1684)
			(drill 0.762)
			(layers "*.Cu" "*.Mask")
			(remove_unused_layers no)
			(net "GND")
			(clearance 0.0508)
			(thermal_gap 0.0508)
		)
		(pad "P32" thru_hole circle
			(at -2.70002 0)
			(size 1.1684 1.1684)
			(drill 0.762)
			(layers "*.Cu" "*.Mask")
			(remove_unused_layers no)
			(net "GND")
			(clearance 0.0508)
			(thermal_gap 0.0508)
		)
		(pad "S1" thru_hole circle
			(at 0.55499 41.60012)
			(size 1.1684 1.1684)
			(drill 0.762)
			(layers "*.Cu" "*.Mask")
			(remove_unused_layers no)
			(net "T5_BLAD1_TXD")
			(clearance 0.0508)
			(thermal_gap 0.0508)
		)
		(pad "S2" thru_hole circle
			(at -0.71501 42.87012)
			(size 1.1684 1.1684)
			(drill 0.762)
			(layers "*.Cu" "*.Mask")
			(remove_unused_layers no)
			(net "T5_BLAD1_RXD")
			(clearance 0.0508)
			(thermal_gap 0.0508)
		)
		(pad "S3" thru_hole circle
			(at 0.55499 44.14012)
			(size 1.1684 1.1684)
			(drill 0.762)
			(layers "*.Cu" "*.Mask")
			(remove_unused_layers no)
			(net "T5_BLAD1_EN")
			(clearance 0.0508)
			(thermal_gap 0.0508)
		)
		(pad "S4" thru_hole circle
			(at -0.71501 45.41012)
			(size 1.1684 1.1684)
			(drill 0.762)
			(layers "*.Cu" "*.Mask")
			(remove_unused_layers no)
			(net "B9_PSU_ALERT_N")
			(clearance 0.0508)
			(thermal_gap 0.0508)
		)
		(pad "S5" thru_hole circle
			(at 0.55499 46.68012)
			(size 1.1684 1.1684)
			(drill 0.762)
			(layers "*.Cu" "*.Mask")
			(remove_unused_layers no)
			(net "T5_BLAD2_TXD")
			(clearance 0.0508)
			(thermal_gap 0.0508)
		)
		(pad "S6" thru_hole circle
			(at -0.71501 47.95012)
			(size 1.1684 1.1684)
			(drill 0.762)
			(layers "*.Cu" "*.Mask")
			(remove_unused_layers no)
			(net "T5_BLAD2_RXD")
			(clearance 0.0508)
			(thermal_gap 0.0508)
		)
		(pad "S7" thru_hole circle
			(at -3.25501 47.95012)
			(size 1.1684 1.1684)
			(drill 0.762)
			(layers "*.Cu" "*.Mask")
			(remove_unused_layers no)
			(net "T5_BLAD4_RXD")
			(clearance 0.0508)
			(thermal_gap 0.0508)
		)
		(pad "S8" thru_hole circle
			(at -1.98501 46.68012)
			(size 1.1684 1.1684)
			(drill 0.762)
			(layers "*.Cu" "*.Mask")
			(remove_unused_layers no)
			(net "T5_BLAD4_TXD")
			(clearance 0.0508)
			(thermal_gap 0.0508)
		)
		(pad "S9" thru_hole circle
			(at -3.25501 45.41012)
			(size 1.1684 1.1684)
			(drill 0.762)
			(layers "*.Cu" "*.Mask")
			(remove_unused_layers no)
			(net "B10_PSU_ALERT_N")
			(clearance 0.0508)
			(thermal_gap 0.0508)
		)
		(pad "S10" thru_hole circle
			(at -1.98501 44.14012)
			(size 1.1684 1.1684)
			(drill 0.762)
			(layers "*.Cu" "*.Mask")
			(remove_unused_layers no)
			(net "T5_BLAD3_EN")
			(clearance 0.0508)
			(thermal_gap 0.0508)
		)
		(pad "S11" thru_hole circle
			(at -3.25501 42.87012)
			(size 1.1684 1.1684)
			(drill 0.762)
			(layers "*.Cu" "*.Mask")
			(remove_unused_layers no)
			(net "T5_BLAD3_RXD")
			(clearance 0.0508)
			(thermal_gap 0.0508)
		)
		(pad "S12" thru_hole circle
			(at -1.98501 41.60012)
			(size 1.1684 1.1684)
			(drill 0.762)
			(layers "*.Cu" "*.Mask")
			(remove_unused_layers no)
			(net "T5_BLAD3_TXD")
			(clearance 0.0508)
			(thermal_gap 0.0508)
		)
		(zone
			(layer "F.Cu")
			(hatch none 0.5)
			(connect_pads
				(clearance 0)
			)
			(min_thickness 0.25)
			(keepout
				(tracks allowed)
				(vias not_allowed)
				(pads allowed)
				(copperpour not_allowed)
				(footprints allowed)
			)
			(placement
				(enabled no)
				(sheetname "")
			)
			(fill
				(thermal_gap 0.5)
				(thermal_bridge_width 0.5)
				(island_removal_mode 0)
			)
			(polygon
				(pts
					(xy 85.010244 -187.25388) (xy 92.655644 -187.25388) (xy 92.655644 -182.14848) (xy 85.010244 -182.14848)
					(xy 84.984844 -182.14848) (xy 84.984844 -187.25388)
				)
			)
		)
		(zone
			(layer "F.Cu")
			(hatch none 0.5)
			(connect_pads
				(clearance 0)
			)
			(min_thickness 0.25)
			(keepout
				(tracks allowed)
				(vias not_allowed)
				(pads allowed)
				(copperpour not_allowed)
				(footprints allowed)
			)
			(placement
				(enabled no)
				(sheetname "")
			)
			(fill
				(thermal_gap 0.5)
				(thermal_bridge_width 0.5)
				(island_removal_mode 0)
			)
			(polygon
				(pts
					(xy 43.379644 -182.73268) (xy 43.379644 -186.69508) (xy 82.775044 -186.69508) (xy 82.800444 -186.69508)
					(xy 82.800444 -182.73268) (xy 82.800444 -182.70728) (xy 43.379644 -182.70728)
				)
			)
		)
		(zone
			(layers "F.Cu" "B.Cu" "In1.Cu" "In2.Cu" "In3.Cu" "In4.Cu" "In5.Cu" "In6.Cu")
			(hatch none 0.5)
			(connect_pads
				(clearance 0)
			)
			(min_thickness 0.25)
			(keepout
				(tracks not_allowed)
				(vias allowed)
				(pads allowed)
				(copperpour not_allowed)
				(footprints allowed)
			)
			(placement
				(enabled no)
				(sheetname "")
			)
			(fill
				(thermal_gap 0.5)
				(thermal_bridge_width 0.5)
				(island_removal_mode 0)
			)
			(polygon
				(pts
					(arc
						(start 43.180254 -184.71007)
						(mid 39.819834 -184.71007)
						(end 43.180254 -184.71007)
					)
				)
			)
		)
		(zone
			(layers "F.Cu" "B.Cu" "In1.Cu" "In2.Cu" "In3.Cu" "In4.Cu" "In5.Cu" "In6.Cu")
			(hatch none 0.5)
			(connect_pads
				(clearance 0)
			)
			(min_thickness 0.25)
			(keepout
				(tracks not_allowed)
				(vias allowed)
				(pads allowed)
				(copperpour not_allowed)
				(footprints allowed)
			)
			(placement
				(enabled no)
				(sheetname "")
			)
			(fill
				(thermal_gap 0.5)
				(thermal_bridge_width 0.5)
				(island_removal_mode 0)
			)
			(polygon
				(pts
					(arc
						(start 96.524064 -186.06008)
						(mid 93.156024 -186.06008)
						(end 96.524064 -186.06008)
					)
				)
			)
		)
	)
	(footprint ""
		(layer "B.Cu")
		(at 96.468946 -345.12377)
		(property "Reference" "U6"
			(at 4.374134 -0.517906 0)
			(unlocked yes)
			(layer "B.SilkS")
			(effects
				(font
					(size 0.7874 0.5842)
					(thickness 0.1524)
				)
				(justify left mirror)
			)
		)
		(property "Value" ""
			(at 0 0 0)
			(layer "B.Fab")
			(effects
				(font
					(size 1.27 1.27)
				)
				(justify mirror)
			)
		)
		(duplicate_pad_numbers_are_jumpers no)
		(fp_line
			(start -2.5527 -2.0066)
			(end -2.5527 2.0066)
			(stroke
				(width 0.1524)
				(type default)
			)
			(layer "B.SilkS")
		)
		(fp_line
			(start -2.5527 2.0066)
			(end 2.5527 2.0066)
			(stroke
				(width 0.1524)
				(type default)
			)
			(layer "B.SilkS")
		)
		(fp_line
			(start 1.9812 0)
			(end 2.5527 -0.5715)
			(stroke
				(width 0.1524)
				(type default)
			)
			(layer "B.SilkS")
		)
		(fp_line
			(start 2.5527 -2.0066)
			(end -2.5527 -2.0066)
			(stroke
				(width 0.1524)
				(type default)
			)
			(layer "B.SilkS")
		)
		(fp_line
			(start 2.5527 -0.5715)
			(end 2.5527 -2.0066)
			(stroke
				(width 0.1524)
				(type default)
			)
			(layer "B.SilkS")
		)
		(fp_line
			(start 2.5527 0.5715)
			(end 1.9812 0)
			(stroke
				(width 0.1524)
				(type default)
			)
			(layer "B.SilkS")
		)
		(fp_line
			(start 2.5527 2.0066)
			(end 2.5527 0.5715)
			(stroke
				(width 0.1524)
				(type default)
			)
			(layer "B.SilkS")
		)
		(fp_circle
			(center 2.032 1.524)
			(end 2.286 1.524)
			(stroke
				(width 0.1524)
				(type default)
			)
			(fill no)
			(layer "B.SilkS")
		)
		(fp_rect
			(start 2.5527 3.6703)
			(end -2.5527 -3.6703)
			(stroke
				(width 0)
				(type default)
			)
			(fill no)
			(layer "B.CrtYd")
		)
		(fp_line
			(start -2.549906 -2.249932)
			(end -2.549906 2.249932)
			(stroke
				(width 0.1)
				(type default)
			)
			(layer "B.Fab")
		)
		(fp_line
			(start -2.549906 2.249932)
			(end 2.549906 2.249932)
			(stroke
				(width 0.1)
				(type default)
			)
			(layer "B.Fab")
		)
		(fp_line
			(start 2.549906 -2.249932)
			(end -2.549906 -2.249932)
			(stroke
				(width 0.1)
				(type default)
			)
			(layer "B.Fab")
		)
		(fp_line
			(start 2.549906 2.249932)
			(end 2.549906 -2.249932)
			(stroke
				(width 0.1)
				(type default)
			)
			(layer "B.Fab")
		)
		(pad "1" smd rect
			(at 1.949958 2.921 180)
			(size 0.3556 1.4986)
			(layers "B.Cu" "B.Mask" "B.Paste")
			(net "PSU_ALERT_N")
		)
		(pad "2" smd rect
			(at 1.299972 2.921 180)
			(size 0.3556 1.4986)
			(layers "B.Cu" "B.Mask" "B.Paste")
			(net "B13_PSU_ALERT_N")
		)
		(pad "3" smd rect
			(at 0.649986 2.921 180)
			(size 0.3556 1.4986)
			(layers "B.Cu" "B.Mask" "B.Paste")
			(net "PSU_ALERT_N")
		)
		(pad "4" smd rect
			(at 0 2.921 180)
			(size 0.3556 1.4986)
			(layers "B.Cu" "B.Mask" "B.Paste")
			(net "B14_PSU_ALERT_N")
		)
		(pad "5" smd rect
			(at -0.649986 2.921 180)
			(size 0.3556 1.4986)
			(layers "B.Cu" "B.Mask" "B.Paste")
			(net "PSU_ALERT_N")
		)
		(pad "6" smd rect
			(at -1.299972 2.921 180)
			(size 0.3556 1.4986)
			(layers "B.Cu" "B.Mask" "B.Paste")
			(net "B15_PSU_ALERT_N")
		)
		(pad "7" smd rect
			(at -1.949958 2.921 180)
			(size 0.3556 1.4986)
			(layers "B.Cu" "B.Mask" "B.Paste")
			(net "GND")
		)
		(pad "8" smd rect
			(at -1.949958 -2.921 180)
			(size 0.3556 1.4986)
			(layers "B.Cu" "B.Mask" "B.Paste")
			(net "B16_PSU_ALERT_N")
		)
		(pad "9" smd rect
			(at -1.299972 -2.921 180)
			(size 0.3556 1.4986)
			(layers "B.Cu" "B.Mask" "B.Paste")
			(net "PSU_ALERT_N")
		)
		(pad "10" smd rect
			(at -0.649986 -2.921 180)
			(size 0.3556 1.4986)
			(layers "B.Cu" "B.Mask" "B.Paste")
			(net "B17_PSU_ALERT_N")
		)
		(pad "11" smd rect
			(at 0 -2.921 180)
			(size 0.3556 1.4986)
			(layers "B.Cu" "B.Mask" "B.Paste")
			(net "PSU_ALERT_N")
		)
		(pad "12" smd rect
			(at 0.649986 -2.921 180)
			(size 0.3556 1.4986)
			(layers "B.Cu" "B.Mask" "B.Paste")
			(net "B18_PSU_ALERT_N")
		)
		(pad "13" smd rect
			(at 1.299972 -2.921 180)
			(size 0.3556 1.4986)
			(layers "B.Cu" "B.Mask" "B.Paste")
			(net "PSU_ALERT_N")
		)
		(pad "14" smd rect
			(at 1.949958 -2.921 180)
			(size 0.3556 1.4986)
			(layers "B.Cu" "B.Mask" "B.Paste")
			(net "P3V3_BUF")
		)
	)
	(footprint ""
		(layer "B.Cu")
		(at 44.03979 -8.26008 90)
		(property "Reference" "J7"
			(at 6.1214 -5.060442 0)
			(unlocked yes)
			(layer "B.SilkS")
			(effects
				(font
					(size 0.7874 0.5842)
					(thickness 0.1524)
				)
				(justify left mirror)
			)
		)
		(property "Value" ""
			(at 0 0 90)
			(layer "B.Fab")
			(effects
				(font
					(size 1.27 1.27)
				)
				(justify mirror)
			)
		)
		(duplicate_pad_numbers_are_jumpers no)
		(fp_line
			(start 5.275072 -13.910056)
			(end -7.975092 -13.910056)
			(stroke
				(width 0.1524)
				(type default)
			)
			(layer "F.SilkS")
		)
		(fp_line
			(start -7.975092 -13.910056)
			(end -7.975092 62.170056)
			(stroke
				(width 0.1524)
				(type default)
			)
			(layer "F.SilkS")
		)
		(fp_line
			(start 5.275072 62.170056)
			(end 5.275072 -13.910056)
			(stroke
				(width 0.1524)
				(type default)
			)
			(layer "F.SilkS")
		)
		(fp_line
			(start -7.975092 62.170056)
			(end 5.275072 62.170056)
			(stroke
				(width 0.1524)
				(type default)
			)
			(layer "F.SilkS")
		)
		(fp_line
			(start 5.275072 -13.910056)
			(end -7.975092 -13.910056)
			(stroke
				(width 0.1524)
				(type default)
			)
			(layer "B.SilkS")
		)
		(fp_line
			(start -7.975092 -13.910056)
			(end -7.975092 62.170056)
			(stroke
				(width 0.1524)
				(type default)
			)
			(layer "B.SilkS")
		)
		(fp_line
			(start 2.275078 -10.910062)
			(end 2.275078 59.170062)
			(stroke
				(width 0.1524)
				(type default)
			)
			(layer "B.SilkS")
		)
		(fp_line
			(start -4.975098 -10.910062)
			(end 2.275078 -10.910062)
			(stroke
				(width 0.1524)
				(type default)
			)
			(layer "B.SilkS")
		)
		(fp_line
			(start 2.275078 59.170062)
			(end -4.975098 59.170062)
			(stroke
				(width 0.1524)
				(type default)
			)
			(layer "B.SilkS")
		)
		(fp_line
			(start -4.975098 59.170062)
			(end -4.975098 -10.910062)
			(stroke
				(width 0.1524)
				(type default)
			)
			(layer "B.SilkS")
		)
		(fp_line
			(start 5.275072 62.170056)
			(end 5.275072 -13.910056)
			(stroke
				(width 0.1524)
				(type default)
			)
			(layer "B.SilkS")
		)
		(fp_line
			(start -7.975092 62.170056)
			(end 5.275072 62.170056)
			(stroke
				(width 0.1524)
				(type default)
			)
			(layer "B.SilkS")
		)
		(fp_poly
			(pts
				(xy 4.103878 -0.759206) (xy 4.103878 0.764794) (xy 2.579878 0.002794)
			)
			(stroke
				(width 0)
				(type default)
			)
			(fill yes)
			(layer "B.SilkS")
		)
		(fp_poly
			(pts
				(xy 2.275078 -10.910062) (xy 2.275078 59.170062) (xy -4.975098 59.170062) (xy -4.975098 -10.910062)
			)
			(stroke
				(width 0)
				(type default)
			)
			(fill no)
			(layer "B.CrtYd")
		)
		(fp_poly
			(pts
				(xy 1.1938 40.9702) (xy 1.1938 48.6156) (xy -3.9116 48.6156) (xy -3.9116 40.9702) (xy -3.9116 40.9448)
				(xy 1.1938 40.9448)
			)
			(stroke
				(width 0)
				(type default)
			)
			(fill no)
			(layer "F.CrtYd")
		)
		(fp_poly
			(pts
				(xy -3.3274 -0.6604) (xy 0.635 -0.6604) (xy 0.635 38.735) (xy 0.635 38.7604) (xy -3.3274 38.7604)
				(xy -3.3528 38.7604) (xy -3.3528 -0.6604)
			)
			(stroke
				(width 0)
				(type default)
			)
			(fill no)
			(layer "F.CrtYd")
		)
		(fp_poly
			(pts
				(arc
					(start -1.35001 -1.01219)
					(mid -1.35001 -4.06781)
					(end -1.35001 -1.01219)
				)
			)
			(stroke
				(width 0)
				(type default)
			)
			(fill no)
			(layer "F.CrtYd")
		)
		(fp_poly
			(pts
				(arc
					(start 0 52.33162)
					(mid 0 49.26838)
					(end 0 52.33162)
				)
			)
			(stroke
				(width 0)
				(type default)
			)
			(fill no)
			(layer "F.CrtYd")
		)
		(fp_line
			(start 2.275078 -10.910062)
			(end 2.275078 59.170062)
			(stroke
				(width 0.1)
				(type default)
			)
			(layer "B.Fab")
		)
		(fp_line
			(start -4.975098 -10.910062)
			(end 2.275078 -10.910062)
			(stroke
				(width 0.1)
				(type default)
			)
			(layer "B.Fab")
		)
		(fp_line
			(start 2.275078 59.170062)
			(end -4.975098 59.170062)
			(stroke
				(width 0.1)
				(type default)
			)
			(layer "B.Fab")
		)
		(fp_line
			(start -4.975098 59.170062)
			(end -4.975098 -10.910062)
			(stroke
				(width 0.1)
				(type default)
			)
			(layer "B.Fab")
		)
		(fp_poly
			(pts
				(xy 4.103878 -0.759206) (xy 4.103878 0.764794) (xy 2.579878 0.002794)
			)
			(stroke
				(width 0)
				(type default)
			)
			(fill yes)
			(layer "B.Fab")
		)
		(fp_line
			(start 5.275072 -13.910056)
			(end -7.975092 -13.910056)
			(stroke
				(width 0.1)
				(type default)
			)
			(layer "F.Fab")
		)
		(fp_line
			(start -7.975092 -13.910056)
			(end -7.975092 62.170056)
			(stroke
				(width 0.1)
				(type default)
			)
			(layer "F.Fab")
		)
		(fp_line
			(start 5.275072 62.170056)
			(end 5.275072 -13.910056)
			(stroke
				(width 0.1)
				(type default)
			)
			(layer "F.Fab")
		)
		(fp_line
			(start -7.975092 62.170056)
			(end 5.275072 62.170056)
			(stroke
				(width 0.1)
				(type default)
			)
			(layer "F.Fab")
		)
		(fp_text user "P32"
			(at -4.37134 0.049784 0)
			(unlocked yes)
			(layer "F.SilkS")
			(effects
				(font
					(size 0.7874 0.5842)
					(thickness 0.1524)
				)
			)
		)
		(fp_text user "P1"
			(at 6.256782 0.402844 0)
			(unlocked yes)
			(layer "F.SilkS")
			(effects
				(font
					(size 0.7874 0.5842)
					(thickness 0.1524)
				)
			)
		)
		(fp_text user "PRESS-FIT"
			(at 6.390386 8.707882 0)
			(unlocked yes)
			(layer "F.SilkS")
			(effects
				(font
					(size 0.7874 0.5842)
					(thickness 0.1524)
				)
				(justify left)
			)
		)
		(fp_text user "P17"
			(at -4.280408 37.907468 0)
			(unlocked yes)
			(layer "F.SilkS")
			(effects
				(font
					(size 0.7874 0.5842)
					(thickness 0.1524)
				)
			)
		)
		(fp_text user "P16"
			(at 1.418082 37.950648 0)
			(unlocked yes)
			(layer "F.SilkS")
			(effects
				(font
					(size 0.7874 0.5842)
					(thickness 0.1524)
				)
			)
		)
		(fp_text user "S12"
			(at -4.454652 41.239948 0)
			(unlocked yes)
			(layer "F.SilkS")
			(effects
				(font
					(size 0.7874 0.5842)
					(thickness 0.1524)
				)
			)
		)
		(fp_text user "S1"
			(at 2.060448 41.620948 0)
			(unlocked yes)
			(layer "F.SilkS")
			(effects
				(font
					(size 0.7874 0.5842)
					(thickness 0.1524)
				)
			)
		)
		(fp_text user "S6"
			(at 1.65481 47.888652 0)
			(unlocked yes)
			(layer "F.SilkS")
			(effects
				(font
					(size 0.7874 0.5842)
					(thickness 0.1524)
				)
			)
		)
		(fp_text user "S7"
			(at -4.79933 47.88916 0)
			(unlocked yes)
			(layer "F.SilkS")
			(effects
				(font
					(size 0.7874 0.5842)
					(thickness 0.1524)
				)
			)
		)
		(fp_text user "P1"
			(at 2.955798 -1.463548 0)
			(unlocked yes)
			(layer "B.SilkS")
			(effects
				(font
					(size 0.7874 0.5842)
					(thickness 0.1524)
				)
				(justify mirror)
			)
		)
		(fp_text user "P32"
			(at -5.896356 -0.299212 0)
			(unlocked yes)
			(layer "B.SilkS")
			(effects
				(font
					(size 0.7874 0.5842)
					(thickness 0.1524)
				)
				(justify mirror)
			)
		)
		(fp_text user "PRESS-FIT"
			(at -6.81482 32.505396 0)
			(unlocked yes)
			(layer "B.SilkS")
			(effects
				(font
					(size 0.7874 0.5842)
					(thickness 0.1524)
				)
				(justify left mirror)
			)
		)
		(fp_text user "P17"
			(at -5.854192 38.026086 0)
			(unlocked yes)
			(layer "B.SilkS")
			(effects
				(font
					(size 0.7874 0.5842)
					(thickness 0.1524)
				)
				(justify mirror)
			)
		)
		(fp_text user "P16"
			(at 2.939034 38.436296 0)
			(unlocked yes)
			(layer "B.SilkS")
			(effects
				(font
					(size 0.7874 0.5842)
					(thickness 0.1524)
				)
				(justify mirror)
			)
		)
		(fp_text user "S1"
			(at 2.933954 41.936416 0)
			(unlocked yes)
			(layer "B.SilkS")
			(effects
				(font
					(size 0.7874 0.5842)
					(thickness 0.1524)
				)
				(justify mirror)
			)
		)
		(fp_text user "S12"
			(at -5.84962 42.442892 0)
			(unlocked yes)
			(layer "B.SilkS")
			(effects
				(font
					(size 0.7874 0.5842)
					(thickness 0.1524)
				)
				(justify mirror)
			)
		)
		(fp_text user "S6"
			(at 2.930398 47.701708 0)
			(unlocked yes)
			(layer "B.SilkS")
			(effects
				(font
					(size 0.7874 0.5842)
					(thickness 0.1524)
				)
				(justify mirror)
			)
		)
		(fp_text user "S7"
			(at -5.930392 48.382682 0)
			(unlocked yes)
			(layer "B.SilkS")
			(effects
				(font
					(size 0.7874 0.5842)
					(thickness 0.1524)
				)
				(justify mirror)
			)
		)
		(fp_text user "P1"
			(at 3.108452 -1.27 180)
			(unlocked yes)
			(layer "B.Fab")
			(effects
				(font
					(size 0.7874 0.5842)
					(thickness 0.000001)
				)
				(justify mirror)
			)
		)
		(fp_text user "P32"
			(at -5.781548 -0.0508 180)
			(unlocked yes)
			(layer "B.Fab")
			(effects
				(font
					(size 0.7874 0.5842)
					(thickness 0.000001)
				)
				(justify mirror)
			)
		)
		(fp_text user "PRESS-FIT"
			(at -6.82371 29.8831 0)
			(unlocked yes)
			(layer "B.Fab")
			(effects
				(font
					(size 1.6002 1.1938)
					(thickness 0.000001)
				)
				(justify left mirror)
			)
		)
		(fp_text user "P17"
			(at -5.72135 38.0746 180)
			(unlocked yes)
			(layer "B.Fab")
			(effects
				(font
					(size 0.7874 0.5842)
					(thickness 0.000001)
				)
				(justify mirror)
			)
		)
		(fp_text user "P16"
			(at 3.159252 38.3794 180)
			(unlocked yes)
			(layer "B.Fab")
			(effects
				(font
					(size 0.7874 0.5842)
					(thickness 0.000001)
				)
				(justify mirror)
			)
		)
		(fp_text user "S12"
			(at -5.79374 41.42232 180)
			(unlocked yes)
			(layer "B.Fab")
			(effects
				(font
					(size 0.7874 0.5842)
					(thickness 0.000001)
				)
				(justify mirror)
			)
		)
		(fp_text user "S1"
			(at 3.09626 41.656 180)
			(unlocked yes)
			(layer "B.Fab")
			(effects
				(font
					(size 0.7874 0.5842)
					(thickness 0.000001)
				)
				(justify mirror)
			)
		)
		(fp_text user "S6"
			(at 3.133852 48.0822 180)
			(unlocked yes)
			(layer "B.Fab")
			(effects
				(font
					(size 0.7874 0.5842)
					(thickness 0.000001)
				)
				(justify mirror)
			)
		)
		(fp_text user "S7"
			(at -5.781548 48.0822 180)
			(unlocked yes)
			(layer "B.Fab")
			(effects
				(font
					(size 0.7874 0.5842)
					(thickness 0.000001)
				)
				(justify mirror)
			)
		)
		(fp_text user "P32"
			(at -4.071112 -0.0762 180)
			(unlocked yes)
			(layer "F.Fab")
			(effects
				(font
					(size 0.7874 0.5842)
					(thickness 0.000001)
				)
			)
		)
		(fp_text user "P1"
			(at 1.516888 0 180)
			(unlocked yes)
			(layer "F.Fab")
			(effects
				(font
					(size 0.7874 0.5842)
					(thickness 0.000001)
				)
			)
		)
		(fp_text user "PRESS-FIT"
			(at -6.762496 16.251428 0)
			(unlocked yes)
			(layer "F.Fab")
			(effects
				(font
					(size 1.6002 1.1938)
					(thickness 0.000001)
				)
				(justify left)
			)
		)
		(fp_text user "P17"
			(at -4.366768 38.227 180)
			(unlocked yes)
			(layer "F.Fab")
			(effects
				(font
					(size 0.7874 0.5842)
					(thickness 0.000001)
				)
			)
		)
		(fp_text user "P16"
			(at 2.228088 38.354 180)
			(unlocked yes)
			(layer "F.Fab")
			(effects
				(font
					(size 0.7874 0.5842)
					(thickness 0.000001)
				)
			)
		)
		(fp_text user "S12"
			(at -4.362958 41.09212 180)
			(unlocked yes)
			(layer "F.Fab")
			(effects
				(font
					(size 0.7874 0.5842)
					(thickness 0.000001)
				)
			)
		)
		(fp_text user "S1"
			(at 2.164842 41.6306 180)
			(unlocked yes)
			(layer "F.Fab")
			(effects
				(font
					(size 0.7874 0.5842)
					(thickness 0.000001)
				)
			)
		)
		(fp_text user "S6"
			(at 1.923288 48.133 180)
			(unlocked yes)
			(layer "F.Fab")
			(effects
				(font
					(size 0.7874 0.5842)
					(thickness 0.000001)
				)
			)
		)
		(fp_text user "S7"
			(at -4.426712 48.2346 180)
			(unlocked yes)
			(layer "F.Fab")
			(effects
				(font
					(size 0.7874 0.5842)
					(thickness 0.000001)
				)
			)
		)
		(pad "" np_thru_hole circle
			(at -1.35001 -2.54)
			(size 2.5146 2.5146)
			(drill 2.5146)
			(layers "*.Cu" "*.Mask")
			(clearance 0.381)
			(thermal_gap 0.381)
		)
		(pad "" np_thru_hole circle
			(at 0 50.8)
			(size 2.5146 2.5146)
			(drill 2.5146)
			(layers "*.Cu" "*.Mask")
			(clearance 0.381)
			(thermal_gap 0.381)
		)
		(pad "P1" thru_hole rect
			(at 0 0)
			(size 1.1684 1.1684)
			(drill 0.762)
			(layers "*.Cu" "*.Mask")
			(remove_unused_layers no)
			(net "GND")
			(clearance 0.0508)
			(padstack
				(mode front_inner_back)
				(layer "Inner"
					(shape circle)
					(size 1.1684 1.1684)
					(clearance 0.0508)
				)
				(layer "B.Cu"
					(shape rect)
					(size 1.1684 1.1684)
					(thermal_gap 0.0508)
					(clearance 0.0508)
				)
			)
		)
		(pad "P2" thru_hole circle
			(at 0 2.54)
			(size 1.1684 1.1684)
			(drill 0.762)
			(layers "*.Cu" "*.Mask")
			(remove_unused_layers no)
			(net "GND")
			(clearance 0.0508)
			(thermal_gap 0.0508)
		)
		(pad "P3" thru_hole circle
			(at 0 5.08)
			(size 1.1684 1.1684)
			(drill 0.762)
			(layers "*.Cu" "*.Mask")
			(remove_unused_layers no)
			(net "GND")
			(clearance 0.0508)
			(thermal_gap 0.0508)
		)
		(pad "P4" thru_hole circle
			(at 0 7.62)
			(size 1.1684 1.1684)
			(drill 0.762)
			(layers "*.Cu" "*.Mask")
			(remove_unused_layers no)
			(net "GND")
			(clearance 0.0508)
			(thermal_gap 0.0508)
		)
		(pad "P5" thru_hole circle
			(at 0 10.16)
			(size 1.1684 1.1684)
			(drill 0.762)
			(layers "*.Cu" "*.Mask")
			(remove_unused_layers no)
			(net "GND")
			(clearance 0.0508)
			(thermal_gap 0.0508)
		)
		(pad "P6" thru_hole circle
			(at 0 12.7)
			(size 1.1684 1.1684)
			(drill 0.762)
			(layers "*.Cu" "*.Mask")
			(remove_unused_layers no)
			(net "GND")
			(clearance 0.0508)
			(thermal_gap 0.0508)
		)
		(pad "P7" thru_hole circle
			(at 0 15.24)
			(size 1.1684 1.1684)
			(drill 0.762)
			(layers "*.Cu" "*.Mask")
			(remove_unused_layers no)
			(net "GND")
			(clearance 0.0508)
			(thermal_gap 0.0508)
		)
		(pad "P8" thru_hole circle
			(at 0 17.78)
			(size 1.1684 1.1684)
			(drill 0.762)
			(layers "*.Cu" "*.Mask")
			(remove_unused_layers no)
			(net "GND")
			(clearance 0.0508)
			(thermal_gap 0.0508)
		)
		(pad "P9" thru_hole circle
			(at 0 20.32)
			(size 1.1684 1.1684)
			(drill 0.762)
			(layers "*.Cu" "*.Mask")
			(remove_unused_layers no)
			(net "P12V")
			(clearance 0.0508)
			(thermal_gap 0.0508)
		)
		(pad "P10" thru_hole circle
			(at 0 22.86)
			(size 1.1684 1.1684)
			(drill 0.762)
			(layers "*.Cu" "*.Mask")
			(remove_unused_layers no)
			(net "P12V")
			(clearance 0.0508)
			(thermal_gap 0.0508)
		)
		(pad "P11" thru_hole circle
			(at 0 25.4)
			(size 1.1684 1.1684)
			(drill 0.762)
			(layers "*.Cu" "*.Mask")
			(remove_unused_layers no)
			(net "P12V")
			(clearance 0.0508)
			(thermal_gap 0.0508)
		)
		(pad "P12" thru_hole circle
			(at 0 27.94)
			(size 1.1684 1.1684)
			(drill 0.762)
			(layers "*.Cu" "*.Mask")
			(remove_unused_layers no)
			(net "P12V")
			(clearance 0.0508)
			(thermal_gap 0.0508)
		)
		(pad "P13" thru_hole circle
			(at 0 30.48)
			(size 1.1684 1.1684)
			(drill 0.762)
			(layers "*.Cu" "*.Mask")
			(remove_unused_layers no)
			(net "P12V")
			(clearance 0.0508)
			(thermal_gap 0.0508)
		)
		(pad "P14" thru_hole circle
			(at 0 33.02)
			(size 1.1684 1.1684)
			(drill 0.762)
			(layers "*.Cu" "*.Mask")
			(remove_unused_layers no)
			(net "P12V")
			(clearance 0.0508)
			(thermal_gap 0.0508)
		)
		(pad "P15" thru_hole circle
			(at 0 35.56)
			(size 1.1684 1.1684)
			(drill 0.762)
			(layers "*.Cu" "*.Mask")
			(remove_unused_layers no)
			(net "P12V")
			(clearance 0.0508)
			(thermal_gap 0.0508)
		)
		(pad "P16" thru_hole circle
			(at 0 38.1)
			(size 1.1684 1.1684)
			(drill 0.762)
			(layers "*.Cu" "*.Mask")
			(remove_unused_layers no)
			(net "P12V")
			(clearance 0.0508)
			(thermal_gap 0.0508)
		)
		(pad "P17" thru_hole circle
			(at -2.70002 38.1)
			(size 1.1684 1.1684)
			(drill 0.762)
			(layers "*.Cu" "*.Mask")
			(remove_unused_layers no)
			(net "P12V")
			(clearance 0.0508)
			(thermal_gap 0.0508)
		)
		(pad "P18" thru_hole circle
			(at -2.70002 35.56)
			(size 1.1684 1.1684)
			(drill 0.762)
			(layers "*.Cu" "*.Mask")
			(remove_unused_layers no)
			(net "P12V")
			(clearance 0.0508)
			(thermal_gap 0.0508)
		)
		(pad "P19" thru_hole circle
			(at -2.70002 33.02)
			(size 1.1684 1.1684)
			(drill 0.762)
			(layers "*.Cu" "*.Mask")
			(remove_unused_layers no)
			(net "P12V")
			(clearance 0.0508)
			(thermal_gap 0.0508)
		)
		(pad "P20" thru_hole circle
			(at -2.70002 30.48)
			(size 1.1684 1.1684)
			(drill 0.762)
			(layers "*.Cu" "*.Mask")
			(remove_unused_layers no)
			(net "P12V")
			(clearance 0.0508)
			(thermal_gap 0.0508)
		)
		(pad "P21" thru_hole circle
			(at -2.70002 27.94)
			(size 1.1684 1.1684)
			(drill 0.762)
			(layers "*.Cu" "*.Mask")
			(remove_unused_layers no)
			(net "P12V")
			(clearance 0.0508)
			(thermal_gap 0.0508)
		)
		(pad "P22" thru_hole circle
			(at -2.70002 25.4)
			(size 1.1684 1.1684)
			(drill 0.762)
			(layers "*.Cu" "*.Mask")
			(remove_unused_layers no)
			(net "P12V")
			(clearance 0.0508)
			(thermal_gap 0.0508)
		)
		(pad "P23" thru_hole circle
			(at -2.70002 22.86)
			(size 1.1684 1.1684)
			(drill 0.762)
			(layers "*.Cu" "*.Mask")
			(remove_unused_layers no)
			(net "P12V")
			(clearance 0.0508)
			(thermal_gap 0.0508)
		)
		(pad "P24" thru_hole circle
			(at -2.70002 20.32)
			(size 1.1684 1.1684)
			(drill 0.762)
			(layers "*.Cu" "*.Mask")
			(remove_unused_layers no)
			(net "P12V")
			(clearance 0.0508)
			(thermal_gap 0.0508)
		)
		(pad "P25" thru_hole circle
			(at -2.70002 17.78)
			(size 1.1684 1.1684)
			(drill 0.762)
			(layers "*.Cu" "*.Mask")
			(remove_unused_layers no)
			(net "GND")
			(clearance 0.0508)
			(thermal_gap 0.0508)
		)
		(pad "P26" thru_hole circle
			(at -2.70002 15.24)
			(size 1.1684 1.1684)
			(drill 0.762)
			(layers "*.Cu" "*.Mask")
			(remove_unused_layers no)
			(net "GND")
			(clearance 0.0508)
			(thermal_gap 0.0508)
		)
		(pad "P27" thru_hole circle
			(at -2.70002 12.7)
			(size 1.1684 1.1684)
			(drill 0.762)
			(layers "*.Cu" "*.Mask")
			(remove_unused_layers no)
			(net "GND")
			(clearance 0.0508)
			(thermal_gap 0.0508)
		)
		(pad "P28" thru_hole circle
			(at -2.70002 10.16)
			(size 1.1684 1.1684)
			(drill 0.762)
			(layers "*.Cu" "*.Mask")
			(remove_unused_layers no)
			(net "GND")
			(clearance 0.0508)
			(thermal_gap 0.0508)
		)
		(pad "P29" thru_hole circle
			(at -2.70002 7.62)
			(size 1.1684 1.1684)
			(drill 0.762)
			(layers "*.Cu" "*.Mask")
			(remove_unused_layers no)
			(net "GND")
			(clearance 0.0508)
			(thermal_gap 0.0508)
		)
		(pad "P30" thru_hole circle
			(at -2.70002 5.08)
			(size 1.1684 1.1684)
			(drill 0.762)
			(layers "*.Cu" "*.Mask")
			(remove_unused_layers no)
			(net "GND")
			(clearance 0.0508)
			(thermal_gap 0.0508)
		)
		(pad "P31" thru_hole circle
			(at -2.70002 2.54)
			(size 1.1684 1.1684)
			(drill 0.762)
			(layers "*.Cu" "*.Mask")
			(remove_unused_layers no)
			(net "GND")
			(clearance 0.0508)
			(thermal_gap 0.0508)
		)
		(pad "P32" thru_hole circle
			(at -2.70002 0)
			(size 1.1684 1.1684)
			(drill 0.762)
			(layers "*.Cu" "*.Mask")
			(remove_unused_layers no)
			(net "GND")
			(clearance 0.0508)
			(thermal_gap 0.0508)
		)
		(pad "S1" thru_hole circle
			(at 0.55499 41.60012)
			(size 1.1684 1.1684)
			(drill 0.762)
			(layers "*.Cu" "*.Mask")
			(remove_unused_layers no)
			(net "T1_BLAD1_TXD")
			(clearance 0.0508)
			(thermal_gap 0.0508)
		)
		(pad "S2" thru_hole circle
			(at -0.71501 42.87012)
			(size 1.1684 1.1684)
			(drill 0.762)
			(layers "*.Cu" "*.Mask")
			(remove_unused_layers no)
			(net "T1_BLAD1_RXD")
			(clearance 0.0508)
			(thermal_gap 0.0508)
		)
		(pad "S3" thru_hole circle
			(at 0.55499 44.14012)
			(size 1.1684 1.1684)
			(drill 0.762)
			(layers "*.Cu" "*.Mask")
			(remove_unused_layers no)
			(net "T1_BLAD1_EN")
			(clearance 0.0508)
			(thermal_gap 0.0508)
		)
		(pad "S4" thru_hole circle
			(at -0.71501 45.41012)
			(size 1.1684 1.1684)
			(drill 0.762)
			(layers "*.Cu" "*.Mask")
			(remove_unused_layers no)
			(net "B1_PSU_ALERT_N")
			(clearance 0.0508)
			(thermal_gap 0.0508)
		)
		(pad "S5" thru_hole circle
			(at 0.55499 46.68012)
			(size 1.1684 1.1684)
			(drill 0.762)
			(layers "*.Cu" "*.Mask")
			(remove_unused_layers no)
			(net "T1_BLAD2_TXD")
			(clearance 0.0508)
			(thermal_gap 0.0508)
		)
		(pad "S6" thru_hole circle
			(at -0.71501 47.95012)
			(size 1.1684 1.1684)
			(drill 0.762)
			(layers "*.Cu" "*.Mask")
			(remove_unused_layers no)
			(net "T1_BLAD2_RXD")
			(clearance 0.0508)
			(thermal_gap 0.0508)
		)
		(pad "S7" thru_hole circle
			(at -3.25501 47.95012)
			(size 1.1684 1.1684)
			(drill 0.762)
			(layers "*.Cu" "*.Mask")
			(remove_unused_layers no)
			(net "T1_BLAD4_RXD")
			(clearance 0.0508)
			(thermal_gap 0.0508)
		)
		(pad "S8" thru_hole circle
			(at -1.98501 46.68012)
			(size 1.1684 1.1684)
			(drill 0.762)
			(layers "*.Cu" "*.Mask")
			(remove_unused_layers no)
			(net "T1_BLAD4_TXD")
			(clearance 0.0508)
			(thermal_gap 0.0508)
		)
		(pad "S9" thru_hole circle
			(at -3.25501 45.41012)
			(size 1.1684 1.1684)
			(drill 0.762)
			(layers "*.Cu" "*.Mask")
			(remove_unused_layers no)
			(net "B2_PSU_ALERT_N")
			(clearance 0.0508)
			(thermal_gap 0.0508)
		)
		(pad "S10" thru_hole circle
			(at -1.98501 44.14012)
			(size 1.1684 1.1684)
			(drill 0.762)
			(layers "*.Cu" "*.Mask")
			(remove_unused_layers no)
			(net "T1_BLAD3_EN")
			(clearance 0.0508)
			(thermal_gap 0.0508)
		)
		(pad "S11" thru_hole circle
			(at -3.25501 42.87012)
			(size 1.1684 1.1684)
			(drill 0.762)
			(layers "*.Cu" "*.Mask")
			(remove_unused_layers no)
			(net "T1_BLAD3_RXD")
			(clearance 0.0508)
			(thermal_gap 0.0508)
		)
		(pad "S12" thru_hole circle
			(at -1.98501 41.60012)
			(size 1.1684 1.1684)
			(drill 0.762)
			(layers "*.Cu" "*.Mask")
			(remove_unused_layers no)
			(net "T1_BLAD3_TXD")
			(clearance 0.0508)
			(thermal_gap 0.0508)
		)
		(zone
			(layer "F.Cu")
			(hatch none 0.5)
			(connect_pads
				(clearance 0)
			)
			(min_thickness 0.25)
			(keepout
				(tracks allowed)
				(vias not_allowed)
				(pads allowed)
				(copperpour not_allowed)
				(footprints allowed)
			)
			(placement
				(enabled no)
				(sheetname "")
			)
			(fill
				(thermal_gap 0.5)
				(thermal_bridge_width 0.5)
				(island_removal_mode 0)
			)
			(polygon
				(pts
					(xy 85.00999 -9.45388) (xy 92.65539 -9.45388) (xy 92.65539 -4.34848) (xy 85.00999 -4.34848) (xy 84.98459 -4.34848)
					(xy 84.98459 -9.45388)
				)
			)
		)
		(zone
			(layer "F.Cu")
			(hatch none 0.5)
			(connect_pads
				(clearance 0)
			)
			(min_thickness 0.25)
			(keepout
				(tracks allowed)
				(vias not_allowed)
				(pads allowed)
				(copperpour not_allowed)
				(footprints allowed)
			)
			(placement
				(enabled no)
				(sheetname "")
			)
			(fill
				(thermal_gap 0.5)
				(thermal_bridge_width 0.5)
				(island_removal_mode 0)
			)
			(polygon
				(pts
					(xy 43.37939 -4.93268) (xy 43.37939 -8.89508) (xy 82.77479 -8.89508) (xy 82.80019 -8.89508) (xy 82.80019 -4.93268)
					(xy 82.80019 -4.90728) (xy 43.37939 -4.90728)
				)
			)
		)
		(zone
			(layers "F.Cu" "B.Cu" "In1.Cu" "In2.Cu" "In3.Cu" "In4.Cu" "In5.Cu" "In6.Cu")
			(hatch none 0.5)
			(connect_pads
				(clearance 0)
			)
			(min_thickness 0.25)
			(keepout
				(tracks not_allowed)
				(vias allowed)
				(pads allowed)
				(copperpour not_allowed)
				(footprints allowed)
			)
			(placement
				(enabled no)
				(sheetname "")
			)
			(fill
				(thermal_gap 0.5)
				(thermal_bridge_width 0.5)
				(island_removal_mode 0)
			)
			(polygon
				(pts
					(arc
						(start 43.18 -6.91007)
						(mid 39.81958 -6.91007)
						(end 43.18 -6.91007)
					)
				)
			)
		)
		(zone
			(layers "F.Cu" "B.Cu" "In1.Cu" "In2.Cu" "In3.Cu" "In4.Cu" "In5.Cu" "In6.Cu")
			(hatch none 0.5)
			(connect_pads
				(clearance 0)
			)
			(min_thickness 0.25)
			(keepout
				(tracks not_allowed)
				(vias allowed)
				(pads allowed)
				(copperpour not_allowed)
				(footprints allowed)
			)
			(placement
				(enabled no)
				(sheetname "")
			)
			(fill
				(thermal_gap 0.5)
				(thermal_bridge_width 0.5)
				(island_removal_mode 0)
			)
			(polygon
				(pts
					(arc
						(start 96.52381 -8.26008)
						(mid 93.15577 -8.26008)
						(end 96.52381 -8.26008)
					)
				)
			)
		)
	)
	(footprint ""
		(layer "B.Cu")
		(at 44.03979 -97.16008 90)
		(property "Reference" "J9"
			(at 6.238748 -5.04063 0)
			(unlocked yes)
			(layer "B.SilkS")
			(effects
				(font
					(size 0.7874 0.5842)
					(thickness 0.1524)
				)
				(justify left mirror)
			)
		)
		(property "Value" ""
			(at 0 0 90)
			(layer "B.Fab")
			(effects
				(font
					(size 1.27 1.27)
				)
				(justify mirror)
			)
		)
		(duplicate_pad_numbers_are_jumpers no)
		(fp_line
			(start 5.275072 -13.910056)
			(end -7.975092 -13.910056)
			(stroke
				(width 0.1524)
				(type default)
			)
			(layer "F.SilkS")
		)
		(fp_line
			(start -7.975092 -13.910056)
			(end -7.975092 62.170056)
			(stroke
				(width 0.1524)
				(type default)
			)
			(layer "F.SilkS")
		)
		(fp_line
			(start 5.275072 62.170056)
			(end 5.275072 -13.910056)
			(stroke
				(width 0.1524)
				(type default)
			)
			(layer "F.SilkS")
		)
		(fp_line
			(start -7.975092 62.170056)
			(end 5.275072 62.170056)
			(stroke
				(width 0.1524)
				(type default)
			)
			(layer "F.SilkS")
		)
		(fp_line
			(start 5.275072 -13.910056)
			(end -7.975092 -13.910056)
			(stroke
				(width 0.1524)
				(type default)
			)
			(layer "B.SilkS")
		)
		(fp_line
			(start -7.975092 -13.910056)
			(end -7.975092 62.170056)
			(stroke
				(width 0.1524)
				(type default)
			)
			(layer "B.SilkS")
		)
		(fp_line
			(start 2.275078 -10.910062)
			(end 2.275078 59.170062)
			(stroke
				(width 0.1524)
				(type default)
			)
			(layer "B.SilkS")
		)
		(fp_line
			(start -4.975098 -10.910062)
			(end 2.275078 -10.910062)
			(stroke
				(width 0.1524)
				(type default)
			)
			(layer "B.SilkS")
		)
		(fp_line
			(start 2.275078 59.170062)
			(end -4.975098 59.170062)
			(stroke
				(width 0.1524)
				(type default)
			)
			(layer "B.SilkS")
		)
		(fp_line
			(start -4.975098 59.170062)
			(end -4.975098 -10.910062)
			(stroke
				(width 0.1524)
				(type default)
			)
			(layer "B.SilkS")
		)
		(fp_line
			(start 5.275072 62.170056)
			(end 5.275072 -13.910056)
			(stroke
				(width 0.1524)
				(type default)
			)
			(layer "B.SilkS")
		)
		(fp_line
			(start -7.975092 62.170056)
			(end 5.275072 62.170056)
			(stroke
				(width 0.1524)
				(type default)
			)
			(layer "B.SilkS")
		)
		(fp_poly
			(pts
				(xy 4.103878 -0.759206) (xy 4.103878 0.764794) (xy 2.579878 0.002794)
			)
			(stroke
				(width 0)
				(type default)
			)
			(fill yes)
			(layer "B.SilkS")
		)
		(fp_poly
			(pts
				(xy 2.275078 -10.910062) (xy 2.275078 59.170062) (xy -4.975098 59.170062) (xy -4.975098 -10.910062)
			)
			(stroke
				(width 0)
				(type default)
			)
			(fill no)
			(layer "B.CrtYd")
		)
		(fp_poly
			(pts
				(xy 1.1938 40.9702) (xy 1.1938 48.6156) (xy -3.9116 48.6156) (xy -3.9116 40.9702) (xy -3.9116 40.9448)
				(xy 1.1938 40.9448)
			)
			(stroke
				(width 0)
				(type default)
			)
			(fill no)
			(layer "F.CrtYd")
		)
		(fp_poly
			(pts
				(xy -3.3274 -0.6604) (xy 0.635 -0.6604) (xy 0.635 38.735) (xy 0.635 38.7604) (xy -3.3274 38.7604)
				(xy -3.3528 38.7604) (xy -3.3528 -0.6604)
			)
			(stroke
				(width 0)
				(type default)
			)
			(fill no)
			(layer "F.CrtYd")
		)
		(fp_poly
			(pts
				(arc
					(start -1.35001 -1.01219)
					(mid -1.35001 -4.06781)
					(end -1.35001 -1.01219)
				)
			)
			(stroke
				(width 0)
				(type default)
			)
			(fill no)
			(layer "F.CrtYd")
		)
		(fp_poly
			(pts
				(arc
					(start 0 52.33162)
					(mid 0 49.26838)
					(end 0 52.33162)
				)
			)
			(stroke
				(width 0)
				(type default)
			)
			(fill no)
			(layer "F.CrtYd")
		)
		(fp_line
			(start 2.275078 -10.910062)
			(end 2.275078 59.170062)
			(stroke
				(width 0.1)
				(type default)
			)
			(layer "B.Fab")
		)
		(fp_line
			(start -4.975098 -10.910062)
			(end 2.275078 -10.910062)
			(stroke
				(width 0.1)
				(type default)
			)
			(layer "B.Fab")
		)
		(fp_line
			(start 2.275078 59.170062)
			(end -4.975098 59.170062)
			(stroke
				(width 0.1)
				(type default)
			)
			(layer "B.Fab")
		)
		(fp_line
			(start -4.975098 59.170062)
			(end -4.975098 -10.910062)
			(stroke
				(width 0.1)
				(type default)
			)
			(layer "B.Fab")
		)
		(fp_poly
			(pts
				(xy 4.103878 -0.759206) (xy 4.103878 0.764794) (xy 2.579878 0.002794)
			)
			(stroke
				(width 0)
				(type default)
			)
			(fill yes)
			(layer "B.Fab")
		)
		(fp_line
			(start 5.275072 -13.910056)
			(end -7.975092 -13.910056)
			(stroke
				(width 0.1)
				(type default)
			)
			(layer "F.Fab")
		)
		(fp_line
			(start -7.975092 -13.910056)
			(end -7.975092 62.170056)
			(stroke
				(width 0.1)
				(type default)
			)
			(layer "F.Fab")
		)
		(fp_line
			(start 5.275072 62.170056)
			(end 5.275072 -13.910056)
			(stroke
				(width 0.1)
				(type default)
			)
			(layer "F.Fab")
		)
		(fp_line
			(start -7.975092 62.170056)
			(end 5.275072 62.170056)
			(stroke
				(width 0.1)
				(type default)
			)
			(layer "F.Fab")
		)
		(fp_text user "P32"
			(at -8.987536 -0.131826 0)
			(unlocked yes)
			(layer "F.SilkS")
			(effects
				(font
					(size 0.7874 0.5842)
					(thickness 0.1524)
				)
			)
		)
		(fp_text user "P1"
			(at 6.585966 2.207514 0)
			(unlocked yes)
			(layer "F.SilkS")
			(effects
				(font
					(size 0.7874 0.5842)
					(thickness 0.1524)
				)
			)
		)
		(fp_text user "PRESS-FIT"
			(at -9.707626 10.997946 0)
			(unlocked yes)
			(layer "F.SilkS")
			(effects
				(font
					(size 0.7874 0.5842)
					(thickness 0.1524)
				)
				(justify left)
			)
		)
		(fp_text user "P16"
			(at 6.97992 37.823394 0)
			(unlocked yes)
			(layer "F.SilkS")
			(effects
				(font
					(size 0.7874 0.5842)
					(thickness 0.1524)
				)
			)
		)
		(fp_text user "P17"
			(at -8.79221 38.342824 0)
			(unlocked yes)
			(layer "F.SilkS")
			(effects
				(font
					(size 0.7874 0.5842)
					(thickness 0.1524)
				)
			)
		)
		(fp_text user "S1"
			(at 6.452362 41.608502 0)
			(unlocked yes)
			(layer "F.SilkS")
			(effects
				(font
					(size 0.7874 0.5842)
					(thickness 0.1524)
				)
			)
		)
		(fp_text user "S12"
			(at -9.221724 41.726612 0)
			(unlocked yes)
			(layer "F.SilkS")
			(effects
				(font
					(size 0.7874 0.5842)
					(thickness 0.1524)
				)
			)
		)
		(fp_text user "S6"
			(at 6.08457 47.991522 0)
			(unlocked yes)
			(layer "F.SilkS")
			(effects
				(font
					(size 0.7874 0.5842)
					(thickness 0.1524)
				)
			)
		)
		(fp_text user "S7"
			(at -9.294368 48.61433 0)
			(unlocked yes)
			(layer "F.SilkS")
			(effects
				(font
					(size 0.7874 0.5842)
					(thickness 0.1524)
				)
			)
		)
		(fp_text user "P1"
			(at 3.052318 -1.361948 0)
			(unlocked yes)
			(layer "B.SilkS")
			(effects
				(font
					(size 0.7874 0.5842)
					(thickness 0.1524)
				)
				(justify mirror)
			)
		)
		(fp_text user "P32"
			(at -5.867654 -0.333502 0)
			(unlocked yes)
			(layer "B.SilkS")
			(effects
				(font
					(size 0.7874 0.5842)
					(thickness 0.1524)
				)
				(justify mirror)
			)
		)
		(fp_text user "PRESS-FIT"
			(at -7.18947 29.8831 0)
			(unlocked yes)
			(layer "B.SilkS")
			(effects
				(font
					(size 0.7874 0.5842)
					(thickness 0.1524)
				)
				(justify left mirror)
			)
		)
		(fp_text user "P17"
			(at -5.72389 37.92347 0)
			(unlocked yes)
			(layer "B.SilkS")
			(effects
				(font
					(size 0.7874 0.5842)
					(thickness 0.1524)
				)
				(justify mirror)
			)
		)
		(fp_text user "P16"
			(at 3.103626 37.925248 0)
			(unlocked yes)
			(layer "B.SilkS")
			(effects
				(font
					(size 0.7874 0.5842)
					(thickness 0.1524)
				)
				(justify mirror)
			)
		)
		(fp_text user "S1"
			(at 3.064256 41.595548 0)
			(unlocked yes)
			(layer "B.SilkS")
			(effects
				(font
					(size 0.7874 0.5842)
					(thickness 0.1524)
				)
				(justify mirror)
			)
		)
		(fp_text user "S12"
			(at -5.753608 42.06748 0)
			(unlocked yes)
			(layer "B.SilkS")
			(effects
				(font
					(size 0.7874 0.5842)
					(thickness 0.1524)
				)
				(justify mirror)
			)
		)
		(fp_text user "S7"
			(at -5.867908 47.837344 0)
			(unlocked yes)
			(layer "B.SilkS")
			(effects
				(font
					(size 0.7874 0.5842)
					(thickness 0.1524)
				)
				(justify mirror)
			)
		)
		(fp_text user "S6"
			(at 2.992628 47.90567 0)
			(unlocked yes)
			(layer "B.SilkS")
			(effects
				(font
					(size 0.7874 0.5842)
					(thickness 0.1524)
				)
				(justify mirror)
			)
		)
		(fp_text user "P1"
			(at 3.108452 -1.27 180)
			(unlocked yes)
			(layer "B.Fab")
			(effects
				(font
					(size 0.7874 0.5842)
					(thickness 0.000001)
				)
				(justify mirror)
			)
		)
		(fp_text user "P32"
			(at -5.781548 -0.0508 180)
			(unlocked yes)
			(layer "B.Fab")
			(effects
				(font
					(size 0.7874 0.5842)
					(thickness 0.000001)
				)
				(justify mirror)
			)
		)
		(fp_text user "PRESS-FIT"
			(at -6.82371 29.8831 0)
			(unlocked yes)
			(layer "B.Fab")
			(effects
				(font
					(size 1.6002 1.1938)
					(thickness 0.000001)
				)
				(justify left mirror)
			)
		)
		(fp_text user "P17"
			(at -5.72135 38.0746 180)
			(unlocked yes)
			(layer "B.Fab")
			(effects
				(font
					(size 0.7874 0.5842)
					(thickness 0.000001)
				)
				(justify mirror)
			)
		)
		(fp_text user "P16"
			(at 3.159252 38.3794 180)
			(unlocked yes)
			(layer "B.Fab")
			(effects
				(font
					(size 0.7874 0.5842)
					(thickness 0.000001)
				)
				(justify mirror)
			)
		)
		(fp_text user "S12"
			(at -5.79374 41.42232 180)
			(unlocked yes)
			(layer "B.Fab")
			(effects
				(font
					(size 0.7874 0.5842)
					(thickness 0.000001)
				)
				(justify mirror)
			)
		)
		(fp_text user "S1"
			(at 3.09626 41.656 180)
			(unlocked yes)
			(layer "B.Fab")
			(effects
				(font
					(size 0.7874 0.5842)
					(thickness 0.000001)
				)
				(justify mirror)
			)
		)
		(fp_text user "S6"
			(at 3.133852 48.0822 180)
			(unlocked yes)
			(layer "B.Fab")
			(effects
				(font
					(size 0.7874 0.5842)
					(thickness 0.000001)
				)
				(justify mirror)
			)
		)
		(fp_text user "S7"
			(at -5.781548 48.0822 180)
			(unlocked yes)
			(layer "B.Fab")
			(effects
				(font
					(size 0.7874 0.5842)
					(thickness 0.000001)
				)
				(justify mirror)
			)
		)
		(fp_text user "P32"
			(at -4.071112 -0.0762 180)
			(unlocked yes)
			(layer "F.Fab")
			(effects
				(font
					(size 0.7874 0.5842)
					(thickness 0.000001)
				)
			)
		)
		(fp_text user "P1"
			(at 1.516888 0 180)
			(unlocked yes)
			(layer "F.Fab")
			(effects
				(font
					(size 0.7874 0.5842)
					(thickness 0.000001)
				)
			)
		)
		(fp_text user "PRESS-FIT"
			(at -6.762496 16.251428 0)
			(unlocked yes)
			(layer "F.Fab")
			(effects
				(font
					(size 1.6002 1.1938)
					(thickness 0.000001)
				)
				(justify left)
			)
		)
		(fp_text user "P17"
			(at -4.366768 38.227 180)
			(unlocked yes)
			(layer "F.Fab")
			(effects
				(font
					(size 0.7874 0.5842)
					(thickness 0.000001)
				)
			)
		)
		(fp_text user "P16"
			(at 2.228088 38.354 180)
			(unlocked yes)
			(layer "F.Fab")
			(effects
				(font
					(size 0.7874 0.5842)
					(thickness 0.000001)
				)
			)
		)
		(fp_text user "S12"
			(at -4.362958 41.09212 180)
			(unlocked yes)
			(layer "F.Fab")
			(effects
				(font
					(size 0.7874 0.5842)
					(thickness 0.000001)
				)
			)
		)
		(fp_text user "S1"
			(at 2.164842 41.6306 180)
			(unlocked yes)
			(layer "F.Fab")
			(effects
				(font
					(size 0.7874 0.5842)
					(thickness 0.000001)
				)
			)
		)
		(fp_text user "S6"
			(at 1.923288 48.133 180)
			(unlocked yes)
			(layer "F.Fab")
			(effects
				(font
					(size 0.7874 0.5842)
					(thickness 0.000001)
				)
			)
		)
		(fp_text user "S7"
			(at -4.426712 48.2346 180)
			(unlocked yes)
			(layer "F.Fab")
			(effects
				(font
					(size 0.7874 0.5842)
					(thickness 0.000001)
				)
			)
		)
		(pad "" np_thru_hole circle
			(at -1.35001 -2.54)
			(size 2.5146 2.5146)
			(drill 2.5146)
			(layers "*.Cu" "*.Mask")
			(clearance 0.381)
			(thermal_gap 0.381)
		)
		(pad "" np_thru_hole circle
			(at 0 50.8)
			(size 2.5146 2.5146)
			(drill 2.5146)
			(layers "*.Cu" "*.Mask")
			(clearance 0.381)
			(thermal_gap 0.381)
		)
		(pad "P1" thru_hole rect
			(at 0 0)
			(size 1.1684 1.1684)
			(drill 0.762)
			(layers "*.Cu" "*.Mask")
			(remove_unused_layers no)
			(net "GND")
			(clearance 0.0508)
			(padstack
				(mode front_inner_back)
				(layer "Inner"
					(shape circle)
					(size 1.1684 1.1684)
					(clearance 0.0508)
				)
				(layer "B.Cu"
					(shape rect)
					(size 1.1684 1.1684)
					(thermal_gap 0.0508)
					(clearance 0.0508)
				)
			)
		)
		(pad "P2" thru_hole circle
			(at 0 2.54)
			(size 1.1684 1.1684)
			(drill 0.762)
			(layers "*.Cu" "*.Mask")
			(remove_unused_layers no)
			(net "GND")
			(clearance 0.0508)
			(thermal_gap 0.0508)
		)
		(pad "P3" thru_hole circle
			(at 0 5.08)
			(size 1.1684 1.1684)
			(drill 0.762)
			(layers "*.Cu" "*.Mask")
			(remove_unused_layers no)
			(net "GND")
			(clearance 0.0508)
			(thermal_gap 0.0508)
		)
		(pad "P4" thru_hole circle
			(at 0 7.62)
			(size 1.1684 1.1684)
			(drill 0.762)
			(layers "*.Cu" "*.Mask")
			(remove_unused_layers no)
			(net "GND")
			(clearance 0.0508)
			(thermal_gap 0.0508)
		)
		(pad "P5" thru_hole circle
			(at 0 10.16)
			(size 1.1684 1.1684)
			(drill 0.762)
			(layers "*.Cu" "*.Mask")
			(remove_unused_layers no)
			(net "GND")
			(clearance 0.0508)
			(thermal_gap 0.0508)
		)
		(pad "P6" thru_hole circle
			(at 0 12.7)
			(size 1.1684 1.1684)
			(drill 0.762)
			(layers "*.Cu" "*.Mask")
			(remove_unused_layers no)
			(net "GND")
			(clearance 0.0508)
			(thermal_gap 0.0508)
		)
		(pad "P7" thru_hole circle
			(at 0 15.24)
			(size 1.1684 1.1684)
			(drill 0.762)
			(layers "*.Cu" "*.Mask")
			(remove_unused_layers no)
			(net "GND")
			(clearance 0.0508)
			(thermal_gap 0.0508)
		)
		(pad "P8" thru_hole circle
			(at 0 17.78)
			(size 1.1684 1.1684)
			(drill 0.762)
			(layers "*.Cu" "*.Mask")
			(remove_unused_layers no)
			(net "GND")
			(clearance 0.0508)
			(thermal_gap 0.0508)
		)
		(pad "P9" thru_hole circle
			(at 0 20.32)
			(size 1.1684 1.1684)
			(drill 0.762)
			(layers "*.Cu" "*.Mask")
			(remove_unused_layers no)
			(net "P12V")
			(clearance 0.0508)
			(thermal_gap 0.0508)
		)
		(pad "P10" thru_hole circle
			(at 0 22.86)
			(size 1.1684 1.1684)
			(drill 0.762)
			(layers "*.Cu" "*.Mask")
			(remove_unused_layers no)
			(net "P12V")
			(clearance 0.0508)
			(thermal_gap 0.0508)
		)
		(pad "P11" thru_hole circle
			(at 0 25.4)
			(size 1.1684 1.1684)
			(drill 0.762)
			(layers "*.Cu" "*.Mask")
			(remove_unused_layers no)
			(net "P12V")
			(clearance 0.0508)
			(thermal_gap 0.0508)
		)
		(pad "P12" thru_hole circle
			(at 0 27.94)
			(size 1.1684 1.1684)
			(drill 0.762)
			(layers "*.Cu" "*.Mask")
			(remove_unused_layers no)
			(net "P12V")
			(clearance 0.0508)
			(thermal_gap 0.0508)
		)
		(pad "P13" thru_hole circle
			(at 0 30.48)
			(size 1.1684 1.1684)
			(drill 0.762)
			(layers "*.Cu" "*.Mask")
			(remove_unused_layers no)
			(net "P12V")
			(clearance 0.0508)
			(thermal_gap 0.0508)
		)
		(pad "P14" thru_hole circle
			(at 0 33.02)
			(size 1.1684 1.1684)
			(drill 0.762)
			(layers "*.Cu" "*.Mask")
			(remove_unused_layers no)
			(net "P12V")
			(clearance 0.0508)
			(thermal_gap 0.0508)
		)
		(pad "P15" thru_hole circle
			(at 0 35.56)
			(size 1.1684 1.1684)
			(drill 0.762)
			(layers "*.Cu" "*.Mask")
			(remove_unused_layers no)
			(net "P12V")
			(clearance 0.0508)
			(thermal_gap 0.0508)
		)
		(pad "P16" thru_hole circle
			(at 0 38.1)
			(size 1.1684 1.1684)
			(drill 0.762)
			(layers "*.Cu" "*.Mask")
			(remove_unused_layers no)
			(net "P12V")
			(clearance 0.0508)
			(thermal_gap 0.0508)
		)
		(pad "P17" thru_hole circle
			(at -2.70002 38.1)
			(size 1.1684 1.1684)
			(drill 0.762)
			(layers "*.Cu" "*.Mask")
			(remove_unused_layers no)
			(net "P12V")
			(clearance 0.0508)
			(thermal_gap 0.0508)
		)
		(pad "P18" thru_hole circle
			(at -2.70002 35.56)
			(size 1.1684 1.1684)
			(drill 0.762)
			(layers "*.Cu" "*.Mask")
			(remove_unused_layers no)
			(net "P12V")
			(clearance 0.0508)
			(thermal_gap 0.0508)
		)
		(pad "P19" thru_hole circle
			(at -2.70002 33.02)
			(size 1.1684 1.1684)
			(drill 0.762)
			(layers "*.Cu" "*.Mask")
			(remove_unused_layers no)
			(net "P12V")
			(clearance 0.0508)
			(thermal_gap 0.0508)
		)
		(pad "P20" thru_hole circle
			(at -2.70002 30.48)
			(size 1.1684 1.1684)
			(drill 0.762)
			(layers "*.Cu" "*.Mask")
			(remove_unused_layers no)
			(net "P12V")
			(clearance 0.0508)
			(thermal_gap 0.0508)
		)
		(pad "P21" thru_hole circle
			(at -2.70002 27.94)
			(size 1.1684 1.1684)
			(drill 0.762)
			(layers "*.Cu" "*.Mask")
			(remove_unused_layers no)
			(net "P12V")
			(clearance 0.0508)
			(thermal_gap 0.0508)
		)
		(pad "P22" thru_hole circle
			(at -2.70002 25.4)
			(size 1.1684 1.1684)
			(drill 0.762)
			(layers "*.Cu" "*.Mask")
			(remove_unused_layers no)
			(net "P12V")
			(clearance 0.0508)
			(thermal_gap 0.0508)
		)
		(pad "P23" thru_hole circle
			(at -2.70002 22.86)
			(size 1.1684 1.1684)
			(drill 0.762)
			(layers "*.Cu" "*.Mask")
			(remove_unused_layers no)
			(net "P12V")
			(clearance 0.0508)
			(thermal_gap 0.0508)
		)
		(pad "P24" thru_hole circle
			(at -2.70002 20.32)
			(size 1.1684 1.1684)
			(drill 0.762)
			(layers "*.Cu" "*.Mask")
			(remove_unused_layers no)
			(net "P12V")
			(clearance 0.0508)
			(thermal_gap 0.0508)
		)
		(pad "P25" thru_hole circle
			(at -2.70002 17.78)
			(size 1.1684 1.1684)
			(drill 0.762)
			(layers "*.Cu" "*.Mask")
			(remove_unused_layers no)
			(net "GND")
			(clearance 0.0508)
			(thermal_gap 0.0508)
		)
		(pad "P26" thru_hole circle
			(at -2.70002 15.24)
			(size 1.1684 1.1684)
			(drill 0.762)
			(layers "*.Cu" "*.Mask")
			(remove_unused_layers no)
			(net "GND")
			(clearance 0.0508)
			(thermal_gap 0.0508)
		)
		(pad "P27" thru_hole circle
			(at -2.70002 12.7)
			(size 1.1684 1.1684)
			(drill 0.762)
			(layers "*.Cu" "*.Mask")
			(remove_unused_layers no)
			(net "GND")
			(clearance 0.0508)
			(thermal_gap 0.0508)
		)
		(pad "P28" thru_hole circle
			(at -2.70002 10.16)
			(size 1.1684 1.1684)
			(drill 0.762)
			(layers "*.Cu" "*.Mask")
			(remove_unused_layers no)
			(net "GND")
			(clearance 0.0508)
			(thermal_gap 0.0508)
		)
		(pad "P29" thru_hole circle
			(at -2.70002 7.62)
			(size 1.1684 1.1684)
			(drill 0.762)
			(layers "*.Cu" "*.Mask")
			(remove_unused_layers no)
			(net "GND")
			(clearance 0.0508)
			(thermal_gap 0.0508)
		)
		(pad "P30" thru_hole circle
			(at -2.70002 5.08)
			(size 1.1684 1.1684)
			(drill 0.762)
			(layers "*.Cu" "*.Mask")
			(remove_unused_layers no)
			(net "GND")
			(clearance 0.0508)
			(thermal_gap 0.0508)
		)
		(pad "P31" thru_hole circle
			(at -2.70002 2.54)
			(size 1.1684 1.1684)
			(drill 0.762)
			(layers "*.Cu" "*.Mask")
			(remove_unused_layers no)
			(net "GND")
			(clearance 0.0508)
			(thermal_gap 0.0508)
		)
		(pad "P32" thru_hole circle
			(at -2.70002 0)
			(size 1.1684 1.1684)
			(drill 0.762)
			(layers "*.Cu" "*.Mask")
			(remove_unused_layers no)
			(net "GND")
			(clearance 0.0508)
			(thermal_gap 0.0508)
		)
		(pad "S1" thru_hole circle
			(at 0.55499 41.60012)
			(size 1.1684 1.1684)
			(drill 0.762)
			(layers "*.Cu" "*.Mask")
			(remove_unused_layers no)
			(net "T3_BLAD1_TXD")
			(clearance 0.0508)
			(thermal_gap 0.0508)
		)
		(pad "S2" thru_hole circle
			(at -0.71501 42.87012)
			(size 1.1684 1.1684)
			(drill 0.762)
			(layers "*.Cu" "*.Mask")
			(remove_unused_layers no)
			(net "T3_BLAD1_RXD")
			(clearance 0.0508)
			(thermal_gap 0.0508)
		)
		(pad "S3" thru_hole circle
			(at 0.55499 44.14012)
			(size 1.1684 1.1684)
			(drill 0.762)
			(layers "*.Cu" "*.Mask")
			(remove_unused_layers no)
			(net "T3_BLAD1_EN")
			(clearance 0.0508)
			(thermal_gap 0.0508)
		)
		(pad "S4" thru_hole circle
			(at -0.71501 45.41012)
			(size 1.1684 1.1684)
			(drill 0.762)
			(layers "*.Cu" "*.Mask")
			(remove_unused_layers no)
			(net "B5_PSU_ALERT_N")
			(clearance 0.0508)
			(thermal_gap 0.0508)
		)
		(pad "S5" thru_hole circle
			(at 0.55499 46.68012)
			(size 1.1684 1.1684)
			(drill 0.762)
			(layers "*.Cu" "*.Mask")
			(remove_unused_layers no)
			(net "T3_BLAD2_TXD")
			(clearance 0.0508)
			(thermal_gap 0.0508)
		)
		(pad "S6" thru_hole circle
			(at -0.71501 47.95012)
			(size 1.1684 1.1684)
			(drill 0.762)
			(layers "*.Cu" "*.Mask")
			(remove_unused_layers no)
			(net "T3_BLAD2_RXD")
			(clearance 0.0508)
			(thermal_gap 0.0508)
		)
		(pad "S7" thru_hole circle
			(at -3.25501 47.95012)
			(size 1.1684 1.1684)
			(drill 0.762)
			(layers "*.Cu" "*.Mask")
			(remove_unused_layers no)
			(net "T3_BLAD4_RXD")
			(clearance 0.0508)
			(thermal_gap 0.0508)
		)
		(pad "S8" thru_hole circle
			(at -1.98501 46.68012)
			(size 1.1684 1.1684)
			(drill 0.762)
			(layers "*.Cu" "*.Mask")
			(remove_unused_layers no)
			(net "T3_BLAD4_TXD")
			(clearance 0.0508)
			(thermal_gap 0.0508)
		)
		(pad "S9" thru_hole circle
			(at -3.25501 45.41012)
			(size 1.1684 1.1684)
			(drill 0.762)
			(layers "*.Cu" "*.Mask")
			(remove_unused_layers no)
			(net "B6_PSU_ALERT_N")
			(clearance 0.0508)
			(thermal_gap 0.0508)
		)
		(pad "S10" thru_hole circle
			(at -1.98501 44.14012)
			(size 1.1684 1.1684)
			(drill 0.762)
			(layers "*.Cu" "*.Mask")
			(remove_unused_layers no)
			(net "T3_BLAD3_EN")
			(clearance 0.0508)
			(thermal_gap 0.0508)
		)
		(pad "S11" thru_hole circle
			(at -3.25501 42.87012)
			(size 1.1684 1.1684)
			(drill 0.762)
			(layers "*.Cu" "*.Mask")
			(remove_unused_layers no)
			(net "T3_BLAD3_RXD")
			(clearance 0.0508)
			(thermal_gap 0.0508)
		)
		(pad "S12" thru_hole circle
			(at -1.98501 41.60012)
			(size 1.1684 1.1684)
			(drill 0.762)
			(layers "*.Cu" "*.Mask")
			(remove_unused_layers no)
			(net "T3_BLAD3_TXD")
			(clearance 0.0508)
			(thermal_gap 0.0508)
		)
		(zone
			(layer "F.Cu")
			(hatch none 0.5)
			(connect_pads
				(clearance 0)
			)
			(min_thickness 0.25)
			(keepout
				(tracks allowed)
				(vias not_allowed)
				(pads allowed)
				(copperpour not_allowed)
				(footprints allowed)
			)
			(placement
				(enabled no)
				(sheetname "")
			)
			(fill
				(thermal_gap 0.5)
				(thermal_bridge_width 0.5)
				(island_removal_mode 0)
			)
			(polygon
				(pts
					(xy 85.00999 -98.35388) (xy 92.65539 -98.35388) (xy 92.65539 -93.24848) (xy 85.00999 -93.24848)
					(xy 84.98459 -93.24848) (xy 84.98459 -98.35388)
				)
			)
		)
		(zone
			(layer "F.Cu")
			(hatch none 0.5)
			(connect_pads
				(clearance 0)
			)
			(min_thickness 0.25)
			(keepout
				(tracks allowed)
				(vias not_allowed)
				(pads allowed)
				(copperpour not_allowed)
				(footprints allowed)
			)
			(placement
				(enabled no)
				(sheetname "")
			)
			(fill
				(thermal_gap 0.5)
				(thermal_bridge_width 0.5)
				(island_removal_mode 0)
			)
			(polygon
				(pts
					(xy 43.37939 -93.83268) (xy 43.37939 -97.79508) (xy 82.77479 -97.79508) (xy 82.80019 -97.79508)
					(xy 82.80019 -93.83268) (xy 82.80019 -93.80728) (xy 43.37939 -93.80728)
				)
			)
		)
		(zone
			(layers "F.Cu" "B.Cu" "In1.Cu" "In2.Cu" "In3.Cu" "In4.Cu" "In5.Cu" "In6.Cu")
			(hatch none 0.5)
			(connect_pads
				(clearance 0)
			)
			(min_thickness 0.25)
			(keepout
				(tracks not_allowed)
				(vias allowed)
				(pads allowed)
				(copperpour not_allowed)
				(footprints allowed)
			)
			(placement
				(enabled no)
				(sheetname "")
			)
			(fill
				(thermal_gap 0.5)
				(thermal_bridge_width 0.5)
				(island_removal_mode 0)
			)
			(polygon
				(pts
					(arc
						(start 43.18 -95.81007)
						(mid 39.81958 -95.81007)
						(end 43.18 -95.81007)
					)
				)
			)
		)
		(zone
			(layers "F.Cu" "B.Cu" "In1.Cu" "In2.Cu" "In3.Cu" "In4.Cu" "In5.Cu" "In6.Cu")
			(hatch none 0.5)
			(connect_pads
				(clearance 0)
			)
			(min_thickness 0.25)
			(keepout
				(tracks not_allowed)
				(vias allowed)
				(pads allowed)
				(copperpour not_allowed)
				(footprints allowed)
			)
			(placement
				(enabled no)
				(sheetname "")
			)
			(fill
				(thermal_gap 0.5)
				(thermal_bridge_width 0.5)
				(island_removal_mode 0)
			)
			(polygon
				(pts
					(arc
						(start 96.52381 -97.16008)
						(mid 93.15577 -97.16008)
						(end 96.52381 -97.16008)
					)
				)
			)
		)
	)
	(footprint ""
		(layer "B.Cu")
		(at 44.03979 -408.31008 90)
		(property "Reference" "J16"
			(at 6.272784 -4.326636 0)
			(unlocked yes)
			(layer "B.SilkS")
			(effects
				(font
					(size 0.7874 0.5842)
					(thickness 0.1524)
				)
				(justify left mirror)
			)
		)
		(property "Value" ""
			(at 0 0 90)
			(layer "B.Fab")
			(effects
				(font
					(size 1.27 1.27)
				)
				(justify mirror)
			)
		)
		(duplicate_pad_numbers_are_jumpers no)
		(fp_line
			(start 5.275072 -13.910056)
			(end -7.975092 -13.910056)
			(stroke
				(width 0.1524)
				(type default)
			)
			(layer "F.SilkS")
		)
		(fp_line
			(start -7.975092 -13.910056)
			(end -7.975092 62.170056)
			(stroke
				(width 0.1524)
				(type default)
			)
			(layer "F.SilkS")
		)
		(fp_line
			(start 5.275072 62.170056)
			(end 5.275072 -13.910056)
			(stroke
				(width 0.1524)
				(type default)
			)
			(layer "F.SilkS")
		)
		(fp_line
			(start -7.975092 62.170056)
			(end 5.275072 62.170056)
			(stroke
				(width 0.1524)
				(type default)
			)
			(layer "F.SilkS")
		)
		(fp_line
			(start 5.275072 -13.910056)
			(end -7.975092 -13.910056)
			(stroke
				(width 0.1524)
				(type default)
			)
			(layer "B.SilkS")
		)
		(fp_line
			(start -7.975092 -13.910056)
			(end -7.975092 62.170056)
			(stroke
				(width 0.1524)
				(type default)
			)
			(layer "B.SilkS")
		)
		(fp_line
			(start 2.275078 -10.910062)
			(end 2.275078 59.170062)
			(stroke
				(width 0.1524)
				(type default)
			)
			(layer "B.SilkS")
		)
		(fp_line
			(start -4.975098 -10.910062)
			(end 2.275078 -10.910062)
			(stroke
				(width 0.1524)
				(type default)
			)
			(layer "B.SilkS")
		)
		(fp_line
			(start 2.275078 59.170062)
			(end -4.975098 59.170062)
			(stroke
				(width 0.1524)
				(type default)
			)
			(layer "B.SilkS")
		)
		(fp_line
			(start -4.975098 59.170062)
			(end -4.975098 -10.910062)
			(stroke
				(width 0.1524)
				(type default)
			)
			(layer "B.SilkS")
		)
		(fp_line
			(start 5.275072 62.170056)
			(end 5.275072 -13.910056)
			(stroke
				(width 0.1524)
				(type default)
			)
			(layer "B.SilkS")
		)
		(fp_line
			(start -7.975092 62.170056)
			(end 5.275072 62.170056)
			(stroke
				(width 0.1524)
				(type default)
			)
			(layer "B.SilkS")
		)
		(fp_poly
			(pts
				(xy 4.103878 -0.759206) (xy 4.103878 0.764794) (xy 2.579878 0.002794)
			)
			(stroke
				(width 0)
				(type default)
			)
			(fill yes)
			(layer "B.SilkS")
		)
		(fp_poly
			(pts
				(xy 2.275078 -10.910062) (xy 2.275078 59.170062) (xy -4.975098 59.170062) (xy -4.975098 -10.910062)
			)
			(stroke
				(width 0)
				(type default)
			)
			(fill no)
			(layer "B.CrtYd")
		)
		(fp_poly
			(pts
				(xy 1.1938 40.9702) (xy 1.1938 48.6156) (xy -3.9116 48.6156) (xy -3.9116 40.9702) (xy -3.9116 40.9448)
				(xy 1.1938 40.9448)
			)
			(stroke
				(width 0)
				(type default)
			)
			(fill no)
			(layer "F.CrtYd")
		)
		(fp_poly
			(pts
				(xy -3.3274 -0.6604) (xy 0.635 -0.6604) (xy 0.635 38.735) (xy 0.635 38.7604) (xy -3.3274 38.7604)
				(xy -3.3528 38.7604) (xy -3.3528 -0.6604)
			)
			(stroke
				(width 0)
				(type default)
			)
			(fill no)
			(layer "F.CrtYd")
		)
		(fp_poly
			(pts
				(arc
					(start -1.35001 -1.01219)
					(mid -1.35001 -4.06781)
					(end -1.35001 -1.01219)
				)
			)
			(stroke
				(width 0)
				(type default)
			)
			(fill no)
			(layer "F.CrtYd")
		)
		(fp_poly
			(pts
				(arc
					(start 0 52.33162)
					(mid 0 49.26838)
					(end 0 52.33162)
				)
			)
			(stroke
				(width 0)
				(type default)
			)
			(fill no)
			(layer "F.CrtYd")
		)
		(fp_line
			(start 2.275078 -10.910062)
			(end 2.275078 59.170062)
			(stroke
				(width 0.1)
				(type default)
			)
			(layer "B.Fab")
		)
		(fp_line
			(start -4.975098 -10.910062)
			(end 2.275078 -10.910062)
			(stroke
				(width 0.1)
				(type default)
			)
			(layer "B.Fab")
		)
		(fp_line
			(start 2.275078 59.170062)
			(end -4.975098 59.170062)
			(stroke
				(width 0.1)
				(type default)
			)
			(layer "B.Fab")
		)
		(fp_line
			(start -4.975098 59.170062)
			(end -4.975098 -10.910062)
			(stroke
				(width 0.1)
				(type default)
			)
			(layer "B.Fab")
		)
		(fp_poly
			(pts
				(xy 4.103878 -0.759206) (xy 4.103878 0.764794) (xy 2.579878 0.002794)
			)
			(stroke
				(width 0)
				(type default)
			)
			(fill yes)
			(layer "B.Fab")
		)
		(fp_line
			(start 5.275072 -13.910056)
			(end -7.975092 -13.910056)
			(stroke
				(width 0.1)
				(type default)
			)
			(layer "F.Fab")
		)
		(fp_line
			(start -7.975092 -13.910056)
			(end -7.975092 62.170056)
			(stroke
				(width 0.1)
				(type default)
			)
			(layer "F.Fab")
		)
		(fp_line
			(start 5.275072 62.170056)
			(end 5.275072 -13.910056)
			(stroke
				(width 0.1)
				(type default)
			)
			(layer "F.Fab")
		)
		(fp_line
			(start -7.975092 62.170056)
			(end 5.275072 62.170056)
			(stroke
				(width 0.1)
				(type default)
			)
			(layer "F.Fab")
		)
		(fp_text user "P32"
			(at -8.804656 0.001778 0)
			(unlocked yes)
			(layer "F.SilkS")
			(effects
				(font
					(size 0.7874 0.5842)
					(thickness 0.1524)
				)
			)
		)
		(fp_text user "P1"
			(at 6.234176 0.469646 0)
			(unlocked yes)
			(layer "F.SilkS")
			(effects
				(font
					(size 0.7874 0.5842)
					(thickness 0.1524)
				)
			)
		)
		(fp_text user "PRESS-FIT"
			(at -9.339326 15.441422 0)
			(unlocked yes)
			(layer "F.SilkS")
			(effects
				(font
					(size 0.7874 0.5842)
					(thickness 0.1524)
				)
				(justify left)
			)
		)
		(fp_text user "P16"
			(at 5.963666 37.724842 0)
			(unlocked yes)
			(layer "F.SilkS")
			(effects
				(font
					(size 0.7874 0.5842)
					(thickness 0.1524)
				)
			)
		)
		(fp_text user "P17"
			(at -11.678158 38.451536 0)
			(unlocked yes)
			(layer "F.SilkS")
			(effects
				(font
					(size 0.7874 0.5842)
					(thickness 0.1524)
				)
			)
		)
		(fp_text user "S1"
			(at 6.265164 41.224454 0)
			(unlocked yes)
			(layer "F.SilkS")
			(effects
				(font
					(size 0.7874 0.5842)
					(thickness 0.1524)
				)
			)
		)
		(fp_text user "S12"
			(at -11.443462 41.784016 0)
			(unlocked yes)
			(layer "F.SilkS")
			(effects
				(font
					(size 0.7874 0.5842)
					(thickness 0.1524)
				)
			)
		)
		(fp_text user "S6"
			(at 6.030214 47.525686 0)
			(unlocked yes)
			(layer "F.SilkS")
			(effects
				(font
					(size 0.7874 0.5842)
					(thickness 0.1524)
				)
			)
		)
		(fp_text user "S7"
			(at -11.651996 48.364394 0)
			(unlocked yes)
			(layer "F.SilkS")
			(effects
				(font
					(size 0.7874 0.5842)
					(thickness 0.1524)
				)
			)
		)
		(fp_text user "P1"
			(at 2.951988 -1.351788 0)
			(unlocked yes)
			(layer "B.SilkS")
			(effects
				(font
					(size 0.7874 0.5842)
					(thickness 0.1524)
				)
				(justify mirror)
			)
		)
		(fp_text user "P32"
			(at -5.865876 0.085344 0)
			(unlocked yes)
			(layer "B.SilkS")
			(effects
				(font
					(size 0.7874 0.5842)
					(thickness 0.1524)
				)
				(justify mirror)
			)
		)
		(fp_text user "PRESS-FIT"
			(at -7.18947 29.8831 0)
			(unlocked yes)
			(layer "B.SilkS")
			(effects
				(font
					(size 0.7874 0.5842)
					(thickness 0.1524)
				)
				(justify left mirror)
			)
		)
		(fp_text user "P17"
			(at -5.858002 37.627814 0)
			(unlocked yes)
			(layer "B.SilkS")
			(effects
				(font
					(size 0.7874 0.5842)
					(thickness 0.1524)
				)
				(justify mirror)
			)
		)
		(fp_text user "P16"
			(at 3.071622 37.902134 0)
			(unlocked yes)
			(layer "B.SilkS")
			(effects
				(font
					(size 0.7874 0.5842)
					(thickness 0.1524)
				)
				(justify mirror)
			)
		)
		(fp_text user "S1"
			(at 3.066542 41.60647 0)
			(unlocked yes)
			(layer "B.SilkS")
			(effects
				(font
					(size 0.7874 0.5842)
					(thickness 0.1524)
				)
				(justify mirror)
			)
		)
		(fp_text user "S12"
			(at -5.725668 42.13733 180)
			(unlocked yes)
			(layer "B.SilkS")
			(effects
				(font
					(size 0.7874 0.5842)
					(thickness 0.1524)
				)
				(justify mirror)
			)
		)
		(fp_text user "S6"
			(at 3.02895 47.780194 0)
			(unlocked yes)
			(layer "B.SilkS")
			(effects
				(font
					(size 0.7874 0.5842)
					(thickness 0.1524)
				)
				(justify mirror)
			)
		)
		(fp_text user "S7"
			(at -5.899658 48.120808 0)
			(unlocked yes)
			(layer "B.SilkS")
			(effects
				(font
					(size 0.7874 0.5842)
					(thickness 0.1524)
				)
				(justify mirror)
			)
		)
		(fp_text user "P1"
			(at 3.108452 -1.27 180)
			(unlocked yes)
			(layer "B.Fab")
			(effects
				(font
					(size 0.7874 0.5842)
					(thickness 0.000001)
				)
				(justify mirror)
			)
		)
		(fp_text user "P32"
			(at -5.781548 -0.0508 180)
			(unlocked yes)
			(layer "B.Fab")
			(effects
				(font
					(size 0.7874 0.5842)
					(thickness 0.000001)
				)
				(justify mirror)
			)
		)
		(fp_text user "PRESS-FIT"
			(at -6.82371 29.8831 0)
			(unlocked yes)
			(layer "B.Fab")
			(effects
				(font
					(size 1.6002 1.1938)
					(thickness 0.000001)
				)
				(justify left mirror)
			)
		)
		(fp_text user "P17"
			(at -5.72135 38.0746 180)
			(unlocked yes)
			(layer "B.Fab")
			(effects
				(font
					(size 0.7874 0.5842)
					(thickness 0.000001)
				)
				(justify mirror)
			)
		)
		(fp_text user "P16"
			(at 3.159252 38.3794 180)
			(unlocked yes)
			(layer "B.Fab")
			(effects
				(font
					(size 0.7874 0.5842)
					(thickness 0.000001)
				)
				(justify mirror)
			)
		)
		(fp_text user "S12"
			(at -5.79374 41.42232 180)
			(unlocked yes)
			(layer "B.Fab")
			(effects
				(font
					(size 0.7874 0.5842)
					(thickness 0.000001)
				)
				(justify mirror)
			)
		)
		(fp_text user "S1"
			(at 3.09626 41.656 180)
			(unlocked yes)
			(layer "B.Fab")
			(effects
				(font
					(size 0.7874 0.5842)
					(thickness 0.000001)
				)
				(justify mirror)
			)
		)
		(fp_text user "S6"
			(at 3.133852 48.0822 180)
			(unlocked yes)
			(layer "B.Fab")
			(effects
				(font
					(size 0.7874 0.5842)
					(thickness 0.000001)
				)
				(justify mirror)
			)
		)
		(fp_text user "S7"
			(at -5.781548 48.0822 180)
			(unlocked yes)
			(layer "B.Fab")
			(effects
				(font
					(size 0.7874 0.5842)
					(thickness 0.000001)
				)
				(justify mirror)
			)
		)
		(fp_text user "P32"
			(at -4.071112 -0.0762 180)
			(unlocked yes)
			(layer "F.Fab")
			(effects
				(font
					(size 0.7874 0.5842)
					(thickness 0.000001)
				)
			)
		)
		(fp_text user "P1"
			(at 1.516888 0 180)
			(unlocked yes)
			(layer "F.Fab")
			(effects
				(font
					(size 0.7874 0.5842)
					(thickness 0.000001)
				)
			)
		)
		(fp_text user "PRESS-FIT"
			(at -6.762496 16.251428 0)
			(unlocked yes)
			(layer "F.Fab")
			(effects
				(font
					(size 1.6002 1.1938)
					(thickness 0.000001)
				)
				(justify left)
			)
		)
		(fp_text user "P17"
			(at -4.366768 38.227 180)
			(unlocked yes)
			(layer "F.Fab")
			(effects
				(font
					(size 0.7874 0.5842)
					(thickness 0.000001)
				)
			)
		)
		(fp_text user "P16"
			(at 2.228088 38.354 180)
			(unlocked yes)
			(layer "F.Fab")
			(effects
				(font
					(size 0.7874 0.5842)
					(thickness 0.000001)
				)
			)
		)
		(fp_text user "S12"
			(at -4.362958 41.09212 180)
			(unlocked yes)
			(layer "F.Fab")
			(effects
				(font
					(size 0.7874 0.5842)
					(thickness 0.000001)
				)
			)
		)
		(fp_text user "S1"
			(at 2.164842 41.6306 180)
			(unlocked yes)
			(layer "F.Fab")
			(effects
				(font
					(size 0.7874 0.5842)
					(thickness 0.000001)
				)
			)
		)
		(fp_text user "S6"
			(at 1.923288 48.133 180)
			(unlocked yes)
			(layer "F.Fab")
			(effects
				(font
					(size 0.7874 0.5842)
					(thickness 0.000001)
				)
			)
		)
		(fp_text user "S7"
			(at -4.426712 48.2346 180)
			(unlocked yes)
			(layer "F.Fab")
			(effects
				(font
					(size 0.7874 0.5842)
					(thickness 0.000001)
				)
			)
		)
		(pad "" np_thru_hole circle
			(at -1.35001 -2.54)
			(size 2.5146 2.5146)
			(drill 2.5146)
			(layers "*.Cu" "*.Mask")
			(clearance 0.381)
			(thermal_gap 0.381)
		)
		(pad "" np_thru_hole circle
			(at 0 50.8)
			(size 2.5146 2.5146)
			(drill 2.5146)
			(layers "*.Cu" "*.Mask")
			(clearance 0.381)
			(thermal_gap 0.381)
		)
		(pad "P1" thru_hole rect
			(at 0 0)
			(size 1.1684 1.1684)
			(drill 0.762)
			(layers "*.Cu" "*.Mask")
			(remove_unused_layers no)
			(net "GND")
			(clearance 0.0508)
			(padstack
				(mode front_inner_back)
				(layer "Inner"
					(shape circle)
					(size 1.1684 1.1684)
					(clearance 0.0508)
				)
				(layer "B.Cu"
					(shape rect)
					(size 1.1684 1.1684)
					(thermal_gap 0.0508)
					(clearance 0.0508)
				)
			)
		)
		(pad "P2" thru_hole circle
			(at 0 2.54)
			(size 1.1684 1.1684)
			(drill 0.762)
			(layers "*.Cu" "*.Mask")
			(remove_unused_layers no)
			(net "GND")
			(clearance 0.0508)
			(thermal_gap 0.0508)
		)
		(pad "P3" thru_hole circle
			(at 0 5.08)
			(size 1.1684 1.1684)
			(drill 0.762)
			(layers "*.Cu" "*.Mask")
			(remove_unused_layers no)
			(net "GND")
			(clearance 0.0508)
			(thermal_gap 0.0508)
		)
		(pad "P4" thru_hole circle
			(at 0 7.62)
			(size 1.1684 1.1684)
			(drill 0.762)
			(layers "*.Cu" "*.Mask")
			(remove_unused_layers no)
			(net "GND")
			(clearance 0.0508)
			(thermal_gap 0.0508)
		)
		(pad "P5" thru_hole circle
			(at 0 10.16)
			(size 1.1684 1.1684)
			(drill 0.762)
			(layers "*.Cu" "*.Mask")
			(remove_unused_layers no)
			(net "GND")
			(clearance 0.0508)
			(thermal_gap 0.0508)
		)
		(pad "P6" thru_hole circle
			(at 0 12.7)
			(size 1.1684 1.1684)
			(drill 0.762)
			(layers "*.Cu" "*.Mask")
			(remove_unused_layers no)
			(net "GND")
			(clearance 0.0508)
			(thermal_gap 0.0508)
		)
		(pad "P7" thru_hole circle
			(at 0 15.24)
			(size 1.1684 1.1684)
			(drill 0.762)
			(layers "*.Cu" "*.Mask")
			(remove_unused_layers no)
			(net "GND")
			(clearance 0.0508)
			(thermal_gap 0.0508)
		)
		(pad "P8" thru_hole circle
			(at 0 17.78)
			(size 1.1684 1.1684)
			(drill 0.762)
			(layers "*.Cu" "*.Mask")
			(remove_unused_layers no)
			(net "GND")
			(clearance 0.0508)
			(thermal_gap 0.0508)
		)
		(pad "P9" thru_hole circle
			(at 0 20.32)
			(size 1.1684 1.1684)
			(drill 0.762)
			(layers "*.Cu" "*.Mask")
			(remove_unused_layers no)
			(net "P12V")
			(clearance 0.0508)
			(thermal_gap 0.0508)
		)
		(pad "P10" thru_hole circle
			(at 0 22.86)
			(size 1.1684 1.1684)
			(drill 0.762)
			(layers "*.Cu" "*.Mask")
			(remove_unused_layers no)
			(net "P12V")
			(clearance 0.0508)
			(thermal_gap 0.0508)
		)
		(pad "P11" thru_hole circle
			(at 0 25.4)
			(size 1.1684 1.1684)
			(drill 0.762)
			(layers "*.Cu" "*.Mask")
			(remove_unused_layers no)
			(net "P12V")
			(clearance 0.0508)
			(thermal_gap 0.0508)
		)
		(pad "P12" thru_hole circle
			(at 0 27.94)
			(size 1.1684 1.1684)
			(drill 0.762)
			(layers "*.Cu" "*.Mask")
			(remove_unused_layers no)
			(net "P12V")
			(clearance 0.0508)
			(thermal_gap 0.0508)
		)
		(pad "P13" thru_hole circle
			(at 0 30.48)
			(size 1.1684 1.1684)
			(drill 0.762)
			(layers "*.Cu" "*.Mask")
			(remove_unused_layers no)
			(net "P12V")
			(clearance 0.0508)
			(thermal_gap 0.0508)
		)
		(pad "P14" thru_hole circle
			(at 0 33.02)
			(size 1.1684 1.1684)
			(drill 0.762)
			(layers "*.Cu" "*.Mask")
			(remove_unused_layers no)
			(net "P12V")
			(clearance 0.0508)
			(thermal_gap 0.0508)
		)
		(pad "P15" thru_hole circle
			(at 0 35.56)
			(size 1.1684 1.1684)
			(drill 0.762)
			(layers "*.Cu" "*.Mask")
			(remove_unused_layers no)
			(net "P12V")
			(clearance 0.0508)
			(thermal_gap 0.0508)
		)
		(pad "P16" thru_hole circle
			(at 0 38.1)
			(size 1.1684 1.1684)
			(drill 0.762)
			(layers "*.Cu" "*.Mask")
			(remove_unused_layers no)
			(net "P12V")
			(clearance 0.0508)
			(thermal_gap 0.0508)
		)
		(pad "P17" thru_hole circle
			(at -2.70002 38.1)
			(size 1.1684 1.1684)
			(drill 0.762)
			(layers "*.Cu" "*.Mask")
			(remove_unused_layers no)
			(net "P12V")
			(clearance 0.0508)
			(thermal_gap 0.0508)
		)
		(pad "P18" thru_hole circle
			(at -2.70002 35.56)
			(size 1.1684 1.1684)
			(drill 0.762)
			(layers "*.Cu" "*.Mask")
			(remove_unused_layers no)
			(net "P12V")
			(clearance 0.0508)
			(thermal_gap 0.0508)
		)
		(pad "P19" thru_hole circle
			(at -2.70002 33.02)
			(size 1.1684 1.1684)
			(drill 0.762)
			(layers "*.Cu" "*.Mask")
			(remove_unused_layers no)
			(net "P12V")
			(clearance 0.0508)
			(thermal_gap 0.0508)
		)
		(pad "P20" thru_hole circle
			(at -2.70002 30.48)
			(size 1.1684 1.1684)
			(drill 0.762)
			(layers "*.Cu" "*.Mask")
			(remove_unused_layers no)
			(net "P12V")
			(clearance 0.0508)
			(thermal_gap 0.0508)
		)
		(pad "P21" thru_hole circle
			(at -2.70002 27.94)
			(size 1.1684 1.1684)
			(drill 0.762)
			(layers "*.Cu" "*.Mask")
			(remove_unused_layers no)
			(net "P12V")
			(clearance 0.0508)
			(thermal_gap 0.0508)
		)
		(pad "P22" thru_hole circle
			(at -2.70002 25.4)
			(size 1.1684 1.1684)
			(drill 0.762)
			(layers "*.Cu" "*.Mask")
			(remove_unused_layers no)
			(net "P12V")
			(clearance 0.0508)
			(thermal_gap 0.0508)
		)
		(pad "P23" thru_hole circle
			(at -2.70002 22.86)
			(size 1.1684 1.1684)
			(drill 0.762)
			(layers "*.Cu" "*.Mask")
			(remove_unused_layers no)
			(net "P12V")
			(clearance 0.0508)
			(thermal_gap 0.0508)
		)
		(pad "P24" thru_hole circle
			(at -2.70002 20.32)
			(size 1.1684 1.1684)
			(drill 0.762)
			(layers "*.Cu" "*.Mask")
			(remove_unused_layers no)
			(net "P12V")
			(clearance 0.0508)
			(thermal_gap 0.0508)
		)
		(pad "P25" thru_hole circle
			(at -2.70002 17.78)
			(size 1.1684 1.1684)
			(drill 0.762)
			(layers "*.Cu" "*.Mask")
			(remove_unused_layers no)
			(net "GND")
			(clearance 0.0508)
			(thermal_gap 0.0508)
		)
		(pad "P26" thru_hole circle
			(at -2.70002 15.24)
			(size 1.1684 1.1684)
			(drill 0.762)
			(layers "*.Cu" "*.Mask")
			(remove_unused_layers no)
			(net "GND")
			(clearance 0.0508)
			(thermal_gap 0.0508)
		)
		(pad "P27" thru_hole circle
			(at -2.70002 12.7)
			(size 1.1684 1.1684)
			(drill 0.762)
			(layers "*.Cu" "*.Mask")
			(remove_unused_layers no)
			(net "GND")
			(clearance 0.0508)
			(thermal_gap 0.0508)
		)
		(pad "P28" thru_hole circle
			(at -2.70002 10.16)
			(size 1.1684 1.1684)
			(drill 0.762)
			(layers "*.Cu" "*.Mask")
			(remove_unused_layers no)
			(net "GND")
			(clearance 0.0508)
			(thermal_gap 0.0508)
		)
		(pad "P29" thru_hole circle
			(at -2.70002 7.62)
			(size 1.1684 1.1684)
			(drill 0.762)
			(layers "*.Cu" "*.Mask")
			(remove_unused_layers no)
			(net "GND")
			(clearance 0.0508)
			(thermal_gap 0.0508)
		)
		(pad "P30" thru_hole circle
			(at -2.70002 5.08)
			(size 1.1684 1.1684)
			(drill 0.762)
			(layers "*.Cu" "*.Mask")
			(remove_unused_layers no)
			(net "GND")
			(clearance 0.0508)
			(thermal_gap 0.0508)
		)
		(pad "P31" thru_hole circle
			(at -2.70002 2.54)
			(size 1.1684 1.1684)
			(drill 0.762)
			(layers "*.Cu" "*.Mask")
			(remove_unused_layers no)
			(net "GND")
			(clearance 0.0508)
			(thermal_gap 0.0508)
		)
		(pad "P32" thru_hole circle
			(at -2.70002 0)
			(size 1.1684 1.1684)
			(drill 0.762)
			(layers "*.Cu" "*.Mask")
			(remove_unused_layers no)
			(net "GND")
			(clearance 0.0508)
			(thermal_gap 0.0508)
		)
		(pad "S1" thru_hole circle
			(at 0.55499 41.60012)
			(size 1.1684 1.1684)
			(drill 0.762)
			(layers "*.Cu" "*.Mask")
			(remove_unused_layers no)
			(net "T10_BLAD1_TXD")
			(clearance 0.0508)
			(thermal_gap 0.0508)
		)
		(pad "S2" thru_hole circle
			(at -0.71501 42.87012)
			(size 1.1684 1.1684)
			(drill 0.762)
			(layers "*.Cu" "*.Mask")
			(remove_unused_layers no)
			(net "T10_BLAD1_RXD")
			(clearance 0.0508)
			(thermal_gap 0.0508)
		)
		(pad "S3" thru_hole circle
			(at 0.55499 44.14012)
			(size 1.1684 1.1684)
			(drill 0.762)
			(layers "*.Cu" "*.Mask")
			(remove_unused_layers no)
			(net "T10_BLAD1_EN")
			(clearance 0.0508)
			(thermal_gap 0.0508)
		)
		(pad "S4" thru_hole circle
			(at -0.71501 45.41012)
			(size 1.1684 1.1684)
			(drill 0.762)
			(layers "*.Cu" "*.Mask")
			(remove_unused_layers no)
			(net "B19_PSU_ALERT_N")
			(clearance 0.0508)
			(thermal_gap 0.0508)
		)
		(pad "S5" thru_hole circle
			(at 0.55499 46.68012)
			(size 1.1684 1.1684)
			(drill 0.762)
			(layers "*.Cu" "*.Mask")
			(remove_unused_layers no)
			(net "T10_BLAD2_TXD")
			(clearance 0.0508)
			(thermal_gap 0.0508)
		)
		(pad "S6" thru_hole circle
			(at -0.71501 47.95012)
			(size 1.1684 1.1684)
			(drill 0.762)
			(layers "*.Cu" "*.Mask")
			(remove_unused_layers no)
			(net "T10_BLAD2_RXD")
			(clearance 0.0508)
			(thermal_gap 0.0508)
		)
		(pad "S7" thru_hole circle
			(at -3.25501 47.95012)
			(size 1.1684 1.1684)
			(drill 0.762)
			(layers "*.Cu" "*.Mask")
			(remove_unused_layers no)
			(net "T10_BLAD4_RXD")
			(clearance 0.0508)
			(thermal_gap 0.0508)
		)
		(pad "S8" thru_hole circle
			(at -1.98501 46.68012)
			(size 1.1684 1.1684)
			(drill 0.762)
			(layers "*.Cu" "*.Mask")
			(remove_unused_layers no)
			(net "T10_BLAD4_TXD")
			(clearance 0.0508)
			(thermal_gap 0.0508)
		)
		(pad "S9" thru_hole circle
			(at -3.25501 45.41012)
			(size 1.1684 1.1684)
			(drill 0.762)
			(layers "*.Cu" "*.Mask")
			(remove_unused_layers no)
			(net "B20_PSU_ALERT_N")
			(clearance 0.0508)
			(thermal_gap 0.0508)
		)
		(pad "S10" thru_hole circle
			(at -1.98501 44.14012)
			(size 1.1684 1.1684)
			(drill 0.762)
			(layers "*.Cu" "*.Mask")
			(remove_unused_layers no)
			(net "T10_BLAD3_EN")
			(clearance 0.0508)
			(thermal_gap 0.0508)
		)
		(pad "S11" thru_hole circle
			(at -3.25501 42.87012)
			(size 1.1684 1.1684)
			(drill 0.762)
			(layers "*.Cu" "*.Mask")
			(remove_unused_layers no)
			(net "T10_BLAD3_RXD")
			(clearance 0.0508)
			(thermal_gap 0.0508)
		)
		(pad "S12" thru_hole circle
			(at -1.98501 41.60012)
			(size 1.1684 1.1684)
			(drill 0.762)
			(layers "*.Cu" "*.Mask")
			(remove_unused_layers no)
			(net "T10_BLAD3_TXD")
			(clearance 0.0508)
			(thermal_gap 0.0508)
		)
		(zone
			(layer "F.Cu")
			(hatch none 0.5)
			(connect_pads
				(clearance 0)
			)
			(min_thickness 0.25)
			(keepout
				(tracks allowed)
				(vias not_allowed)
				(pads allowed)
				(copperpour not_allowed)
				(footprints allowed)
			)
			(placement
				(enabled no)
				(sheetname "")
			)
			(fill
				(thermal_gap 0.5)
				(thermal_bridge_width 0.5)
				(island_removal_mode 0)
			)
			(polygon
				(pts
					(xy 85.00999 -409.50388) (xy 92.65539 -409.50388) (xy 92.65539 -404.39848) (xy 85.00999 -404.39848)
					(xy 84.98459 -404.39848) (xy 84.98459 -409.50388)
				)
			)
		)
		(zone
			(layer "F.Cu")
			(hatch none 0.5)
			(connect_pads
				(clearance 0)
			)
			(min_thickness 0.25)
			(keepout
				(tracks allowed)
				(vias not_allowed)
				(pads allowed)
				(copperpour not_allowed)
				(footprints allowed)
			)
			(placement
				(enabled no)
				(sheetname "")
			)
			(fill
				(thermal_gap 0.5)
				(thermal_bridge_width 0.5)
				(island_removal_mode 0)
			)
			(polygon
				(pts
					(xy 43.37939 -404.98268) (xy 43.37939 -408.94508) (xy 82.77479 -408.94508) (xy 82.80019 -408.94508)
					(xy 82.80019 -404.98268) (xy 82.80019 -404.95728) (xy 43.37939 -404.95728)
				)
			)
		)
		(zone
			(layers "F.Cu" "B.Cu" "In1.Cu" "In2.Cu" "In3.Cu" "In4.Cu" "In5.Cu" "In6.Cu")
			(hatch none 0.5)
			(connect_pads
				(clearance 0)
			)
			(min_thickness 0.25)
			(keepout
				(tracks not_allowed)
				(vias allowed)
				(pads allowed)
				(copperpour not_allowed)
				(footprints allowed)
			)
			(placement
				(enabled no)
				(sheetname "")
			)
			(fill
				(thermal_gap 0.5)
				(thermal_bridge_width 0.5)
				(island_removal_mode 0)
			)
			(polygon
				(pts
					(arc
						(start 43.18 -406.96007)
						(mid 39.81958 -406.96007)
						(end 43.18 -406.96007)
					)
				)
			)
		)
		(zone
			(layers "F.Cu" "B.Cu" "In1.Cu" "In2.Cu" "In3.Cu" "In4.Cu" "In5.Cu" "In6.Cu")
			(hatch none 0.5)
			(connect_pads
				(clearance 0)
			)
			(min_thickness 0.25)
			(keepout
				(tracks not_allowed)
				(vias allowed)
				(pads allowed)
				(copperpour not_allowed)
				(footprints allowed)
			)
			(placement
				(enabled no)
				(sheetname "")
			)
			(fill
				(thermal_gap 0.5)
				(thermal_bridge_width 0.5)
				(island_removal_mode 0)
			)
			(polygon
				(pts
					(arc
						(start 96.52381 -408.31008)
						(mid 93.15577 -408.31008)
						(end 96.52381 -408.31008)
					)
				)
			)
		)
	)
	(footprint ""
		(layer "B.Cu")
		(at 44.03979 -363.86008 90)
		(property "Reference" "J15"
			(at 6.521196 -4.437888 0)
			(unlocked yes)
			(layer "B.SilkS")
			(effects
				(font
					(size 0.7874 0.5842)
					(thickness 0.1524)
				)
				(justify left mirror)
			)
		)
		(property "Value" ""
			(at 0 0 90)
			(layer "B.Fab")
			(effects
				(font
					(size 1.27 1.27)
				)
				(justify mirror)
			)
		)
		(duplicate_pad_numbers_are_jumpers no)
		(fp_line
			(start 5.275072 -13.910056)
			(end -7.975092 -13.910056)
			(stroke
				(width 0.1524)
				(type default)
			)
			(layer "F.SilkS")
		)
		(fp_line
			(start -7.975092 -13.910056)
			(end -7.975092 62.170056)
			(stroke
				(width 0.1524)
				(type default)
			)
			(layer "F.SilkS")
		)
		(fp_line
			(start 5.275072 62.170056)
			(end 5.275072 -13.910056)
			(stroke
				(width 0.1524)
				(type default)
			)
			(layer "F.SilkS")
		)
		(fp_line
			(start -7.975092 62.170056)
			(end 5.275072 62.170056)
			(stroke
				(width 0.1524)
				(type default)
			)
			(layer "F.SilkS")
		)
		(fp_line
			(start 5.275072 -13.910056)
			(end -7.975092 -13.910056)
			(stroke
				(width 0.1524)
				(type default)
			)
			(layer "B.SilkS")
		)
		(fp_line
			(start -7.975092 -13.910056)
			(end -7.975092 62.170056)
			(stroke
				(width 0.1524)
				(type default)
			)
			(layer "B.SilkS")
		)
		(fp_line
			(start 2.275078 -10.910062)
			(end 2.275078 59.170062)
			(stroke
				(width 0.1524)
				(type default)
			)
			(layer "B.SilkS")
		)
		(fp_line
			(start -4.975098 -10.910062)
			(end 2.275078 -10.910062)
			(stroke
				(width 0.1524)
				(type default)
			)
			(layer "B.SilkS")
		)
		(fp_line
			(start 2.275078 59.170062)
			(end -4.975098 59.170062)
			(stroke
				(width 0.1524)
				(type default)
			)
			(layer "B.SilkS")
		)
		(fp_line
			(start -4.975098 59.170062)
			(end -4.975098 -10.910062)
			(stroke
				(width 0.1524)
				(type default)
			)
			(layer "B.SilkS")
		)
		(fp_line
			(start 5.275072 62.170056)
			(end 5.275072 -13.910056)
			(stroke
				(width 0.1524)
				(type default)
			)
			(layer "B.SilkS")
		)
		(fp_line
			(start -7.975092 62.170056)
			(end 5.275072 62.170056)
			(stroke
				(width 0.1524)
				(type default)
			)
			(layer "B.SilkS")
		)
		(fp_poly
			(pts
				(xy 4.103878 -0.759206) (xy 4.103878 0.764794) (xy 2.579878 0.002794)
			)
			(stroke
				(width 0)
				(type default)
			)
			(fill yes)
			(layer "B.SilkS")
		)
		(fp_poly
			(pts
				(xy 2.275078 -10.910062) (xy 2.275078 59.170062) (xy -4.975098 59.170062) (xy -4.975098 -10.910062)
			)
			(stroke
				(width 0)
				(type default)
			)
			(fill no)
			(layer "B.CrtYd")
		)
		(fp_poly
			(pts
				(xy 1.1938 40.9702) (xy 1.1938 48.6156) (xy -3.9116 48.6156) (xy -3.9116 40.9702) (xy -3.9116 40.9448)
				(xy 1.1938 40.9448)
			)
			(stroke
				(width 0)
				(type default)
			)
			(fill no)
			(layer "F.CrtYd")
		)
		(fp_poly
			(pts
				(xy -3.3274 -0.6604) (xy 0.635 -0.6604) (xy 0.635 38.735) (xy 0.635 38.7604) (xy -3.3274 38.7604)
				(xy -3.3528 38.7604) (xy -3.3528 -0.6604)
			)
			(stroke
				(width 0)
				(type default)
			)
			(fill no)
			(layer "F.CrtYd")
		)
		(fp_poly
			(pts
				(arc
					(start -1.35001 -1.01219)
					(mid -1.35001 -4.06781)
					(end -1.35001 -1.01219)
				)
			)
			(stroke
				(width 0)
				(type default)
			)
			(fill no)
			(layer "F.CrtYd")
		)
		(fp_poly
			(pts
				(arc
					(start 0 52.33162)
					(mid 0 49.26838)
					(end 0 52.33162)
				)
			)
			(stroke
				(width 0)
				(type default)
			)
			(fill no)
			(layer "F.CrtYd")
		)
		(fp_line
			(start 2.275078 -10.910062)
			(end 2.275078 59.170062)
			(stroke
				(width 0.1)
				(type default)
			)
			(layer "B.Fab")
		)
		(fp_line
			(start -4.975098 -10.910062)
			(end 2.275078 -10.910062)
			(stroke
				(width 0.1)
				(type default)
			)
			(layer "B.Fab")
		)
		(fp_line
			(start 2.275078 59.170062)
			(end -4.975098 59.170062)
			(stroke
				(width 0.1)
				(type default)
			)
			(layer "B.Fab")
		)
		(fp_line
			(start -4.975098 59.170062)
			(end -4.975098 -10.910062)
			(stroke
				(width 0.1)
				(type default)
			)
			(layer "B.Fab")
		)
		(fp_poly
			(pts
				(xy 4.103878 -0.759206) (xy 4.103878 0.764794) (xy 2.579878 0.002794)
			)
			(stroke
				(width 0)
				(type default)
			)
			(fill yes)
			(layer "B.Fab")
		)
		(fp_line
			(start 5.275072 -13.910056)
			(end -7.975092 -13.910056)
			(stroke
				(width 0.1)
				(type default)
			)
			(layer "F.Fab")
		)
		(fp_line
			(start -7.975092 -13.910056)
			(end -7.975092 62.170056)
			(stroke
				(width 0.1)
				(type default)
			)
			(layer "F.Fab")
		)
		(fp_line
			(start 5.275072 62.170056)
			(end 5.275072 -13.910056)
			(stroke
				(width 0.1)
				(type default)
			)
			(layer "F.Fab")
		)
		(fp_line
			(start -7.975092 62.170056)
			(end 5.275072 62.170056)
			(stroke
				(width 0.1)
				(type default)
			)
			(layer "F.Fab")
		)
		(fp_text user "P32"
			(at -9.0043 0.13589 0)
			(unlocked yes)
			(layer "F.SilkS")
			(effects
				(font
					(size 0.7874 0.5842)
					(thickness 0.1524)
				)
			)
		)
		(fp_text user "P1"
			(at 6.119622 1.773428 0)
			(unlocked yes)
			(layer "F.SilkS")
			(effects
				(font
					(size 0.7874 0.5842)
					(thickness 0.1524)
				)
			)
		)
		(fp_text user "PRESS-FIT"
			(at -9.510014 14.10081 0)
			(unlocked yes)
			(layer "F.SilkS")
			(effects
				(font
					(size 0.7874 0.5842)
					(thickness 0.1524)
				)
				(justify left)
			)
		)
		(fp_text user "P17"
			(at -9.337294 37.89553 0)
			(unlocked yes)
			(layer "F.SilkS")
			(effects
				(font
					(size 0.7874 0.5842)
					(thickness 0.1524)
				)
			)
		)
		(fp_text user "P16"
			(at 5.934202 38.194488 0)
			(unlocked yes)
			(layer "F.SilkS")
			(effects
				(font
					(size 0.7874 0.5842)
					(thickness 0.1524)
				)
			)
		)
		(fp_text user "S12"
			(at -9.223248 41.09339 0)
			(unlocked yes)
			(layer "F.SilkS")
			(effects
				(font
					(size 0.7874 0.5842)
					(thickness 0.1524)
				)
			)
		)
		(fp_text user "S1"
			(at 6.25602 41.568624 0)
			(unlocked yes)
			(layer "F.SilkS")
			(effects
				(font
					(size 0.7874 0.5842)
					(thickness 0.1524)
				)
			)
		)
		(fp_text user "S7"
			(at -9.309608 47.565564 0)
			(unlocked yes)
			(layer "F.SilkS")
			(effects
				(font
					(size 0.7874 0.5842)
					(thickness 0.1524)
				)
			)
		)
		(fp_text user "S6"
			(at 6.055106 47.903384 0)
			(unlocked yes)
			(layer "F.SilkS")
			(effects
				(font
					(size 0.7874 0.5842)
					(thickness 0.1524)
				)
			)
		)
		(fp_text user "P1"
			(at 2.937256 -1.453642 0)
			(unlocked yes)
			(layer "B.SilkS")
			(effects
				(font
					(size 0.7874 0.5842)
					(thickness 0.1524)
				)
				(justify mirror)
			)
		)
		(fp_text user "P32"
			(at -5.914644 -0.221234 0)
			(unlocked yes)
			(layer "B.SilkS")
			(effects
				(font
					(size 0.7874 0.5842)
					(thickness 0.1524)
				)
				(justify mirror)
			)
		)
		(fp_text user "PRESS-FIT"
			(at -7.18947 29.8831 0)
			(unlocked yes)
			(layer "B.SilkS")
			(effects
				(font
					(size 0.7874 0.5842)
					(thickness 0.1524)
				)
				(justify left mirror)
			)
		)
		(fp_text user "P16"
			(at 2.988564 37.7317 0)
			(unlocked yes)
			(layer "B.SilkS")
			(effects
				(font
					(size 0.7874 0.5842)
					(thickness 0.1524)
				)
				(justify mirror)
			)
		)
		(fp_text user "P17"
			(at -6.012688 37.821616 0)
			(unlocked yes)
			(layer "B.SilkS")
			(effects
				(font
					(size 0.7874 0.5842)
					(thickness 0.1524)
				)
				(justify mirror)
			)
		)
		(fp_text user "S1"
			(at 3.051556 41.674542 0)
			(unlocked yes)
			(layer "B.SilkS")
			(effects
				(font
					(size 0.7874 0.5842)
					(thickness 0.1524)
				)
				(justify mirror)
			)
		)
		(fp_text user "S12"
			(at -5.871972 42.408348 0)
			(unlocked yes)
			(layer "B.SilkS")
			(effects
				(font
					(size 0.7874 0.5842)
					(thickness 0.1524)
				)
				(justify mirror)
			)
		)
		(fp_text user "S6"
			(at 3.014218 47.541688 0)
			(unlocked yes)
			(layer "B.SilkS")
			(effects
				(font
					(size 0.7874 0.5842)
					(thickness 0.1524)
				)
				(justify mirror)
			)
		)
		(fp_text user "S7"
			(at -6.020562 47.973742 0)
			(unlocked yes)
			(layer "B.SilkS")
			(effects
				(font
					(size 0.7874 0.5842)
					(thickness 0.1524)
				)
				(justify mirror)
			)
		)
		(fp_text user "P1"
			(at 3.108452 -1.27 180)
			(unlocked yes)
			(layer "B.Fab")
			(effects
				(font
					(size 0.7874 0.5842)
					(thickness 0.000001)
				)
				(justify mirror)
			)
		)
		(fp_text user "P32"
			(at -5.781548 -0.0508 180)
			(unlocked yes)
			(layer "B.Fab")
			(effects
				(font
					(size 0.7874 0.5842)
					(thickness 0.000001)
				)
				(justify mirror)
			)
		)
		(fp_text user "PRESS-FIT"
			(at -6.82371 29.8831 0)
			(unlocked yes)
			(layer "B.Fab")
			(effects
				(font
					(size 1.6002 1.1938)
					(thickness 0.000001)
				)
				(justify left mirror)
			)
		)
		(fp_text user "P17"
			(at -5.72135 38.0746 180)
			(unlocked yes)
			(layer "B.Fab")
			(effects
				(font
					(size 0.7874 0.5842)
					(thickness 0.000001)
				)
				(justify mirror)
			)
		)
		(fp_text user "P16"
			(at 3.159252 38.3794 180)
			(unlocked yes)
			(layer "B.Fab")
			(effects
				(font
					(size 0.7874 0.5842)
					(thickness 0.000001)
				)
				(justify mirror)
			)
		)
		(fp_text user "S12"
			(at -5.79374 41.42232 180)
			(unlocked yes)
			(layer "B.Fab")
			(effects
				(font
					(size 0.7874 0.5842)
					(thickness 0.000001)
				)
				(justify mirror)
			)
		)
		(fp_text user "S1"
			(at 3.09626 41.656 180)
			(unlocked yes)
			(layer "B.Fab")
			(effects
				(font
					(size 0.7874 0.5842)
					(thickness 0.000001)
				)
				(justify mirror)
			)
		)
		(fp_text user "S6"
			(at 3.133852 48.0822 180)
			(unlocked yes)
			(layer "B.Fab")
			(effects
				(font
					(size 0.7874 0.5842)
					(thickness 0.000001)
				)
				(justify mirror)
			)
		)
		(fp_text user "S7"
			(at -5.781548 48.0822 180)
			(unlocked yes)
			(layer "B.Fab")
			(effects
				(font
					(size 0.7874 0.5842)
					(thickness 0.000001)
				)
				(justify mirror)
			)
		)
		(fp_text user "P32"
			(at -4.071112 -0.0762 180)
			(unlocked yes)
			(layer "F.Fab")
			(effects
				(font
					(size 0.7874 0.5842)
					(thickness 0.000001)
				)
			)
		)
		(fp_text user "P1"
			(at 1.516888 0 180)
			(unlocked yes)
			(layer "F.Fab")
			(effects
				(font
					(size 0.7874 0.5842)
					(thickness 0.000001)
				)
			)
		)
		(fp_text user "PRESS-FIT"
			(at -6.762496 16.251428 0)
			(unlocked yes)
			(layer "F.Fab")
			(effects
				(font
					(size 1.6002 1.1938)
					(thickness 0.000001)
				)
				(justify left)
			)
		)
		(fp_text user "P17"
			(at -4.366768 38.227 180)
			(unlocked yes)
			(layer "F.Fab")
			(effects
				(font
					(size 0.7874 0.5842)
					(thickness 0.000001)
				)
			)
		)
		(fp_text user "P16"
			(at 2.228088 38.354 180)
			(unlocked yes)
			(layer "F.Fab")
			(effects
				(font
					(size 0.7874 0.5842)
					(thickness 0.000001)
				)
			)
		)
		(fp_text user "S12"
			(at -4.362958 41.09212 180)
			(unlocked yes)
			(layer "F.Fab")
			(effects
				(font
					(size 0.7874 0.5842)
					(thickness 0.000001)
				)
			)
		)
		(fp_text user "S1"
			(at 2.164842 41.6306 180)
			(unlocked yes)
			(layer "F.Fab")
			(effects
				(font
					(size 0.7874 0.5842)
					(thickness 0.000001)
				)
			)
		)
		(fp_text user "S6"
			(at 1.923288 48.133 180)
			(unlocked yes)
			(layer "F.Fab")
			(effects
				(font
					(size 0.7874 0.5842)
					(thickness 0.000001)
				)
			)
		)
		(fp_text user "S7"
			(at -4.426712 48.2346 180)
			(unlocked yes)
			(layer "F.Fab")
			(effects
				(font
					(size 0.7874 0.5842)
					(thickness 0.000001)
				)
			)
		)
		(pad "" np_thru_hole circle
			(at -1.35001 -2.54)
			(size 2.5146 2.5146)
			(drill 2.5146)
			(layers "*.Cu" "*.Mask")
			(clearance 0.381)
			(thermal_gap 0.381)
		)
		(pad "" np_thru_hole circle
			(at 0 50.8)
			(size 2.5146 2.5146)
			(drill 2.5146)
			(layers "*.Cu" "*.Mask")
			(clearance 0.381)
			(thermal_gap 0.381)
		)
		(pad "P1" thru_hole rect
			(at 0 0)
			(size 1.1684 1.1684)
			(drill 0.762)
			(layers "*.Cu" "*.Mask")
			(remove_unused_layers no)
			(net "GND")
			(clearance 0.0508)
			(padstack
				(mode front_inner_back)
				(layer "Inner"
					(shape circle)
					(size 1.1684 1.1684)
					(clearance 0.0508)
				)
				(layer "B.Cu"
					(shape rect)
					(size 1.1684 1.1684)
					(thermal_gap 0.0508)
					(clearance 0.0508)
				)
			)
		)
		(pad "P2" thru_hole circle
			(at 0 2.54)
			(size 1.1684 1.1684)
			(drill 0.762)
			(layers "*.Cu" "*.Mask")
			(remove_unused_layers no)
			(net "GND")
			(clearance 0.0508)
			(thermal_gap 0.0508)
		)
		(pad "P3" thru_hole circle
			(at 0 5.08)
			(size 1.1684 1.1684)
			(drill 0.762)
			(layers "*.Cu" "*.Mask")
			(remove_unused_layers no)
			(net "GND")
			(clearance 0.0508)
			(thermal_gap 0.0508)
		)
		(pad "P4" thru_hole circle
			(at 0 7.62)
			(size 1.1684 1.1684)
			(drill 0.762)
			(layers "*.Cu" "*.Mask")
			(remove_unused_layers no)
			(net "GND")
			(clearance 0.0508)
			(thermal_gap 0.0508)
		)
		(pad "P5" thru_hole circle
			(at 0 10.16)
			(size 1.1684 1.1684)
			(drill 0.762)
			(layers "*.Cu" "*.Mask")
			(remove_unused_layers no)
			(net "GND")
			(clearance 0.0508)
			(thermal_gap 0.0508)
		)
		(pad "P6" thru_hole circle
			(at 0 12.7)
			(size 1.1684 1.1684)
			(drill 0.762)
			(layers "*.Cu" "*.Mask")
			(remove_unused_layers no)
			(net "GND")
			(clearance 0.0508)
			(thermal_gap 0.0508)
		)
		(pad "P7" thru_hole circle
			(at 0 15.24)
			(size 1.1684 1.1684)
			(drill 0.762)
			(layers "*.Cu" "*.Mask")
			(remove_unused_layers no)
			(net "GND")
			(clearance 0.0508)
			(thermal_gap 0.0508)
		)
		(pad "P8" thru_hole circle
			(at 0 17.78)
			(size 1.1684 1.1684)
			(drill 0.762)
			(layers "*.Cu" "*.Mask")
			(remove_unused_layers no)
			(net "GND")
			(clearance 0.0508)
			(thermal_gap 0.0508)
		)
		(pad "P9" thru_hole circle
			(at 0 20.32)
			(size 1.1684 1.1684)
			(drill 0.762)
			(layers "*.Cu" "*.Mask")
			(remove_unused_layers no)
			(net "P12V")
			(clearance 0.0508)
			(thermal_gap 0.0508)
		)
		(pad "P10" thru_hole circle
			(at 0 22.86)
			(size 1.1684 1.1684)
			(drill 0.762)
			(layers "*.Cu" "*.Mask")
			(remove_unused_layers no)
			(net "P12V")
			(clearance 0.0508)
			(thermal_gap 0.0508)
		)
		(pad "P11" thru_hole circle
			(at 0 25.4)
			(size 1.1684 1.1684)
			(drill 0.762)
			(layers "*.Cu" "*.Mask")
			(remove_unused_layers no)
			(net "P12V")
			(clearance 0.0508)
			(thermal_gap 0.0508)
		)
		(pad "P12" thru_hole circle
			(at 0 27.94)
			(size 1.1684 1.1684)
			(drill 0.762)
			(layers "*.Cu" "*.Mask")
			(remove_unused_layers no)
			(net "P12V")
			(clearance 0.0508)
			(thermal_gap 0.0508)
		)
		(pad "P13" thru_hole circle
			(at 0 30.48)
			(size 1.1684 1.1684)
			(drill 0.762)
			(layers "*.Cu" "*.Mask")
			(remove_unused_layers no)
			(net "P12V")
			(clearance 0.0508)
			(thermal_gap 0.0508)
		)
		(pad "P14" thru_hole circle
			(at 0 33.02)
			(size 1.1684 1.1684)
			(drill 0.762)
			(layers "*.Cu" "*.Mask")
			(remove_unused_layers no)
			(net "P12V")
			(clearance 0.0508)
			(thermal_gap 0.0508)
		)
		(pad "P15" thru_hole circle
			(at 0 35.56)
			(size 1.1684 1.1684)
			(drill 0.762)
			(layers "*.Cu" "*.Mask")
			(remove_unused_layers no)
			(net "P12V")
			(clearance 0.0508)
			(thermal_gap 0.0508)
		)
		(pad "P16" thru_hole circle
			(at 0 38.1)
			(size 1.1684 1.1684)
			(drill 0.762)
			(layers "*.Cu" "*.Mask")
			(remove_unused_layers no)
			(net "P12V")
			(clearance 0.0508)
			(thermal_gap 0.0508)
		)
		(pad "P17" thru_hole circle
			(at -2.70002 38.1)
			(size 1.1684 1.1684)
			(drill 0.762)
			(layers "*.Cu" "*.Mask")
			(remove_unused_layers no)
			(net "P12V")
			(clearance 0.0508)
			(thermal_gap 0.0508)
		)
		(pad "P18" thru_hole circle
			(at -2.70002 35.56)
			(size 1.1684 1.1684)
			(drill 0.762)
			(layers "*.Cu" "*.Mask")
			(remove_unused_layers no)
			(net "P12V")
			(clearance 0.0508)
			(thermal_gap 0.0508)
		)
		(pad "P19" thru_hole circle
			(at -2.70002 33.02)
			(size 1.1684 1.1684)
			(drill 0.762)
			(layers "*.Cu" "*.Mask")
			(remove_unused_layers no)
			(net "P12V")
			(clearance 0.0508)
			(thermal_gap 0.0508)
		)
		(pad "P20" thru_hole circle
			(at -2.70002 30.48)
			(size 1.1684 1.1684)
			(drill 0.762)
			(layers "*.Cu" "*.Mask")
			(remove_unused_layers no)
			(net "P12V")
			(clearance 0.0508)
			(thermal_gap 0.0508)
		)
		(pad "P21" thru_hole circle
			(at -2.70002 27.94)
			(size 1.1684 1.1684)
			(drill 0.762)
			(layers "*.Cu" "*.Mask")
			(remove_unused_layers no)
			(net "P12V")
			(clearance 0.0508)
			(thermal_gap 0.0508)
		)
		(pad "P22" thru_hole circle
			(at -2.70002 25.4)
			(size 1.1684 1.1684)
			(drill 0.762)
			(layers "*.Cu" "*.Mask")
			(remove_unused_layers no)
			(net "P12V")
			(clearance 0.0508)
			(thermal_gap 0.0508)
		)
		(pad "P23" thru_hole circle
			(at -2.70002 22.86)
			(size 1.1684 1.1684)
			(drill 0.762)
			(layers "*.Cu" "*.Mask")
			(remove_unused_layers no)
			(net "P12V")
			(clearance 0.0508)
			(thermal_gap 0.0508)
		)
		(pad "P24" thru_hole circle
			(at -2.70002 20.32)
			(size 1.1684 1.1684)
			(drill 0.762)
			(layers "*.Cu" "*.Mask")
			(remove_unused_layers no)
			(net "P12V")
			(clearance 0.0508)
			(thermal_gap 0.0508)
		)
		(pad "P25" thru_hole circle
			(at -2.70002 17.78)
			(size 1.1684 1.1684)
			(drill 0.762)
			(layers "*.Cu" "*.Mask")
			(remove_unused_layers no)
			(net "GND")
			(clearance 0.0508)
			(thermal_gap 0.0508)
		)
		(pad "P26" thru_hole circle
			(at -2.70002 15.24)
			(size 1.1684 1.1684)
			(drill 0.762)
			(layers "*.Cu" "*.Mask")
			(remove_unused_layers no)
			(net "GND")
			(clearance 0.0508)
			(thermal_gap 0.0508)
		)
		(pad "P27" thru_hole circle
			(at -2.70002 12.7)
			(size 1.1684 1.1684)
			(drill 0.762)
			(layers "*.Cu" "*.Mask")
			(remove_unused_layers no)
			(net "GND")
			(clearance 0.0508)
			(thermal_gap 0.0508)
		)
		(pad "P28" thru_hole circle
			(at -2.70002 10.16)
			(size 1.1684 1.1684)
			(drill 0.762)
			(layers "*.Cu" "*.Mask")
			(remove_unused_layers no)
			(net "GND")
			(clearance 0.0508)
			(thermal_gap 0.0508)
		)
		(pad "P29" thru_hole circle
			(at -2.70002 7.62)
			(size 1.1684 1.1684)
			(drill 0.762)
			(layers "*.Cu" "*.Mask")
			(remove_unused_layers no)
			(net "GND")
			(clearance 0.0508)
			(thermal_gap 0.0508)
		)
		(pad "P30" thru_hole circle
			(at -2.70002 5.08)
			(size 1.1684 1.1684)
			(drill 0.762)
			(layers "*.Cu" "*.Mask")
			(remove_unused_layers no)
			(net "GND")
			(clearance 0.0508)
			(thermal_gap 0.0508)
		)
		(pad "P31" thru_hole circle
			(at -2.70002 2.54)
			(size 1.1684 1.1684)
			(drill 0.762)
			(layers "*.Cu" "*.Mask")
			(remove_unused_layers no)
			(net "GND")
			(clearance 0.0508)
			(thermal_gap 0.0508)
		)
		(pad "P32" thru_hole circle
			(at -2.70002 0)
			(size 1.1684 1.1684)
			(drill 0.762)
			(layers "*.Cu" "*.Mask")
			(remove_unused_layers no)
			(net "GND")
			(clearance 0.0508)
			(thermal_gap 0.0508)
		)
		(pad "S1" thru_hole circle
			(at 0.55499 41.60012)
			(size 1.1684 1.1684)
			(drill 0.762)
			(layers "*.Cu" "*.Mask")
			(remove_unused_layers no)
			(net "T9_BLAD1_TXD")
			(clearance 0.0508)
			(thermal_gap 0.0508)
		)
		(pad "S2" thru_hole circle
			(at -0.71501 42.87012)
			(size 1.1684 1.1684)
			(drill 0.762)
			(layers "*.Cu" "*.Mask")
			(remove_unused_layers no)
			(net "T9_BLAD1_RXD")
			(clearance 0.0508)
			(thermal_gap 0.0508)
		)
		(pad "S3" thru_hole circle
			(at 0.55499 44.14012)
			(size 1.1684 1.1684)
			(drill 0.762)
			(layers "*.Cu" "*.Mask")
			(remove_unused_layers no)
			(net "T9_BLAD1_EN")
			(clearance 0.0508)
			(thermal_gap 0.0508)
		)
		(pad "S4" thru_hole circle
			(at -0.71501 45.41012)
			(size 1.1684 1.1684)
			(drill 0.762)
			(layers "*.Cu" "*.Mask")
			(remove_unused_layers no)
			(net "B17_PSU_ALERT_N")
			(clearance 0.0508)
			(thermal_gap 0.0508)
		)
		(pad "S5" thru_hole circle
			(at 0.55499 46.68012)
			(size 1.1684 1.1684)
			(drill 0.762)
			(layers "*.Cu" "*.Mask")
			(remove_unused_layers no)
			(net "T9_BLAD2_TXD")
			(clearance 0.0508)
			(thermal_gap 0.0508)
		)
		(pad "S6" thru_hole circle
			(at -0.71501 47.95012)
			(size 1.1684 1.1684)
			(drill 0.762)
			(layers "*.Cu" "*.Mask")
			(remove_unused_layers no)
			(net "T9_BLAD2_RXD")
			(clearance 0.0508)
			(thermal_gap 0.0508)
		)
		(pad "S7" thru_hole circle
			(at -3.25501 47.95012)
			(size 1.1684 1.1684)
			(drill 0.762)
			(layers "*.Cu" "*.Mask")
			(remove_unused_layers no)
			(net "T9_BLAD4_RXD")
			(clearance 0.0508)
			(thermal_gap 0.0508)
		)
		(pad "S8" thru_hole circle
			(at -1.98501 46.68012)
			(size 1.1684 1.1684)
			(drill 0.762)
			(layers "*.Cu" "*.Mask")
			(remove_unused_layers no)
			(net "T9_BLAD4_TXD")
			(clearance 0.0508)
			(thermal_gap 0.0508)
		)
		(pad "S9" thru_hole circle
			(at -3.25501 45.41012)
			(size 1.1684 1.1684)
			(drill 0.762)
			(layers "*.Cu" "*.Mask")
			(remove_unused_layers no)
			(net "B18_PSU_ALERT_N")
			(clearance 0.0508)
			(thermal_gap 0.0508)
		)
		(pad "S10" thru_hole circle
			(at -1.98501 44.14012)
			(size 1.1684 1.1684)
			(drill 0.762)
			(layers "*.Cu" "*.Mask")
			(remove_unused_layers no)
			(net "T9_BLAD3_EN")
			(clearance 0.0508)
			(thermal_gap 0.0508)
		)
		(pad "S11" thru_hole circle
			(at -3.25501 42.87012)
			(size 1.1684 1.1684)
			(drill 0.762)
			(layers "*.Cu" "*.Mask")
			(remove_unused_layers no)
			(net "T9_BLAD3_RXD")
			(clearance 0.0508)
			(thermal_gap 0.0508)
		)
		(pad "S12" thru_hole circle
			(at -1.98501 41.60012)
			(size 1.1684 1.1684)
			(drill 0.762)
			(layers "*.Cu" "*.Mask")
			(remove_unused_layers no)
			(net "T9_BLAD3_TXD")
			(clearance 0.0508)
			(thermal_gap 0.0508)
		)
		(zone
			(layer "F.Cu")
			(hatch none 0.5)
			(connect_pads
				(clearance 0)
			)
			(min_thickness 0.25)
			(keepout
				(tracks allowed)
				(vias not_allowed)
				(pads allowed)
				(copperpour not_allowed)
				(footprints allowed)
			)
			(placement
				(enabled no)
				(sheetname "")
			)
			(fill
				(thermal_gap 0.5)
				(thermal_bridge_width 0.5)
				(island_removal_mode 0)
			)
			(polygon
				(pts
					(xy 85.00999 -365.05388) (xy 92.65539 -365.05388) (xy 92.65539 -359.94848) (xy 85.00999 -359.94848)
					(xy 84.98459 -359.94848) (xy 84.98459 -365.05388)
				)
			)
		)
		(zone
			(layer "F.Cu")
			(hatch none 0.5)
			(connect_pads
				(clearance 0)
			)
			(min_thickness 0.25)
			(keepout
				(tracks allowed)
				(vias not_allowed)
				(pads allowed)
				(copperpour not_allowed)
				(footprints allowed)
			)
			(placement
				(enabled no)
				(sheetname "")
			)
			(fill
				(thermal_gap 0.5)
				(thermal_bridge_width 0.5)
				(island_removal_mode 0)
			)
			(polygon
				(pts
					(xy 43.37939 -360.53268) (xy 43.37939 -364.49508) (xy 82.77479 -364.49508) (xy 82.80019 -364.49508)
					(xy 82.80019 -360.53268) (xy 82.80019 -360.50728) (xy 43.37939 -360.50728)
				)
			)
		)
		(zone
			(layers "F.Cu" "B.Cu" "In1.Cu" "In2.Cu" "In3.Cu" "In4.Cu" "In5.Cu" "In6.Cu")
			(hatch none 0.5)
			(connect_pads
				(clearance 0)
			)
			(min_thickness 0.25)
			(keepout
				(tracks not_allowed)
				(vias allowed)
				(pads allowed)
				(copperpour not_allowed)
				(footprints allowed)
			)
			(placement
				(enabled no)
				(sheetname "")
			)
			(fill
				(thermal_gap 0.5)
				(thermal_bridge_width 0.5)
				(island_removal_mode 0)
			)
			(polygon
				(pts
					(arc
						(start 43.18 -362.51007)
						(mid 39.81958 -362.51007)
						(end 43.18 -362.51007)
					)
				)
			)
		)
		(zone
			(layers "F.Cu" "B.Cu" "In1.Cu" "In2.Cu" "In3.Cu" "In4.Cu" "In5.Cu" "In6.Cu")
			(hatch none 0.5)
			(connect_pads
				(clearance 0)
			)
			(min_thickness 0.25)
			(keepout
				(tracks not_allowed)
				(vias allowed)
				(pads allowed)
				(copperpour not_allowed)
				(footprints allowed)
			)
			(placement
				(enabled no)
				(sheetname "")
			)
			(fill
				(thermal_gap 0.5)
				(thermal_bridge_width 0.5)
				(island_removal_mode 0)
			)
			(polygon
				(pts
					(arc
						(start 96.52381 -363.86008)
						(mid 93.15577 -363.86008)
						(end 96.52381 -363.86008)
					)
				)
			)
		)
	)
	(footprint ""
		(layer "B.Cu")
		(at 44.03979 -452.76008 90)
		(property "Reference" "J17"
			(at 6.342888 1.323848 0)
			(unlocked yes)
			(layer "B.SilkS")
			(effects
				(font
					(size 0.7874 0.5842)
					(thickness 0.1524)
				)
				(justify left mirror)
			)
		)
		(property "Value" ""
			(at 0 0 90)
			(layer "B.Fab")
			(effects
				(font
					(size 1.27 1.27)
				)
				(justify mirror)
			)
		)
		(duplicate_pad_numbers_are_jumpers no)
		(fp_line
			(start 5.275072 -13.910056)
			(end -7.975092 -13.910056)
			(stroke
				(width 0.1524)
				(type default)
			)
			(layer "F.SilkS")
		)
		(fp_line
			(start -7.975092 -13.910056)
			(end -7.975092 62.170056)
			(stroke
				(width 0.1524)
				(type default)
			)
			(layer "F.SilkS")
		)
		(fp_line
			(start 5.275072 62.170056)
			(end 5.275072 -13.910056)
			(stroke
				(width 0.1524)
				(type default)
			)
			(layer "F.SilkS")
		)
		(fp_line
			(start -7.975092 62.170056)
			(end 5.275072 62.170056)
			(stroke
				(width 0.1524)
				(type default)
			)
			(layer "F.SilkS")
		)
		(fp_line
			(start 5.275072 -13.910056)
			(end -7.975092 -13.910056)
			(stroke
				(width 0.1524)
				(type default)
			)
			(layer "B.SilkS")
		)
		(fp_line
			(start -7.975092 -13.910056)
			(end -7.975092 62.170056)
			(stroke
				(width 0.1524)
				(type default)
			)
			(layer "B.SilkS")
		)
		(fp_line
			(start 2.275078 -10.910062)
			(end 2.275078 59.170062)
			(stroke
				(width 0.1524)
				(type default)
			)
			(layer "B.SilkS")
		)
		(fp_line
			(start -4.975098 -10.910062)
			(end 2.275078 -10.910062)
			(stroke
				(width 0.1524)
				(type default)
			)
			(layer "B.SilkS")
		)
		(fp_line
			(start 2.275078 59.170062)
			(end -4.975098 59.170062)
			(stroke
				(width 0.1524)
				(type default)
			)
			(layer "B.SilkS")
		)
		(fp_line
			(start -4.975098 59.170062)
			(end -4.975098 -10.910062)
			(stroke
				(width 0.1524)
				(type default)
			)
			(layer "B.SilkS")
		)
		(fp_line
			(start 5.275072 62.170056)
			(end 5.275072 -13.910056)
			(stroke
				(width 0.1524)
				(type default)
			)
			(layer "B.SilkS")
		)
		(fp_line
			(start -7.975092 62.170056)
			(end 5.275072 62.170056)
			(stroke
				(width 0.1524)
				(type default)
			)
			(layer "B.SilkS")
		)
		(fp_poly
			(pts
				(xy 4.103878 -0.759206) (xy 4.103878 0.764794) (xy 2.579878 0.002794)
			)
			(stroke
				(width 0)
				(type default)
			)
			(fill yes)
			(layer "B.SilkS")
		)
		(fp_poly
			(pts
				(xy 2.275078 -10.910062) (xy 2.275078 59.170062) (xy -4.975098 59.170062) (xy -4.975098 -10.910062)
			)
			(stroke
				(width 0)
				(type default)
			)
			(fill no)
			(layer "B.CrtYd")
		)
		(fp_poly
			(pts
				(xy 1.1938 40.9702) (xy 1.1938 48.6156) (xy -3.9116 48.6156) (xy -3.9116 40.9702) (xy -3.9116 40.9448)
				(xy 1.1938 40.9448)
			)
			(stroke
				(width 0)
				(type default)
			)
			(fill no)
			(layer "F.CrtYd")
		)
		(fp_poly
			(pts
				(xy -3.3274 -0.6604) (xy 0.635 -0.6604) (xy 0.635 38.735) (xy 0.635 38.7604) (xy -3.3274 38.7604)
				(xy -3.3528 38.7604) (xy -3.3528 -0.6604)
			)
			(stroke
				(width 0)
				(type default)
			)
			(fill no)
			(layer "F.CrtYd")
		)
		(fp_poly
			(pts
				(arc
					(start -1.35001 -1.01219)
					(mid -1.35001 -4.06781)
					(end -1.35001 -1.01219)
				)
			)
			(stroke
				(width 0)
				(type default)
			)
			(fill no)
			(layer "F.CrtYd")
		)
		(fp_poly
			(pts
				(arc
					(start 0 52.33162)
					(mid 0 49.26838)
					(end 0 52.33162)
				)
			)
			(stroke
				(width 0)
				(type default)
			)
			(fill no)
			(layer "F.CrtYd")
		)
		(fp_line
			(start 2.275078 -10.910062)
			(end 2.275078 59.170062)
			(stroke
				(width 0.1)
				(type default)
			)
			(layer "B.Fab")
		)
		(fp_line
			(start -4.975098 -10.910062)
			(end 2.275078 -10.910062)
			(stroke
				(width 0.1)
				(type default)
			)
			(layer "B.Fab")
		)
		(fp_line
			(start 2.275078 59.170062)
			(end -4.975098 59.170062)
			(stroke
				(width 0.1)
				(type default)
			)
			(layer "B.Fab")
		)
		(fp_line
			(start -4.975098 59.170062)
			(end -4.975098 -10.910062)
			(stroke
				(width 0.1)
				(type default)
			)
			(layer "B.Fab")
		)
		(fp_poly
			(pts
				(xy 4.103878 -0.759206) (xy 4.103878 0.764794) (xy 2.579878 0.002794)
			)
			(stroke
				(width 0)
				(type default)
			)
			(fill yes)
			(layer "B.Fab")
		)
		(fp_line
			(start 5.275072 -13.910056)
			(end -7.975092 -13.910056)
			(stroke
				(width 0.1)
				(type default)
			)
			(layer "F.Fab")
		)
		(fp_line
			(start -7.975092 -13.910056)
			(end -7.975092 62.170056)
			(stroke
				(width 0.1)
				(type default)
			)
			(layer "F.Fab")
		)
		(fp_line
			(start 5.275072 62.170056)
			(end 5.275072 -13.910056)
			(stroke
				(width 0.1)
				(type default)
			)
			(layer "F.Fab")
		)
		(fp_line
			(start -7.975092 62.170056)
			(end 5.275072 62.170056)
			(stroke
				(width 0.1)
				(type default)
			)
			(layer "F.Fab")
		)
		(fp_text user "P32"
			(at -4.197096 -0.0254 0)
			(unlocked yes)
			(layer "F.SilkS")
			(effects
				(font
					(size 0.7874 0.5842)
					(thickness 0.1524)
				)
			)
		)
		(fp_text user "P1"
			(at 1.519936 0.06858 0)
			(unlocked yes)
			(layer "F.SilkS")
			(effects
				(font
					(size 0.7874 0.5842)
					(thickness 0.1524)
				)
			)
		)
		(fp_text user "PRESS-FIT"
			(at -9.413748 16.821912 0)
			(unlocked yes)
			(layer "F.SilkS")
			(effects
				(font
					(size 0.7874 0.5842)
					(thickness 0.1524)
				)
				(justify left)
			)
		)
		(fp_text user "P17"
			(at -9.424924 37.42436 0)
			(unlocked yes)
			(layer "F.SilkS")
			(effects
				(font
					(size 0.7874 0.5842)
					(thickness 0.1524)
				)
			)
		)
		(fp_text user "P16"
			(at 6.03758 39.340028 0)
			(unlocked yes)
			(layer "F.SilkS")
			(effects
				(font
					(size 0.7874 0.5842)
					(thickness 0.1524)
				)
			)
		)
		(fp_text user "S12"
			(at -9.360662 40.654224 0)
			(unlocked yes)
			(layer "F.SilkS")
			(effects
				(font
					(size 0.7874 0.5842)
					(thickness 0.1524)
				)
			)
		)
		(fp_text user "S1"
			(at 6.61162 42.942002 0)
			(unlocked yes)
			(layer "F.SilkS")
			(effects
				(font
					(size 0.7874 0.5842)
					(thickness 0.1524)
				)
			)
		)
		(fp_text user "S7"
			(at -9.467088 47.575216 0)
			(unlocked yes)
			(layer "F.SilkS")
			(effects
				(font
					(size 0.7874 0.5842)
					(thickness 0.1524)
				)
			)
		)
		(fp_text user "S6"
			(at 6.098286 48.259238 0)
			(unlocked yes)
			(layer "F.SilkS")
			(effects
				(font
					(size 0.7874 0.5842)
					(thickness 0.1524)
				)
			)
		)
		(fp_text user "P1"
			(at 3.034538 -1.521714 0)
			(unlocked yes)
			(layer "B.SilkS")
			(effects
				(font
					(size 0.7874 0.5842)
					(thickness 0.1524)
				)
				(justify mirror)
			)
		)
		(fp_text user "P32"
			(at -5.885688 0.255524 0)
			(unlocked yes)
			(layer "B.SilkS")
			(effects
				(font
					(size 0.7874 0.5842)
					(thickness 0.1524)
				)
				(justify mirror)
			)
		)
		(fp_text user "PRESS-FIT"
			(at -7.18947 29.8831 0)
			(unlocked yes)
			(layer "B.SilkS")
			(effects
				(font
					(size 0.7874 0.5842)
					(thickness 0.1524)
				)
				(justify left mirror)
			)
		)
		(fp_text user "P17"
			(at -5.813806 37.83203 0)
			(unlocked yes)
			(layer "B.SilkS")
			(effects
				(font
					(size 0.7874 0.5842)
					(thickness 0.1524)
				)
				(justify mirror)
			)
		)
		(fp_text user "P16"
			(at 3.187954 38.140132 0)
			(unlocked yes)
			(layer "B.SilkS")
			(effects
				(font
					(size 0.7874 0.5842)
					(thickness 0.1524)
				)
				(justify mirror)
			)
		)
		(fp_text user "S12"
			(at -5.741162 41.908222 0)
			(unlocked yes)
			(layer "B.SilkS")
			(effects
				(font
					(size 0.7874 0.5842)
					(thickness 0.1524)
				)
				(justify mirror)
			)
		)
		(fp_text user "S1"
			(at 3.080512 42.117264 0)
			(unlocked yes)
			(layer "B.SilkS")
			(effects
				(font
					(size 0.7874 0.5842)
					(thickness 0.1524)
				)
				(justify mirror)
			)
		)
		(fp_text user "S7"
			(at -5.855716 48.15459 0)
			(unlocked yes)
			(layer "B.SilkS")
			(effects
				(font
					(size 0.7874 0.5842)
					(thickness 0.1524)
				)
				(justify mirror)
			)
		)
		(fp_text user "S6"
			(at 2.941066 48.35906 0)
			(unlocked yes)
			(layer "B.SilkS")
			(effects
				(font
					(size 0.7874 0.5842)
					(thickness 0.1524)
				)
				(justify mirror)
			)
		)
		(fp_text user "P1"
			(at 3.108452 -1.27 180)
			(unlocked yes)
			(layer "B.Fab")
			(effects
				(font
					(size 0.7874 0.5842)
					(thickness 0.000001)
				)
				(justify mirror)
			)
		)
		(fp_text user "P32"
			(at -5.781548 -0.0508 180)
			(unlocked yes)
			(layer "B.Fab")
			(effects
				(font
					(size 0.7874 0.5842)
					(thickness 0.000001)
				)
				(justify mirror)
			)
		)
		(fp_text user "PRESS-FIT"
			(at -6.82371 29.8831 0)
			(unlocked yes)
			(layer "B.Fab")
			(effects
				(font
					(size 1.6002 1.1938)
					(thickness 0.000001)
				)
				(justify left mirror)
			)
		)
		(fp_text user "P17"
			(at -5.72135 38.0746 180)
			(unlocked yes)
			(layer "B.Fab")
			(effects
				(font
					(size 0.7874 0.5842)
					(thickness 0.000001)
				)
				(justify mirror)
			)
		)
		(fp_text user "P16"
			(at 3.159252 38.3794 180)
			(unlocked yes)
			(layer "B.Fab")
			(effects
				(font
					(size 0.7874 0.5842)
					(thickness 0.000001)
				)
				(justify mirror)
			)
		)
		(fp_text user "S12"
			(at -5.79374 41.42232 180)
			(unlocked yes)
			(layer "B.Fab")
			(effects
				(font
					(size 0.7874 0.5842)
					(thickness 0.000001)
				)
				(justify mirror)
			)
		)
		(fp_text user "S1"
			(at 3.09626 41.656 180)
			(unlocked yes)
			(layer "B.Fab")
			(effects
				(font
					(size 0.7874 0.5842)
					(thickness 0.000001)
				)
				(justify mirror)
			)
		)
		(fp_text user "S6"
			(at 3.133852 48.0822 180)
			(unlocked yes)
			(layer "B.Fab")
			(effects
				(font
					(size 0.7874 0.5842)
					(thickness 0.000001)
				)
				(justify mirror)
			)
		)
		(fp_text user "S7"
			(at -5.781548 48.0822 180)
			(unlocked yes)
			(layer "B.Fab")
			(effects
				(font
					(size 0.7874 0.5842)
					(thickness 0.000001)
				)
				(justify mirror)
			)
		)
		(fp_text user "P32"
			(at -4.071112 -0.0762 180)
			(unlocked yes)
			(layer "F.Fab")
			(effects
				(font
					(size 0.7874 0.5842)
					(thickness 0.000001)
				)
			)
		)
		(fp_text user "P1"
			(at 1.516888 0 180)
			(unlocked yes)
			(layer "F.Fab")
			(effects
				(font
					(size 0.7874 0.5842)
					(thickness 0.000001)
				)
			)
		)
		(fp_text user "PRESS-FIT"
			(at -6.762496 16.251428 0)
			(unlocked yes)
			(layer "F.Fab")
			(effects
				(font
					(size 1.6002 1.1938)
					(thickness 0.000001)
				)
				(justify left)
			)
		)
		(fp_text user "P17"
			(at -4.366768 38.227 180)
			(unlocked yes)
			(layer "F.Fab")
			(effects
				(font
					(size 0.7874 0.5842)
					(thickness 0.000001)
				)
			)
		)
		(fp_text user "P16"
			(at 2.228088 38.354 180)
			(unlocked yes)
			(layer "F.Fab")
			(effects
				(font
					(size 0.7874 0.5842)
					(thickness 0.000001)
				)
			)
		)
		(fp_text user "S12"
			(at -4.362958 41.09212 180)
			(unlocked yes)
			(layer "F.Fab")
			(effects
				(font
					(size 0.7874 0.5842)
					(thickness 0.000001)
				)
			)
		)
		(fp_text user "S1"
			(at 2.164842 41.6306 180)
			(unlocked yes)
			(layer "F.Fab")
			(effects
				(font
					(size 0.7874 0.5842)
					(thickness 0.000001)
				)
			)
		)
		(fp_text user "S6"
			(at 1.923288 48.133 180)
			(unlocked yes)
			(layer "F.Fab")
			(effects
				(font
					(size 0.7874 0.5842)
					(thickness 0.000001)
				)
			)
		)
		(fp_text user "S7"
			(at -4.426712 48.2346 180)
			(unlocked yes)
			(layer "F.Fab")
			(effects
				(font
					(size 0.7874 0.5842)
					(thickness 0.000001)
				)
			)
		)
		(pad "" np_thru_hole circle
			(at -1.35001 -2.54)
			(size 2.5146 2.5146)
			(drill 2.5146)
			(layers "*.Cu" "*.Mask")
			(clearance 0.381)
			(thermal_gap 0.381)
		)
		(pad "" np_thru_hole circle
			(at 0 50.8)
			(size 2.5146 2.5146)
			(drill 2.5146)
			(layers "*.Cu" "*.Mask")
			(clearance 0.381)
			(thermal_gap 0.381)
		)
		(pad "P1" thru_hole rect
			(at 0 0)
			(size 1.1684 1.1684)
			(drill 0.762)
			(layers "*.Cu" "*.Mask")
			(remove_unused_layers no)
			(net "GND")
			(clearance 0.0508)
			(padstack
				(mode front_inner_back)
				(layer "Inner"
					(shape circle)
					(size 1.1684 1.1684)
					(clearance 0.0508)
				)
				(layer "B.Cu"
					(shape rect)
					(size 1.1684 1.1684)
					(thermal_gap 0.0508)
					(clearance 0.0508)
				)
			)
		)
		(pad "P2" thru_hole circle
			(at 0 2.54)
			(size 1.1684 1.1684)
			(drill 0.762)
			(layers "*.Cu" "*.Mask")
			(remove_unused_layers no)
			(net "GND")
			(clearance 0.0508)
			(thermal_gap 0.0508)
		)
		(pad "P3" thru_hole circle
			(at 0 5.08)
			(size 1.1684 1.1684)
			(drill 0.762)
			(layers "*.Cu" "*.Mask")
			(remove_unused_layers no)
			(net "GND")
			(clearance 0.0508)
			(thermal_gap 0.0508)
		)
		(pad "P4" thru_hole circle
			(at 0 7.62)
			(size 1.1684 1.1684)
			(drill 0.762)
			(layers "*.Cu" "*.Mask")
			(remove_unused_layers no)
			(net "GND")
			(clearance 0.0508)
			(thermal_gap 0.0508)
		)
		(pad "P5" thru_hole circle
			(at 0 10.16)
			(size 1.1684 1.1684)
			(drill 0.762)
			(layers "*.Cu" "*.Mask")
			(remove_unused_layers no)
			(net "GND")
			(clearance 0.0508)
			(thermal_gap 0.0508)
		)
		(pad "P6" thru_hole circle
			(at 0 12.7)
			(size 1.1684 1.1684)
			(drill 0.762)
			(layers "*.Cu" "*.Mask")
			(remove_unused_layers no)
			(net "GND")
			(clearance 0.0508)
			(thermal_gap 0.0508)
		)
		(pad "P7" thru_hole circle
			(at 0 15.24)
			(size 1.1684 1.1684)
			(drill 0.762)
			(layers "*.Cu" "*.Mask")
			(remove_unused_layers no)
			(net "GND")
			(clearance 0.0508)
			(thermal_gap 0.0508)
		)
		(pad "P8" thru_hole circle
			(at 0 17.78)
			(size 1.1684 1.1684)
			(drill 0.762)
			(layers "*.Cu" "*.Mask")
			(remove_unused_layers no)
			(net "GND")
			(clearance 0.0508)
			(thermal_gap 0.0508)
		)
		(pad "P9" thru_hole circle
			(at 0 20.32)
			(size 1.1684 1.1684)
			(drill 0.762)
			(layers "*.Cu" "*.Mask")
			(remove_unused_layers no)
			(net "P12V")
			(clearance 0.0508)
			(thermal_gap 0.0508)
		)
		(pad "P10" thru_hole circle
			(at 0 22.86)
			(size 1.1684 1.1684)
			(drill 0.762)
			(layers "*.Cu" "*.Mask")
			(remove_unused_layers no)
			(net "P12V")
			(clearance 0.0508)
			(thermal_gap 0.0508)
		)
		(pad "P11" thru_hole circle
			(at 0 25.4)
			(size 1.1684 1.1684)
			(drill 0.762)
			(layers "*.Cu" "*.Mask")
			(remove_unused_layers no)
			(net "P12V")
			(clearance 0.0508)
			(thermal_gap 0.0508)
		)
		(pad "P12" thru_hole circle
			(at 0 27.94)
			(size 1.1684 1.1684)
			(drill 0.762)
			(layers "*.Cu" "*.Mask")
			(remove_unused_layers no)
			(net "P12V")
			(clearance 0.0508)
			(thermal_gap 0.0508)
		)
		(pad "P13" thru_hole circle
			(at 0 30.48)
			(size 1.1684 1.1684)
			(drill 0.762)
			(layers "*.Cu" "*.Mask")
			(remove_unused_layers no)
			(net "P12V")
			(clearance 0.0508)
			(thermal_gap 0.0508)
		)
		(pad "P14" thru_hole circle
			(at 0 33.02)
			(size 1.1684 1.1684)
			(drill 0.762)
			(layers "*.Cu" "*.Mask")
			(remove_unused_layers no)
			(net "P12V")
			(clearance 0.0508)
			(thermal_gap 0.0508)
		)
		(pad "P15" thru_hole circle
			(at 0 35.56)
			(size 1.1684 1.1684)
			(drill 0.762)
			(layers "*.Cu" "*.Mask")
			(remove_unused_layers no)
			(net "P12V")
			(clearance 0.0508)
			(thermal_gap 0.0508)
		)
		(pad "P16" thru_hole circle
			(at 0 38.1)
			(size 1.1684 1.1684)
			(drill 0.762)
			(layers "*.Cu" "*.Mask")
			(remove_unused_layers no)
			(net "P12V")
			(clearance 0.0508)
			(thermal_gap 0.0508)
		)
		(pad "P17" thru_hole circle
			(at -2.70002 38.1)
			(size 1.1684 1.1684)
			(drill 0.762)
			(layers "*.Cu" "*.Mask")
			(remove_unused_layers no)
			(net "P12V")
			(clearance 0.0508)
			(thermal_gap 0.0508)
		)
		(pad "P18" thru_hole circle
			(at -2.70002 35.56)
			(size 1.1684 1.1684)
			(drill 0.762)
			(layers "*.Cu" "*.Mask")
			(remove_unused_layers no)
			(net "P12V")
			(clearance 0.0508)
			(thermal_gap 0.0508)
		)
		(pad "P19" thru_hole circle
			(at -2.70002 33.02)
			(size 1.1684 1.1684)
			(drill 0.762)
			(layers "*.Cu" "*.Mask")
			(remove_unused_layers no)
			(net "P12V")
			(clearance 0.0508)
			(thermal_gap 0.0508)
		)
		(pad "P20" thru_hole circle
			(at -2.70002 30.48)
			(size 1.1684 1.1684)
			(drill 0.762)
			(layers "*.Cu" "*.Mask")
			(remove_unused_layers no)
			(net "P12V")
			(clearance 0.0508)
			(thermal_gap 0.0508)
		)
		(pad "P21" thru_hole circle
			(at -2.70002 27.94)
			(size 1.1684 1.1684)
			(drill 0.762)
			(layers "*.Cu" "*.Mask")
			(remove_unused_layers no)
			(net "P12V")
			(clearance 0.0508)
			(thermal_gap 0.0508)
		)
		(pad "P22" thru_hole circle
			(at -2.70002 25.4)
			(size 1.1684 1.1684)
			(drill 0.762)
			(layers "*.Cu" "*.Mask")
			(remove_unused_layers no)
			(net "P12V")
			(clearance 0.0508)
			(thermal_gap 0.0508)
		)
		(pad "P23" thru_hole circle
			(at -2.70002 22.86)
			(size 1.1684 1.1684)
			(drill 0.762)
			(layers "*.Cu" "*.Mask")
			(remove_unused_layers no)
			(net "P12V")
			(clearance 0.0508)
			(thermal_gap 0.0508)
		)
		(pad "P24" thru_hole circle
			(at -2.70002 20.32)
			(size 1.1684 1.1684)
			(drill 0.762)
			(layers "*.Cu" "*.Mask")
			(remove_unused_layers no)
			(net "P12V")
			(clearance 0.0508)
			(thermal_gap 0.0508)
		)
		(pad "P25" thru_hole circle
			(at -2.70002 17.78)
			(size 1.1684 1.1684)
			(drill 0.762)
			(layers "*.Cu" "*.Mask")
			(remove_unused_layers no)
			(net "GND")
			(clearance 0.0508)
			(thermal_gap 0.0508)
		)
		(pad "P26" thru_hole circle
			(at -2.70002 15.24)
			(size 1.1684 1.1684)
			(drill 0.762)
			(layers "*.Cu" "*.Mask")
			(remove_unused_layers no)
			(net "GND")
			(clearance 0.0508)
			(thermal_gap 0.0508)
		)
		(pad "P27" thru_hole circle
			(at -2.70002 12.7)
			(size 1.1684 1.1684)
			(drill 0.762)
			(layers "*.Cu" "*.Mask")
			(remove_unused_layers no)
			(net "GND")
			(clearance 0.0508)
			(thermal_gap 0.0508)
		)
		(pad "P28" thru_hole circle
			(at -2.70002 10.16)
			(size 1.1684 1.1684)
			(drill 0.762)
			(layers "*.Cu" "*.Mask")
			(remove_unused_layers no)
			(net "GND")
			(clearance 0.0508)
			(thermal_gap 0.0508)
		)
		(pad "P29" thru_hole circle
			(at -2.70002 7.62)
			(size 1.1684 1.1684)
			(drill 0.762)
			(layers "*.Cu" "*.Mask")
			(remove_unused_layers no)
			(net "GND")
			(clearance 0.0508)
			(thermal_gap 0.0508)
		)
		(pad "P30" thru_hole circle
			(at -2.70002 5.08)
			(size 1.1684 1.1684)
			(drill 0.762)
			(layers "*.Cu" "*.Mask")
			(remove_unused_layers no)
			(net "GND")
			(clearance 0.0508)
			(thermal_gap 0.0508)
		)
		(pad "P31" thru_hole circle
			(at -2.70002 2.54)
			(size 1.1684 1.1684)
			(drill 0.762)
			(layers "*.Cu" "*.Mask")
			(remove_unused_layers no)
			(net "GND")
			(clearance 0.0508)
			(thermal_gap 0.0508)
		)
		(pad "P32" thru_hole circle
			(at -2.70002 0)
			(size 1.1684 1.1684)
			(drill 0.762)
			(layers "*.Cu" "*.Mask")
			(remove_unused_layers no)
			(net "GND")
			(clearance 0.0508)
			(thermal_gap 0.0508)
		)
		(pad "S1" thru_hole circle
			(at 0.55499 41.60012)
			(size 1.1684 1.1684)
			(drill 0.762)
			(layers "*.Cu" "*.Mask")
			(remove_unused_layers no)
			(net "T11_BLAD1_TXD")
			(clearance 0.0508)
			(thermal_gap 0.0508)
		)
		(pad "S2" thru_hole circle
			(at -0.71501 42.87012)
			(size 1.1684 1.1684)
			(drill 0.762)
			(layers "*.Cu" "*.Mask")
			(remove_unused_layers no)
			(net "T11_BLAD1_RXD")
			(clearance 0.0508)
			(thermal_gap 0.0508)
		)
		(pad "S3" thru_hole circle
			(at 0.55499 44.14012)
			(size 1.1684 1.1684)
			(drill 0.762)
			(layers "*.Cu" "*.Mask")
			(remove_unused_layers no)
			(net "T11_BLAD1_EN")
			(clearance 0.0508)
			(thermal_gap 0.0508)
		)
		(pad "S4" thru_hole circle
			(at -0.71501 45.41012)
			(size 1.1684 1.1684)
			(drill 0.762)
			(layers "*.Cu" "*.Mask")
			(remove_unused_layers no)
			(net "B21_PSU_ALERT_N")
			(clearance 0.0508)
			(thermal_gap 0.0508)
		)
		(pad "S5" thru_hole circle
			(at 0.55499 46.68012)
			(size 1.1684 1.1684)
			(drill 0.762)
			(layers "*.Cu" "*.Mask")
			(remove_unused_layers no)
			(net "T11_BLAD2_TXD")
			(clearance 0.0508)
			(thermal_gap 0.0508)
		)
		(pad "S6" thru_hole circle
			(at -0.71501 47.95012)
			(size 1.1684 1.1684)
			(drill 0.762)
			(layers "*.Cu" "*.Mask")
			(remove_unused_layers no)
			(net "T11_BLAD2_RXD")
			(clearance 0.0508)
			(thermal_gap 0.0508)
		)
		(pad "S7" thru_hole circle
			(at -3.25501 47.95012)
			(size 1.1684 1.1684)
			(drill 0.762)
			(layers "*.Cu" "*.Mask")
			(remove_unused_layers no)
			(net "T11_BLAD4_RXD")
			(clearance 0.0508)
			(thermal_gap 0.0508)
		)
		(pad "S8" thru_hole circle
			(at -1.98501 46.68012)
			(size 1.1684 1.1684)
			(drill 0.762)
			(layers "*.Cu" "*.Mask")
			(remove_unused_layers no)
			(net "T11_BLAD4_TXD")
			(clearance 0.0508)
			(thermal_gap 0.0508)
		)
		(pad "S9" thru_hole circle
			(at -3.25501 45.41012)
			(size 1.1684 1.1684)
			(drill 0.762)
			(layers "*.Cu" "*.Mask")
			(remove_unused_layers no)
			(net "B22_PSU_ALERT_N")
			(clearance 0.0508)
			(thermal_gap 0.0508)
		)
		(pad "S10" thru_hole circle
			(at -1.98501 44.14012)
			(size 1.1684 1.1684)
			(drill 0.762)
			(layers "*.Cu" "*.Mask")
			(remove_unused_layers no)
			(net "T11_BLAD3_EN")
			(clearance 0.0508)
			(thermal_gap 0.0508)
		)
		(pad "S11" thru_hole circle
			(at -3.25501 42.87012)
			(size 1.1684 1.1684)
			(drill 0.762)
			(layers "*.Cu" "*.Mask")
			(remove_unused_layers no)
			(net "T11_BLAD3_RXD")
			(clearance 0.0508)
			(thermal_gap 0.0508)
		)
		(pad "S12" thru_hole circle
			(at -1.98501 41.60012)
			(size 1.1684 1.1684)
			(drill 0.762)
			(layers "*.Cu" "*.Mask")
			(remove_unused_layers no)
			(net "T11_BLAD3_TXD")
			(clearance 0.0508)
			(thermal_gap 0.0508)
		)
		(zone
			(layer "F.Cu")
			(hatch none 0.5)
			(connect_pads
				(clearance 0)
			)
			(min_thickness 0.25)
			(keepout
				(tracks allowed)
				(vias not_allowed)
				(pads allowed)
				(copperpour not_allowed)
				(footprints allowed)
			)
			(placement
				(enabled no)
				(sheetname "")
			)
			(fill
				(thermal_gap 0.5)
				(thermal_bridge_width 0.5)
				(island_removal_mode 0)
			)
			(polygon
				(pts
					(xy 85.00999 -453.95388) (xy 92.65539 -453.95388) (xy 92.65539 -448.84848) (xy 85.00999 -448.84848)
					(xy 84.98459 -448.84848) (xy 84.98459 -453.95388)
				)
			)
		)
		(zone
			(layer "F.Cu")
			(hatch none 0.5)
			(connect_pads
				(clearance 0)
			)
			(min_thickness 0.25)
			(keepout
				(tracks allowed)
				(vias not_allowed)
				(pads allowed)
				(copperpour not_allowed)
				(footprints allowed)
			)
			(placement
				(enabled no)
				(sheetname "")
			)
			(fill
				(thermal_gap 0.5)
				(thermal_bridge_width 0.5)
				(island_removal_mode 0)
			)
			(polygon
				(pts
					(xy 43.37939 -449.43268) (xy 43.37939 -453.39508) (xy 82.77479 -453.39508) (xy 82.80019 -453.39508)
					(xy 82.80019 -449.43268) (xy 82.80019 -449.40728) (xy 43.37939 -449.40728)
				)
			)
		)
		(zone
			(layers "F.Cu" "B.Cu" "In1.Cu" "In2.Cu" "In3.Cu" "In4.Cu" "In5.Cu" "In6.Cu")
			(hatch none 0.5)
			(connect_pads
				(clearance 0)
			)
			(min_thickness 0.25)
			(keepout
				(tracks not_allowed)
				(vias allowed)
				(pads allowed)
				(copperpour not_allowed)
				(footprints allowed)
			)
			(placement
				(enabled no)
				(sheetname "")
			)
			(fill
				(thermal_gap 0.5)
				(thermal_bridge_width 0.5)
				(island_removal_mode 0)
			)
			(polygon
				(pts
					(arc
						(start 43.18 -451.41007)
						(mid 39.81958 -451.41007)
						(end 43.18 -451.41007)
					)
				)
			)
		)
		(zone
			(layers "F.Cu" "B.Cu" "In1.Cu" "In2.Cu" "In3.Cu" "In4.Cu" "In5.Cu" "In6.Cu")
			(hatch none 0.5)
			(connect_pads
				(clearance 0)
			)
			(min_thickness 0.25)
			(keepout
				(tracks not_allowed)
				(vias allowed)
				(pads allowed)
				(copperpour not_allowed)
				(footprints allowed)
			)
			(placement
				(enabled no)
				(sheetname "")
			)
			(fill
				(thermal_gap 0.5)
				(thermal_bridge_width 0.5)
				(island_removal_mode 0)
			)
			(polygon
				(pts
					(arc
						(start 96.52381 -452.76008)
						(mid 93.15577 -452.76008)
						(end 96.52381 -452.76008)
					)
				)
			)
		)
	)
	(footprint ""
		(layer "B.Cu")
		(at 87.585804 -516.95858)
		(property "Reference" ""
			(at 0 0 0)
			(layer "B.SilkS")
			(hide yes)
			(effects
				(font
					(size 1.27 1.27)
				)
				(justify mirror)
			)
		)
		(property "Value" ""
			(at 0 0 0)
			(layer "B.Fab")
			(effects
				(font
					(size 1.27 1.27)
				)
				(justify mirror)
			)
		)
		(duplicate_pad_numbers_are_jumpers no)
		(fp_poly
			(pts
				(arc
					(start 1.4986 0)
					(mid -1.4986 0)
					(end 1.4986 0)
				)
			)
			(stroke
				(width 0)
				(type default)
			)
			(fill no)
			(layer "B.CrtYd")
		)
		(pad "1" smd circle
			(at 0 0 180)
			(size 0.9906 0.9906)
			(layers "B.Cu" "B.Mask" "B.Paste")
			(net "Net_71")
		)
		(zone
			(layer "B.Cu")
			(hatch none 0.5)
			(connect_pads
				(clearance 0)
			)
			(min_thickness 0.25)
			(keepout
				(tracks not_allowed)
				(vias allowed)
				(pads allowed)
				(copperpour not_allowed)
				(footprints allowed)
			)
			(placement
				(enabled no)
				(sheetname "")
			)
			(fill
				(thermal_gap 0.5)
				(thermal_bridge_width 0.5)
				(island_removal_mode 0)
			)
			(polygon
				(pts
					(arc
						(start 89.211404 -516.95858)
						(mid 85.960204 -516.95858)
						(end 89.211404 -516.95858)
					)
				)
			)
		)
	)
	(footprint ""
		(layer "B.Cu")
		(at 44.03979 -52.71008 90)
		(property "Reference" "J8"
			(at 6.17982 -4.9149 0)
			(unlocked yes)
			(layer "B.SilkS")
			(effects
				(font
					(size 0.7874 0.5842)
					(thickness 0.1524)
				)
				(justify left mirror)
			)
		)
		(property "Value" ""
			(at 0 0 90)
			(layer "B.Fab")
			(effects
				(font
					(size 1.27 1.27)
				)
				(justify mirror)
			)
		)
		(duplicate_pad_numbers_are_jumpers no)
		(fp_line
			(start 5.275072 -13.910056)
			(end -7.975092 -13.910056)
			(stroke
				(width 0.1524)
				(type default)
			)
			(layer "F.SilkS")
		)
		(fp_line
			(start -7.975092 -13.910056)
			(end -7.975092 62.170056)
			(stroke
				(width 0.1524)
				(type default)
			)
			(layer "F.SilkS")
		)
		(fp_line
			(start 5.275072 62.170056)
			(end 5.275072 -13.910056)
			(stroke
				(width 0.1524)
				(type default)
			)
			(layer "F.SilkS")
		)
		(fp_line
			(start -7.975092 62.170056)
			(end 5.275072 62.170056)
			(stroke
				(width 0.1524)
				(type default)
			)
			(layer "F.SilkS")
		)
		(fp_line
			(start 5.275072 -13.910056)
			(end -7.975092 -13.910056)
			(stroke
				(width 0.1524)
				(type default)
			)
			(layer "B.SilkS")
		)
		(fp_line
			(start -7.975092 -13.910056)
			(end -7.975092 62.170056)
			(stroke
				(width 0.1524)
				(type default)
			)
			(layer "B.SilkS")
		)
		(fp_line
			(start 2.275078 -10.910062)
			(end 2.275078 59.170062)
			(stroke
				(width 0.1524)
				(type default)
			)
			(layer "B.SilkS")
		)
		(fp_line
			(start -4.975098 -10.910062)
			(end 2.275078 -10.910062)
			(stroke
				(width 0.1524)
				(type default)
			)
			(layer "B.SilkS")
		)
		(fp_line
			(start 2.275078 59.170062)
			(end -4.975098 59.170062)
			(stroke
				(width 0.1524)
				(type default)
			)
			(layer "B.SilkS")
		)
		(fp_line
			(start -4.975098 59.170062)
			(end -4.975098 -10.910062)
			(stroke
				(width 0.1524)
				(type default)
			)
			(layer "B.SilkS")
		)
		(fp_line
			(start 5.275072 62.170056)
			(end 5.275072 -13.910056)
			(stroke
				(width 0.1524)
				(type default)
			)
			(layer "B.SilkS")
		)
		(fp_line
			(start -7.975092 62.170056)
			(end 5.275072 62.170056)
			(stroke
				(width 0.1524)
				(type default)
			)
			(layer "B.SilkS")
		)
		(fp_poly
			(pts
				(xy 4.103878 -0.759206) (xy 4.103878 0.764794) (xy 2.579878 0.002794)
			)
			(stroke
				(width 0)
				(type default)
			)
			(fill yes)
			(layer "B.SilkS")
		)
		(fp_poly
			(pts
				(xy 2.275078 -10.910062) (xy 2.275078 59.170062) (xy -4.975098 59.170062) (xy -4.975098 -10.910062)
			)
			(stroke
				(width 0)
				(type default)
			)
			(fill no)
			(layer "B.CrtYd")
		)
		(fp_poly
			(pts
				(xy 1.1938 40.9702) (xy 1.1938 48.6156) (xy -3.9116 48.6156) (xy -3.9116 40.9702) (xy -3.9116 40.9448)
				(xy 1.1938 40.9448)
			)
			(stroke
				(width 0)
				(type default)
			)
			(fill no)
			(layer "F.CrtYd")
		)
		(fp_poly
			(pts
				(xy -3.3274 -0.6604) (xy 0.635 -0.6604) (xy 0.635 38.735) (xy 0.635 38.7604) (xy -3.3274 38.7604)
				(xy -3.3528 38.7604) (xy -3.3528 -0.6604)
			)
			(stroke
				(width 0)
				(type default)
			)
			(fill no)
			(layer "F.CrtYd")
		)
		(fp_poly
			(pts
				(arc
					(start -1.35001 -1.01219)
					(mid -1.35001 -4.06781)
					(end -1.35001 -1.01219)
				)
			)
			(stroke
				(width 0)
				(type default)
			)
			(fill no)
			(layer "F.CrtYd")
		)
		(fp_poly
			(pts
				(arc
					(start 0 52.33162)
					(mid 0 49.26838)
					(end 0 52.33162)
				)
			)
			(stroke
				(width 0)
				(type default)
			)
			(fill no)
			(layer "F.CrtYd")
		)
		(fp_line
			(start 2.275078 -10.910062)
			(end 2.275078 59.170062)
			(stroke
				(width 0.1)
				(type default)
			)
			(layer "B.Fab")
		)
		(fp_line
			(start -4.975098 -10.910062)
			(end 2.275078 -10.910062)
			(stroke
				(width 0.1)
				(type default)
			)
			(layer "B.Fab")
		)
		(fp_line
			(start 2.275078 59.170062)
			(end -4.975098 59.170062)
			(stroke
				(width 0.1)
				(type default)
			)
			(layer "B.Fab")
		)
		(fp_line
			(start -4.975098 59.170062)
			(end -4.975098 -10.910062)
			(stroke
				(width 0.1)
				(type default)
			)
			(layer "B.Fab")
		)
		(fp_poly
			(pts
				(xy 4.103878 -0.759206) (xy 4.103878 0.764794) (xy 2.579878 0.002794)
			)
			(stroke
				(width 0)
				(type default)
			)
			(fill yes)
			(layer "B.Fab")
		)
		(fp_line
			(start 5.275072 -13.910056)
			(end -7.975092 -13.910056)
			(stroke
				(width 0.1)
				(type default)
			)
			(layer "F.Fab")
		)
		(fp_line
			(start -7.975092 -13.910056)
			(end -7.975092 62.170056)
			(stroke
				(width 0.1)
				(type default)
			)
			(layer "F.Fab")
		)
		(fp_line
			(start 5.275072 62.170056)
			(end 5.275072 -13.910056)
			(stroke
				(width 0.1)
				(type default)
			)
			(layer "F.Fab")
		)
		(fp_line
			(start -7.975092 62.170056)
			(end 5.275072 62.170056)
			(stroke
				(width 0.1)
				(type default)
			)
			(layer "F.Fab")
		)
		(fp_text user "P32"
			(at -8.889746 -0.874522 0)
			(unlocked yes)
			(layer "F.SilkS")
			(effects
				(font
					(size 0.7874 0.5842)
					(thickness 0.1524)
				)
			)
		)
		(fp_text user "P1"
			(at 6.75513 0.202184 0)
			(unlocked yes)
			(layer "F.SilkS")
			(effects
				(font
					(size 0.7874 0.5842)
					(thickness 0.1524)
				)
			)
		)
		(fp_text user "PRESS-FIT"
			(at -9.12368 0.829564 0)
			(unlocked yes)
			(layer "F.SilkS")
			(effects
				(font
					(size 0.7874 0.5842)
					(thickness 0.1524)
				)
				(justify left)
			)
		)
		(fp_text user "P17"
			(at -8.8519 37.893752 0)
			(unlocked yes)
			(layer "F.SilkS")
			(effects
				(font
					(size 0.7874 0.5842)
					(thickness 0.1524)
				)
			)
		)
		(fp_text user "P16"
			(at 6.922008 38.79596 0)
			(unlocked yes)
			(layer "F.SilkS")
			(effects
				(font
					(size 0.7874 0.5842)
					(thickness 0.1524)
				)
			)
		)
		(fp_text user "S1"
			(at 6.321298 41.858184 0)
			(unlocked yes)
			(layer "F.SilkS")
			(effects
				(font
					(size 0.7874 0.5842)
					(thickness 0.1524)
				)
			)
		)
		(fp_text user "S12"
			(at -8.95223 42.004234 0)
			(unlocked yes)
			(layer "F.SilkS")
			(effects
				(font
					(size 0.7874 0.5842)
					(thickness 0.1524)
				)
			)
		)
		(fp_text user "S6"
			(at 5.94995 47.81931 0)
			(unlocked yes)
			(layer "F.SilkS")
			(effects
				(font
					(size 0.7874 0.5842)
					(thickness 0.1524)
				)
			)
		)
		(fp_text user "S7"
			(at -9.26084 48.429672 0)
			(unlocked yes)
			(layer "F.SilkS")
			(effects
				(font
					(size 0.7874 0.5842)
					(thickness 0.1524)
				)
			)
		)
		(fp_text user "P1"
			(at 3.209544 -1.55575 0)
			(unlocked yes)
			(layer "B.SilkS")
			(effects
				(font
					(size 0.7874 0.5842)
					(thickness 0.1524)
				)
				(justify mirror)
			)
		)
		(fp_text user "P32"
			(at -5.949188 -0.289052 0)
			(unlocked yes)
			(layer "B.SilkS")
			(effects
				(font
					(size 0.7874 0.5842)
					(thickness 0.1524)
				)
				(justify mirror)
			)
		)
		(fp_text user "PRESS-FIT"
			(at -5.72643 28.794456 0)
			(unlocked yes)
			(layer "B.SilkS")
			(effects
				(font
					(size 0.7874 0.5842)
					(thickness 0.1524)
				)
				(justify left mirror)
			)
		)
		(fp_text user "P17"
			(at -5.53212 37.899848 0)
			(unlocked yes)
			(layer "B.SilkS")
			(effects
				(font
					(size 0.7874 0.5842)
					(thickness 0.1524)
				)
				(justify mirror)
			)
		)
		(fp_text user "P16"
			(at 3.090926 38.106096 0)
			(unlocked yes)
			(layer "B.SilkS")
			(effects
				(font
					(size 0.7874 0.5842)
					(thickness 0.1524)
				)
				(justify mirror)
			)
		)
		(fp_text user "S12"
			(at -5.766054 41.499282 0)
			(unlocked yes)
			(layer "B.SilkS")
			(effects
				(font
					(size 0.7874 0.5842)
					(thickness 0.1524)
				)
				(justify mirror)
			)
		)
		(fp_text user "S1"
			(at 3.0861 41.980612 0)
			(unlocked yes)
			(layer "B.SilkS")
			(effects
				(font
					(size 0.7874 0.5842)
					(thickness 0.1524)
				)
				(justify mirror)
			)
		)
		(fp_text user "S7"
			(at -5.676138 44.170092 0)
			(unlocked yes)
			(layer "B.SilkS")
			(effects
				(font
					(size 0.7874 0.5842)
					(thickness 0.1524)
				)
				(justify mirror)
			)
		)
		(fp_text user "S6"
			(at 2.91211 48.052228 0)
			(unlocked yes)
			(layer "B.SilkS")
			(effects
				(font
					(size 0.7874 0.5842)
					(thickness 0.1524)
				)
				(justify mirror)
			)
		)
		(fp_text user "P1"
			(at 3.108452 -1.27 180)
			(unlocked yes)
			(layer "B.Fab")
			(effects
				(font
					(size 0.7874 0.5842)
					(thickness 0.000001)
				)
				(justify mirror)
			)
		)
		(fp_text user "P32"
			(at -5.781548 -0.0508 180)
			(unlocked yes)
			(layer "B.Fab")
			(effects
				(font
					(size 0.7874 0.5842)
					(thickness 0.000001)
				)
				(justify mirror)
			)
		)
		(fp_text user "PRESS-FIT"
			(at -6.82371 29.8831 0)
			(unlocked yes)
			(layer "B.Fab")
			(effects
				(font
					(size 1.6002 1.1938)
					(thickness 0.000001)
				)
				(justify left mirror)
			)
		)
		(fp_text user "P17"
			(at -5.72135 38.0746 180)
			(unlocked yes)
			(layer "B.Fab")
			(effects
				(font
					(size 0.7874 0.5842)
					(thickness 0.000001)
				)
				(justify mirror)
			)
		)
		(fp_text user "P16"
			(at 3.159252 38.3794 180)
			(unlocked yes)
			(layer "B.Fab")
			(effects
				(font
					(size 0.7874 0.5842)
					(thickness 0.000001)
				)
				(justify mirror)
			)
		)
		(fp_text user "S12"
			(at -5.79374 41.42232 180)
			(unlocked yes)
			(layer "B.Fab")
			(effects
				(font
					(size 0.7874 0.5842)
					(thickness 0.000001)
				)
				(justify mirror)
			)
		)
		(fp_text user "S1"
			(at 3.09626 41.656 180)
			(unlocked yes)
			(layer "B.Fab")
			(effects
				(font
					(size 0.7874 0.5842)
					(thickness 0.000001)
				)
				(justify mirror)
			)
		)
		(fp_text user "S6"
			(at 3.133852 48.0822 180)
			(unlocked yes)
			(layer "B.Fab")
			(effects
				(font
					(size 0.7874 0.5842)
					(thickness 0.000001)
				)
				(justify mirror)
			)
		)
		(fp_text user "S7"
			(at -5.781548 48.0822 180)
			(unlocked yes)
			(layer "B.Fab")
			(effects
				(font
					(size 0.7874 0.5842)
					(thickness 0.000001)
				)
				(justify mirror)
			)
		)
		(fp_text user "P32"
			(at -4.071112 -0.0762 180)
			(unlocked yes)
			(layer "F.Fab")
			(effects
				(font
					(size 0.7874 0.5842)
					(thickness 0.000001)
				)
			)
		)
		(fp_text user "P1"
			(at 1.516888 0 180)
			(unlocked yes)
			(layer "F.Fab")
			(effects
				(font
					(size 0.7874 0.5842)
					(thickness 0.000001)
				)
			)
		)
		(fp_text user "PRESS-FIT"
			(at -6.762496 16.251428 0)
			(unlocked yes)
			(layer "F.Fab")
			(effects
				(font
					(size 1.6002 1.1938)
					(thickness 0.000001)
				)
				(justify left)
			)
		)
		(fp_text user "P17"
			(at -4.366768 38.227 180)
			(unlocked yes)
			(layer "F.Fab")
			(effects
				(font
					(size 0.7874 0.5842)
					(thickness 0.000001)
				)
			)
		)
		(fp_text user "P16"
			(at 2.228088 38.354 180)
			(unlocked yes)
			(layer "F.Fab")
			(effects
				(font
					(size 0.7874 0.5842)
					(thickness 0.000001)
				)
			)
		)
		(fp_text user "S12"
			(at -4.362958 41.09212 180)
			(unlocked yes)
			(layer "F.Fab")
			(effects
				(font
					(size 0.7874 0.5842)
					(thickness 0.000001)
				)
			)
		)
		(fp_text user "S1"
			(at 2.164842 41.6306 180)
			(unlocked yes)
			(layer "F.Fab")
			(effects
				(font
					(size 0.7874 0.5842)
					(thickness 0.000001)
				)
			)
		)
		(fp_text user "S6"
			(at 1.923288 48.133 180)
			(unlocked yes)
			(layer "F.Fab")
			(effects
				(font
					(size 0.7874 0.5842)
					(thickness 0.000001)
				)
			)
		)
		(fp_text user "S7"
			(at -4.426712 48.2346 180)
			(unlocked yes)
			(layer "F.Fab")
			(effects
				(font
					(size 0.7874 0.5842)
					(thickness 0.000001)
				)
			)
		)
		(pad "" np_thru_hole circle
			(at -1.35001 -2.54)
			(size 2.5146 2.5146)
			(drill 2.5146)
			(layers "*.Cu" "*.Mask")
			(clearance 0.381)
			(thermal_gap 0.381)
		)
		(pad "" np_thru_hole circle
			(at 0 50.8)
			(size 2.5146 2.5146)
			(drill 2.5146)
			(layers "*.Cu" "*.Mask")
			(clearance 0.381)
			(thermal_gap 0.381)
		)
		(pad "P1" thru_hole rect
			(at 0 0)
			(size 1.1684 1.1684)
			(drill 0.762)
			(layers "*.Cu" "*.Mask")
			(remove_unused_layers no)
			(net "GND")
			(clearance 0.0508)
			(padstack
				(mode front_inner_back)
				(layer "Inner"
					(shape circle)
					(size 1.1684 1.1684)
					(clearance 0.0508)
				)
				(layer "B.Cu"
					(shape rect)
					(size 1.1684 1.1684)
					(thermal_gap 0.0508)
					(clearance 0.0508)
				)
			)
		)
		(pad "P2" thru_hole circle
			(at 0 2.54)
			(size 1.1684 1.1684)
			(drill 0.762)
			(layers "*.Cu" "*.Mask")
			(remove_unused_layers no)
			(net "GND")
			(clearance 0.0508)
			(thermal_gap 0.0508)
		)
		(pad "P3" thru_hole circle
			(at 0 5.08)
			(size 1.1684 1.1684)
			(drill 0.762)
			(layers "*.Cu" "*.Mask")
			(remove_unused_layers no)
			(net "GND")
			(clearance 0.0508)
			(thermal_gap 0.0508)
		)
		(pad "P4" thru_hole circle
			(at 0 7.62)
			(size 1.1684 1.1684)
			(drill 0.762)
			(layers "*.Cu" "*.Mask")
			(remove_unused_layers no)
			(net "GND")
			(clearance 0.0508)
			(thermal_gap 0.0508)
		)
		(pad "P5" thru_hole circle
			(at 0 10.16)
			(size 1.1684 1.1684)
			(drill 0.762)
			(layers "*.Cu" "*.Mask")
			(remove_unused_layers no)
			(net "GND")
			(clearance 0.0508)
			(thermal_gap 0.0508)
		)
		(pad "P6" thru_hole circle
			(at 0 12.7)
			(size 1.1684 1.1684)
			(drill 0.762)
			(layers "*.Cu" "*.Mask")
			(remove_unused_layers no)
			(net "GND")
			(clearance 0.0508)
			(thermal_gap 0.0508)
		)
		(pad "P7" thru_hole circle
			(at 0 15.24)
			(size 1.1684 1.1684)
			(drill 0.762)
			(layers "*.Cu" "*.Mask")
			(remove_unused_layers no)
			(net "GND")
			(clearance 0.0508)
			(thermal_gap 0.0508)
		)
		(pad "P8" thru_hole circle
			(at 0 17.78)
			(size 1.1684 1.1684)
			(drill 0.762)
			(layers "*.Cu" "*.Mask")
			(remove_unused_layers no)
			(net "GND")
			(clearance 0.0508)
			(thermal_gap 0.0508)
		)
		(pad "P9" thru_hole circle
			(at 0 20.32)
			(size 1.1684 1.1684)
			(drill 0.762)
			(layers "*.Cu" "*.Mask")
			(remove_unused_layers no)
			(net "P12V")
			(clearance 0.0508)
			(thermal_gap 0.0508)
		)
		(pad "P10" thru_hole circle
			(at 0 22.86)
			(size 1.1684 1.1684)
			(drill 0.762)
			(layers "*.Cu" "*.Mask")
			(remove_unused_layers no)
			(net "P12V")
			(clearance 0.0508)
			(thermal_gap 0.0508)
		)
		(pad "P11" thru_hole circle
			(at 0 25.4)
			(size 1.1684 1.1684)
			(drill 0.762)
			(layers "*.Cu" "*.Mask")
			(remove_unused_layers no)
			(net "P12V")
			(clearance 0.0508)
			(thermal_gap 0.0508)
		)
		(pad "P12" thru_hole circle
			(at 0 27.94)
			(size 1.1684 1.1684)
			(drill 0.762)
			(layers "*.Cu" "*.Mask")
			(remove_unused_layers no)
			(net "P12V")
			(clearance 0.0508)
			(thermal_gap 0.0508)
		)
		(pad "P13" thru_hole circle
			(at 0 30.48)
			(size 1.1684 1.1684)
			(drill 0.762)
			(layers "*.Cu" "*.Mask")
			(remove_unused_layers no)
			(net "P12V")
			(clearance 0.0508)
			(thermal_gap 0.0508)
		)
		(pad "P14" thru_hole circle
			(at 0 33.02)
			(size 1.1684 1.1684)
			(drill 0.762)
			(layers "*.Cu" "*.Mask")
			(remove_unused_layers no)
			(net "P12V")
			(clearance 0.0508)
			(thermal_gap 0.0508)
		)
		(pad "P15" thru_hole circle
			(at 0 35.56)
			(size 1.1684 1.1684)
			(drill 0.762)
			(layers "*.Cu" "*.Mask")
			(remove_unused_layers no)
			(net "P12V")
			(clearance 0.0508)
			(thermal_gap 0.0508)
		)
		(pad "P16" thru_hole circle
			(at 0 38.1)
			(size 1.1684 1.1684)
			(drill 0.762)
			(layers "*.Cu" "*.Mask")
			(remove_unused_layers no)
			(net "P12V")
			(clearance 0.0508)
			(thermal_gap 0.0508)
		)
		(pad "P17" thru_hole circle
			(at -2.70002 38.1)
			(size 1.1684 1.1684)
			(drill 0.762)
			(layers "*.Cu" "*.Mask")
			(remove_unused_layers no)
			(net "P12V")
			(clearance 0.0508)
			(thermal_gap 0.0508)
		)
		(pad "P18" thru_hole circle
			(at -2.70002 35.56)
			(size 1.1684 1.1684)
			(drill 0.762)
			(layers "*.Cu" "*.Mask")
			(remove_unused_layers no)
			(net "P12V")
			(clearance 0.0508)
			(thermal_gap 0.0508)
		)
		(pad "P19" thru_hole circle
			(at -2.70002 33.02)
			(size 1.1684 1.1684)
			(drill 0.762)
			(layers "*.Cu" "*.Mask")
			(remove_unused_layers no)
			(net "P12V")
			(clearance 0.0508)
			(thermal_gap 0.0508)
		)
		(pad "P20" thru_hole circle
			(at -2.70002 30.48)
			(size 1.1684 1.1684)
			(drill 0.762)
			(layers "*.Cu" "*.Mask")
			(remove_unused_layers no)
			(net "P12V")
			(clearance 0.0508)
			(thermal_gap 0.0508)
		)
		(pad "P21" thru_hole circle
			(at -2.70002 27.94)
			(size 1.1684 1.1684)
			(drill 0.762)
			(layers "*.Cu" "*.Mask")
			(remove_unused_layers no)
			(net "P12V")
			(clearance 0.0508)
			(thermal_gap 0.0508)
		)
		(pad "P22" thru_hole circle
			(at -2.70002 25.4)
			(size 1.1684 1.1684)
			(drill 0.762)
			(layers "*.Cu" "*.Mask")
			(remove_unused_layers no)
			(net "P12V")
			(clearance 0.0508)
			(thermal_gap 0.0508)
		)
		(pad "P23" thru_hole circle
			(at -2.70002 22.86)
			(size 1.1684 1.1684)
			(drill 0.762)
			(layers "*.Cu" "*.Mask")
			(remove_unused_layers no)
			(net "P12V")
			(clearance 0.0508)
			(thermal_gap 0.0508)
		)
		(pad "P24" thru_hole circle
			(at -2.70002 20.32)
			(size 1.1684 1.1684)
			(drill 0.762)
			(layers "*.Cu" "*.Mask")
			(remove_unused_layers no)
			(net "P12V")
			(clearance 0.0508)
			(thermal_gap 0.0508)
		)
		(pad "P25" thru_hole circle
			(at -2.70002 17.78)
			(size 1.1684 1.1684)
			(drill 0.762)
			(layers "*.Cu" "*.Mask")
			(remove_unused_layers no)
			(net "GND")
			(clearance 0.0508)
			(thermal_gap 0.0508)
		)
		(pad "P26" thru_hole circle
			(at -2.70002 15.24)
			(size 1.1684 1.1684)
			(drill 0.762)
			(layers "*.Cu" "*.Mask")
			(remove_unused_layers no)
			(net "GND")
			(clearance 0.0508)
			(thermal_gap 0.0508)
		)
		(pad "P27" thru_hole circle
			(at -2.70002 12.7)
			(size 1.1684 1.1684)
			(drill 0.762)
			(layers "*.Cu" "*.Mask")
			(remove_unused_layers no)
			(net "GND")
			(clearance 0.0508)
			(thermal_gap 0.0508)
		)
		(pad "P28" thru_hole circle
			(at -2.70002 10.16)
			(size 1.1684 1.1684)
			(drill 0.762)
			(layers "*.Cu" "*.Mask")
			(remove_unused_layers no)
			(net "GND")
			(clearance 0.0508)
			(thermal_gap 0.0508)
		)
		(pad "P29" thru_hole circle
			(at -2.70002 7.62)
			(size 1.1684 1.1684)
			(drill 0.762)
			(layers "*.Cu" "*.Mask")
			(remove_unused_layers no)
			(net "GND")
			(clearance 0.0508)
			(thermal_gap 0.0508)
		)
		(pad "P30" thru_hole circle
			(at -2.70002 5.08)
			(size 1.1684 1.1684)
			(drill 0.762)
			(layers "*.Cu" "*.Mask")
			(remove_unused_layers no)
			(net "GND")
			(clearance 0.0508)
			(thermal_gap 0.0508)
		)
		(pad "P31" thru_hole circle
			(at -2.70002 2.54)
			(size 1.1684 1.1684)
			(drill 0.762)
			(layers "*.Cu" "*.Mask")
			(remove_unused_layers no)
			(net "GND")
			(clearance 0.0508)
			(thermal_gap 0.0508)
		)
		(pad "P32" thru_hole circle
			(at -2.70002 0)
			(size 1.1684 1.1684)
			(drill 0.762)
			(layers "*.Cu" "*.Mask")
			(remove_unused_layers no)
			(net "GND")
			(clearance 0.0508)
			(thermal_gap 0.0508)
		)
		(pad "S1" thru_hole circle
			(at 0.55499 41.60012)
			(size 1.1684 1.1684)
			(drill 0.762)
			(layers "*.Cu" "*.Mask")
			(remove_unused_layers no)
			(net "T2_BLAD1_TXD")
			(clearance 0.0508)
			(thermal_gap 0.0508)
		)
		(pad "S2" thru_hole circle
			(at -0.71501 42.87012)
			(size 1.1684 1.1684)
			(drill 0.762)
			(layers "*.Cu" "*.Mask")
			(remove_unused_layers no)
			(net "T2_BLAD1_RXD")
			(clearance 0.0508)
			(thermal_gap 0.0508)
		)
		(pad "S3" thru_hole circle
			(at 0.55499 44.14012)
			(size 1.1684 1.1684)
			(drill 0.762)
			(layers "*.Cu" "*.Mask")
			(remove_unused_layers no)
			(net "T2_BLAD1_EN")
			(clearance 0.0508)
			(thermal_gap 0.0508)
		)
		(pad "S4" thru_hole circle
			(at -0.71501 45.41012)
			(size 1.1684 1.1684)
			(drill 0.762)
			(layers "*.Cu" "*.Mask")
			(remove_unused_layers no)
			(net "B3_PSU_ALERT_N")
			(clearance 0.0508)
			(thermal_gap 0.0508)
		)
		(pad "S5" thru_hole circle
			(at 0.55499 46.68012)
			(size 1.1684 1.1684)
			(drill 0.762)
			(layers "*.Cu" "*.Mask")
			(remove_unused_layers no)
			(net "T2_BLAD2_TXD")
			(clearance 0.0508)
			(thermal_gap 0.0508)
		)
		(pad "S6" thru_hole circle
			(at -0.71501 47.95012)
			(size 1.1684 1.1684)
			(drill 0.762)
			(layers "*.Cu" "*.Mask")
			(remove_unused_layers no)
			(net "T2_BLAD2_RXD")
			(clearance 0.0508)
			(thermal_gap 0.0508)
		)
		(pad "S7" thru_hole circle
			(at -3.25501 47.95012)
			(size 1.1684 1.1684)
			(drill 0.762)
			(layers "*.Cu" "*.Mask")
			(remove_unused_layers no)
			(net "T2_BLAD4_RXD")
			(clearance 0.0508)
			(thermal_gap 0.0508)
		)
		(pad "S8" thru_hole circle
			(at -1.98501 46.68012)
			(size 1.1684 1.1684)
			(drill 0.762)
			(layers "*.Cu" "*.Mask")
			(remove_unused_layers no)
			(net "T2_BLAD4_TXD")
			(clearance 0.0508)
			(thermal_gap 0.0508)
		)
		(pad "S9" thru_hole circle
			(at -3.25501 45.41012)
			(size 1.1684 1.1684)
			(drill 0.762)
			(layers "*.Cu" "*.Mask")
			(remove_unused_layers no)
			(net "B4_PSU_ALERT_N")
			(clearance 0.0508)
			(thermal_gap 0.0508)
		)
		(pad "S10" thru_hole circle
			(at -1.98501 44.14012)
			(size 1.1684 1.1684)
			(drill 0.762)
			(layers "*.Cu" "*.Mask")
			(remove_unused_layers no)
			(net "T2_BLAD3_EN")
			(clearance 0.0508)
			(thermal_gap 0.0508)
		)
		(pad "S11" thru_hole circle
			(at -3.25501 42.87012)
			(size 1.1684 1.1684)
			(drill 0.762)
			(layers "*.Cu" "*.Mask")
			(remove_unused_layers no)
			(net "T2_BLAD3_RXD")
			(clearance 0.0508)
			(thermal_gap 0.0508)
		)
		(pad "S12" thru_hole circle
			(at -1.98501 41.60012)
			(size 1.1684 1.1684)
			(drill 0.762)
			(layers "*.Cu" "*.Mask")
			(remove_unused_layers no)
			(net "T2_BLAD3_TXD")
			(clearance 0.0508)
			(thermal_gap 0.0508)
		)
		(zone
			(layer "F.Cu")
			(hatch none 0.5)
			(connect_pads
				(clearance 0)
			)
			(min_thickness 0.25)
			(keepout
				(tracks allowed)
				(vias not_allowed)
				(pads allowed)
				(copperpour not_allowed)
				(footprints allowed)
			)
			(placement
				(enabled no)
				(sheetname "")
			)
			(fill
				(thermal_gap 0.5)
				(thermal_bridge_width 0.5)
				(island_removal_mode 0)
			)
			(polygon
				(pts
					(xy 85.00999 -53.90388) (xy 92.65539 -53.90388) (xy 92.65539 -48.79848) (xy 85.00999 -48.79848)
					(xy 84.98459 -48.79848) (xy 84.98459 -53.90388)
				)
			)
		)
		(zone
			(layer "F.Cu")
			(hatch none 0.5)
			(connect_pads
				(clearance 0)
			)
			(min_thickness 0.25)
			(keepout
				(tracks allowed)
				(vias not_allowed)
				(pads allowed)
				(copperpour not_allowed)
				(footprints allowed)
			)
			(placement
				(enabled no)
				(sheetname "")
			)
			(fill
				(thermal_gap 0.5)
				(thermal_bridge_width 0.5)
				(island_removal_mode 0)
			)
			(polygon
				(pts
					(xy 43.37939 -49.38268) (xy 43.37939 -53.34508) (xy 82.77479 -53.34508) (xy 82.80019 -53.34508)
					(xy 82.80019 -49.38268) (xy 82.80019 -49.35728) (xy 43.37939 -49.35728)
				)
			)
		)
		(zone
			(layers "F.Cu" "B.Cu" "In1.Cu" "In2.Cu" "In3.Cu" "In4.Cu" "In5.Cu" "In6.Cu")
			(hatch none 0.5)
			(connect_pads
				(clearance 0)
			)
			(min_thickness 0.25)
			(keepout
				(tracks not_allowed)
				(vias allowed)
				(pads allowed)
				(copperpour not_allowed)
				(footprints allowed)
			)
			(placement
				(enabled no)
				(sheetname "")
			)
			(fill
				(thermal_gap 0.5)
				(thermal_bridge_width 0.5)
				(island_removal_mode 0)
			)
			(polygon
				(pts
					(arc
						(start 43.18 -51.36007)
						(mid 39.81958 -51.36007)
						(end 43.18 -51.36007)
					)
				)
			)
		)
		(zone
			(layers "F.Cu" "B.Cu" "In1.Cu" "In2.Cu" "In3.Cu" "In4.Cu" "In5.Cu" "In6.Cu")
			(hatch none 0.5)
			(connect_pads
				(clearance 0)
			)
			(min_thickness 0.25)
			(keepout
				(tracks not_allowed)
				(vias allowed)
				(pads allowed)
				(copperpour not_allowed)
				(footprints allowed)
			)
			(placement
				(enabled no)
				(sheetname "")
			)
			(fill
				(thermal_gap 0.5)
				(thermal_bridge_width 0.5)
				(island_removal_mode 0)
			)
			(polygon
				(pts
					(arc
						(start 96.52381 -52.71008)
						(mid 93.15577 -52.71008)
						(end 96.52381 -52.71008)
					)
				)
			)
		)
	)
	(footprint ""
		(layer "B.Cu")
		(at 44.03979 -497.21008 90)
		(property "Reference" "J18"
			(at 6.695948 -2.740406 0)
			(unlocked yes)
			(layer "B.SilkS")
			(effects
				(font
					(size 0.7874 0.5842)
					(thickness 0.1524)
				)
				(justify left mirror)
			)
		)
		(property "Value" ""
			(at 0 0 90)
			(layer "B.Fab")
			(effects
				(font
					(size 1.27 1.27)
				)
				(justify mirror)
			)
		)
		(duplicate_pad_numbers_are_jumpers no)
		(fp_line
			(start 5.275072 -13.910056)
			(end -7.975092 -13.910056)
			(stroke
				(width 0.1524)
				(type default)
			)
			(layer "F.SilkS")
		)
		(fp_line
			(start -7.975092 -13.910056)
			(end -7.975092 62.170056)
			(stroke
				(width 0.1524)
				(type default)
			)
			(layer "F.SilkS")
		)
		(fp_line
			(start 5.275072 62.170056)
			(end 5.275072 -13.910056)
			(stroke
				(width 0.1524)
				(type default)
			)
			(layer "F.SilkS")
		)
		(fp_line
			(start -7.975092 62.170056)
			(end 5.275072 62.170056)
			(stroke
				(width 0.1524)
				(type default)
			)
			(layer "F.SilkS")
		)
		(fp_line
			(start 4.066286 -13.910056)
			(end -7.975092 -13.910056)
			(stroke
				(width 0.1524)
				(type default)
			)
			(layer "B.SilkS")
		)
		(fp_line
			(start -7.975092 -13.910056)
			(end -7.975092 62.170056)
			(stroke
				(width 0.1524)
				(type default)
			)
			(layer "B.SilkS")
		)
		(fp_line
			(start 2.275078 -10.910062)
			(end 2.275078 59.170062)
			(stroke
				(width 0.1524)
				(type default)
			)
			(layer "B.SilkS")
		)
		(fp_line
			(start -4.975098 -10.910062)
			(end 2.275078 -10.910062)
			(stroke
				(width 0.1524)
				(type default)
			)
			(layer "B.SilkS")
		)
		(fp_line
			(start 2.275078 59.170062)
			(end -4.975098 59.170062)
			(stroke
				(width 0.1524)
				(type default)
			)
			(layer "B.SilkS")
		)
		(fp_line
			(start -4.975098 59.170062)
			(end -4.975098 -10.910062)
			(stroke
				(width 0.1524)
				(type default)
			)
			(layer "B.SilkS")
		)
		(fp_line
			(start 5.275072 62.170056)
			(end 5.275072 -12.454128)
			(stroke
				(width 0.1524)
				(type default)
			)
			(layer "B.SilkS")
		)
		(fp_line
			(start -7.975092 62.170056)
			(end 5.275072 62.170056)
			(stroke
				(width 0.1524)
				(type default)
			)
			(layer "B.SilkS")
		)
		(fp_poly
			(pts
				(xy 4.103878 -0.759206) (xy 4.103878 0.764794) (xy 2.579878 0.002794)
			)
			(stroke
				(width 0)
				(type default)
			)
			(fill yes)
			(layer "B.SilkS")
		)
		(fp_poly
			(pts
				(xy 2.275078 -10.910062) (xy 2.275078 59.170062) (xy -4.975098 59.170062) (xy -4.975098 -10.910062)
			)
			(stroke
				(width 0)
				(type default)
			)
			(fill no)
			(layer "B.CrtYd")
		)
		(fp_poly
			(pts
				(xy 1.1938 40.9702) (xy 1.1938 48.6156) (xy -3.9116 48.6156) (xy -3.9116 40.9702) (xy -3.9116 40.9448)
				(xy 1.1938 40.9448)
			)
			(stroke
				(width 0)
				(type default)
			)
			(fill no)
			(layer "F.CrtYd")
		)
		(fp_poly
			(pts
				(xy -3.3274 -0.6604) (xy 0.635 -0.6604) (xy 0.635 38.735) (xy 0.635 38.7604) (xy -3.3274 38.7604)
				(xy -3.3528 38.7604) (xy -3.3528 -0.6604)
			)
			(stroke
				(width 0)
				(type default)
			)
			(fill no)
			(layer "F.CrtYd")
		)
		(fp_poly
			(pts
				(arc
					(start -1.35001 -1.01219)
					(mid -1.35001 -4.06781)
					(end -1.35001 -1.01219)
				)
			)
			(stroke
				(width 0)
				(type default)
			)
			(fill no)
			(layer "F.CrtYd")
		)
		(fp_poly
			(pts
				(arc
					(start 0 52.33162)
					(mid 0 49.26838)
					(end 0 52.33162)
				)
			)
			(stroke
				(width 0)
				(type default)
			)
			(fill no)
			(layer "F.CrtYd")
		)
		(fp_line
			(start 2.275078 -10.910062)
			(end 2.275078 59.170062)
			(stroke
				(width 0.1)
				(type default)
			)
			(layer "B.Fab")
		)
		(fp_line
			(start -4.975098 -10.910062)
			(end 2.275078 -10.910062)
			(stroke
				(width 0.1)
				(type default)
			)
			(layer "B.Fab")
		)
		(fp_line
			(start 2.275078 59.170062)
			(end -4.975098 59.170062)
			(stroke
				(width 0.1)
				(type default)
			)
			(layer "B.Fab")
		)
		(fp_line
			(start -4.975098 59.170062)
			(end -4.975098 -10.910062)
			(stroke
				(width 0.1)
				(type default)
			)
			(layer "B.Fab")
		)
		(fp_poly
			(pts
				(xy 4.103878 -0.759206) (xy 4.103878 0.764794) (xy 2.579878 0.002794)
			)
			(stroke
				(width 0)
				(type default)
			)
			(fill yes)
			(layer "B.Fab")
		)
		(fp_line
			(start 5.275072 -13.910056)
			(end -7.975092 -13.910056)
			(stroke
				(width 0.1)
				(type default)
			)
			(layer "F.Fab")
		)
		(fp_line
			(start -7.975092 -13.910056)
			(end -7.975092 62.170056)
			(stroke
				(width 0.1)
				(type default)
			)
			(layer "F.Fab")
		)
		(fp_line
			(start 5.275072 62.170056)
			(end 5.275072 -13.910056)
			(stroke
				(width 0.1)
				(type default)
			)
			(layer "F.Fab")
		)
		(fp_line
			(start -7.975092 62.170056)
			(end 5.275072 62.170056)
			(stroke
				(width 0.1)
				(type default)
			)
			(layer "F.Fab")
		)
		(fp_text user "P32"
			(at -8.943086 -0.332486 0)
			(unlocked yes)
			(layer "F.SilkS")
			(effects
				(font
					(size 0.7874 0.5842)
					(thickness 0.1524)
				)
			)
		)
		(fp_text user "P1"
			(at 6.095492 -0.065278 0)
			(unlocked yes)
			(layer "F.SilkS")
			(effects
				(font
					(size 0.7874 0.5842)
					(thickness 0.1524)
				)
			)
		)
		(fp_text user "PRESS-FIT"
			(at -9.344152 3.343402 0)
			(unlocked yes)
			(layer "F.SilkS")
			(effects
				(font
					(size 0.7874 0.5842)
					(thickness 0.1524)
				)
				(justify left)
			)
		)
		(fp_text user "P17"
			(at -9.676638 38.171628 0)
			(unlocked yes)
			(layer "F.SilkS")
			(effects
				(font
					(size 0.7874 0.5842)
					(thickness 0.1524)
				)
			)
		)
		(fp_text user "P16"
			(at 6.32968 41.040558 0)
			(unlocked yes)
			(layer "F.SilkS")
			(effects
				(font
					(size 0.7874 0.5842)
					(thickness 0.1524)
				)
			)
		)
		(fp_text user "S12"
			(at -9.711436 42.05478 0)
			(unlocked yes)
			(layer "F.SilkS")
			(effects
				(font
					(size 0.7874 0.5842)
					(thickness 0.1524)
				)
			)
		)
		(fp_text user "S1"
			(at 6.32968 43.179492 0)
			(unlocked yes)
			(layer "F.SilkS")
			(effects
				(font
					(size 0.7874 0.5842)
					(thickness 0.1524)
				)
			)
		)
		(fp_text user "S7"
			(at -9.884664 49.058322 0)
			(unlocked yes)
			(layer "F.SilkS")
			(effects
				(font
					(size 0.7874 0.5842)
					(thickness 0.1524)
				)
			)
		)
		(fp_text user "S6"
			(at 6.229096 50.832258 0)
			(unlocked yes)
			(layer "F.SilkS")
			(effects
				(font
					(size 0.7874 0.5842)
					(thickness 0.1524)
				)
			)
		)
		(fp_text user "P1"
			(at 3.015488 -1.521714 0)
			(unlocked yes)
			(layer "B.SilkS")
			(effects
				(font
					(size 0.7874 0.5842)
					(thickness 0.1524)
				)
				(justify mirror)
			)
		)
		(fp_text user "P32"
			(at -5.97281 -0.357124 0)
			(unlocked yes)
			(layer "B.SilkS")
			(effects
				(font
					(size 0.7874 0.5842)
					(thickness 0.1524)
				)
				(justify mirror)
			)
		)
		(fp_text user "PRESS-FIT"
			(at -7.18947 29.8831 0)
			(unlocked yes)
			(layer "B.SilkS")
			(effects
				(font
					(size 0.7874 0.5842)
					(thickness 0.1524)
				)
				(justify left mirror)
			)
		)
		(fp_text user "P17"
			(at -5.998972 37.934138 0)
			(unlocked yes)
			(layer "B.SilkS")
			(effects
				(font
					(size 0.7874 0.5842)
					(thickness 0.1524)
				)
				(justify mirror)
			)
		)
		(fp_text user "P16"
			(at 3.100832 38.038024 0)
			(unlocked yes)
			(layer "B.SilkS")
			(effects
				(font
					(size 0.7874 0.5842)
					(thickness 0.1524)
				)
				(justify mirror)
			)
		)
		(fp_text user "S1"
			(at 3.02768 41.844468 0)
			(unlocked yes)
			(layer "B.SilkS")
			(effects
				(font
					(size 0.7874 0.5842)
					(thickness 0.1524)
				)
				(justify mirror)
			)
		)
		(fp_text user "S12"
			(at -5.926582 42.72534 0)
			(unlocked yes)
			(layer "B.SilkS")
			(effects
				(font
					(size 0.7874 0.5842)
					(thickness 0.1524)
				)
				(justify mirror)
			)
		)
		(fp_text user "S6"
			(at 3.126232 47.643542 0)
			(unlocked yes)
			(layer "B.SilkS")
			(effects
				(font
					(size 0.7874 0.5842)
					(thickness 0.1524)
				)
				(justify mirror)
			)
		)
		(fp_text user "S7"
			(at -5.836412 48.290734 0)
			(unlocked yes)
			(layer "B.SilkS")
			(effects
				(font
					(size 0.7874 0.5842)
					(thickness 0.1524)
				)
				(justify mirror)
			)
		)
		(fp_text user "P1"
			(at 3.108452 -1.27 180)
			(unlocked yes)
			(layer "B.Fab")
			(effects
				(font
					(size 0.7874 0.5842)
					(thickness 0.000001)
				)
				(justify mirror)
			)
		)
		(fp_text user "P32"
			(at -5.781548 -0.0508 180)
			(unlocked yes)
			(layer "B.Fab")
			(effects
				(font
					(size 0.7874 0.5842)
					(thickness 0.000001)
				)
				(justify mirror)
			)
		)
		(fp_text user "PRESS-FIT"
			(at -6.82371 29.8831 0)
			(unlocked yes)
			(layer "B.Fab")
			(effects
				(font
					(size 1.6002 1.1938)
					(thickness 0.000001)
				)
				(justify left mirror)
			)
		)
		(fp_text user "P17"
			(at -5.72135 38.0746 180)
			(unlocked yes)
			(layer "B.Fab")
			(effects
				(font
					(size 0.7874 0.5842)
					(thickness 0.000001)
				)
				(justify mirror)
			)
		)
		(fp_text user "P16"
			(at 3.159252 38.3794 180)
			(unlocked yes)
			(layer "B.Fab")
			(effects
				(font
					(size 0.7874 0.5842)
					(thickness 0.000001)
				)
				(justify mirror)
			)
		)
		(fp_text user "S12"
			(at -5.79374 41.42232 180)
			(unlocked yes)
			(layer "B.Fab")
			(effects
				(font
					(size 0.7874 0.5842)
					(thickness 0.000001)
				)
				(justify mirror)
			)
		)
		(fp_text user "S1"
			(at 3.09626 41.656 180)
			(unlocked yes)
			(layer "B.Fab")
			(effects
				(font
					(size 0.7874 0.5842)
					(thickness 0.000001)
				)
				(justify mirror)
			)
		)
		(fp_text user "S6"
			(at 3.133852 48.0822 180)
			(unlocked yes)
			(layer "B.Fab")
			(effects
				(font
					(size 0.7874 0.5842)
					(thickness 0.000001)
				)
				(justify mirror)
			)
		)
		(fp_text user "S7"
			(at -5.781548 48.0822 180)
			(unlocked yes)
			(layer "B.Fab")
			(effects
				(font
					(size 0.7874 0.5842)
					(thickness 0.000001)
				)
				(justify mirror)
			)
		)
		(fp_text user "P32"
			(at -4.071112 -0.0762 180)
			(unlocked yes)
			(layer "F.Fab")
			(effects
				(font
					(size 0.7874 0.5842)
					(thickness 0.000001)
				)
			)
		)
		(fp_text user "P1"
			(at 1.516888 0 180)
			(unlocked yes)
			(layer "F.Fab")
			(effects
				(font
					(size 0.7874 0.5842)
					(thickness 0.000001)
				)
			)
		)
		(fp_text user "PRESS-FIT"
			(at -6.762496 16.251428 0)
			(unlocked yes)
			(layer "F.Fab")
			(effects
				(font
					(size 1.6002 1.1938)
					(thickness 0.000001)
				)
				(justify left)
			)
		)
		(fp_text user "P17"
			(at -4.366768 38.227 180)
			(unlocked yes)
			(layer "F.Fab")
			(effects
				(font
					(size 0.7874 0.5842)
					(thickness 0.000001)
				)
			)
		)
		(fp_text user "P16"
			(at 2.228088 38.354 180)
			(unlocked yes)
			(layer "F.Fab")
			(effects
				(font
					(size 0.7874 0.5842)
					(thickness 0.000001)
				)
			)
		)
		(fp_text user "S12"
			(at -4.362958 41.09212 180)
			(unlocked yes)
			(layer "F.Fab")
			(effects
				(font
					(size 0.7874 0.5842)
					(thickness 0.000001)
				)
			)
		)
		(fp_text user "S1"
			(at 2.164842 41.6306 180)
			(unlocked yes)
			(layer "F.Fab")
			(effects
				(font
					(size 0.7874 0.5842)
					(thickness 0.000001)
				)
			)
		)
		(fp_text user "S6"
			(at 1.923288 48.133 180)
			(unlocked yes)
			(layer "F.Fab")
			(effects
				(font
					(size 0.7874 0.5842)
					(thickness 0.000001)
				)
			)
		)
		(fp_text user "S7"
			(at -4.426712 48.2346 180)
			(unlocked yes)
			(layer "F.Fab")
			(effects
				(font
					(size 0.7874 0.5842)
					(thickness 0.000001)
				)
			)
		)
		(pad "" np_thru_hole circle
			(at -1.35001 -2.54)
			(size 2.5146 2.5146)
			(drill 2.5146)
			(layers "*.Cu" "*.Mask")
			(clearance 0.381)
			(thermal_gap 0.381)
		)
		(pad "" np_thru_hole circle
			(at 0 50.8)
			(size 2.5146 2.5146)
			(drill 2.5146)
			(layers "*.Cu" "*.Mask")
			(clearance 0.381)
			(thermal_gap 0.381)
		)
		(pad "P1" thru_hole rect
			(at 0 0)
			(size 1.1684 1.1684)
			(drill 0.762)
			(layers "*.Cu" "*.Mask")
			(remove_unused_layers no)
			(net "GND")
			(clearance 0.0508)
			(padstack
				(mode front_inner_back)
				(layer "Inner"
					(shape circle)
					(size 1.1684 1.1684)
					(clearance 0.0508)
				)
				(layer "B.Cu"
					(shape rect)
					(size 1.1684 1.1684)
					(thermal_gap 0.0508)
					(clearance 0.0508)
				)
			)
		)
		(pad "P2" thru_hole circle
			(at 0 2.54)
			(size 1.1684 1.1684)
			(drill 0.762)
			(layers "*.Cu" "*.Mask")
			(remove_unused_layers no)
			(net "GND")
			(clearance 0.0508)
			(thermal_gap 0.0508)
		)
		(pad "P3" thru_hole circle
			(at 0 5.08)
			(size 1.1684 1.1684)
			(drill 0.762)
			(layers "*.Cu" "*.Mask")
			(remove_unused_layers no)
			(net "GND")
			(clearance 0.0508)
			(thermal_gap 0.0508)
		)
		(pad "P4" thru_hole circle
			(at 0 7.62)
			(size 1.1684 1.1684)
			(drill 0.762)
			(layers "*.Cu" "*.Mask")
			(remove_unused_layers no)
			(net "GND")
			(clearance 0.0508)
			(thermal_gap 0.0508)
		)
		(pad "P5" thru_hole circle
			(at 0 10.16)
			(size 1.1684 1.1684)
			(drill 0.762)
			(layers "*.Cu" "*.Mask")
			(remove_unused_layers no)
			(net "GND")
			(clearance 0.0508)
			(thermal_gap 0.0508)
		)
		(pad "P6" thru_hole circle
			(at 0 12.7)
			(size 1.1684 1.1684)
			(drill 0.762)
			(layers "*.Cu" "*.Mask")
			(remove_unused_layers no)
			(net "GND")
			(clearance 0.0508)
			(thermal_gap 0.0508)
		)
		(pad "P7" thru_hole circle
			(at 0 15.24)
			(size 1.1684 1.1684)
			(drill 0.762)
			(layers "*.Cu" "*.Mask")
			(remove_unused_layers no)
			(net "GND")
			(clearance 0.0508)
			(thermal_gap 0.0508)
		)
		(pad "P8" thru_hole circle
			(at 0 17.78)
			(size 1.1684 1.1684)
			(drill 0.762)
			(layers "*.Cu" "*.Mask")
			(remove_unused_layers no)
			(net "GND")
			(clearance 0.0508)
			(thermal_gap 0.0508)
		)
		(pad "P9" thru_hole circle
			(at 0 20.32)
			(size 1.1684 1.1684)
			(drill 0.762)
			(layers "*.Cu" "*.Mask")
			(remove_unused_layers no)
			(net "P12V")
			(clearance 0.0508)
			(thermal_gap 0.0508)
		)
		(pad "P10" thru_hole circle
			(at 0 22.86)
			(size 1.1684 1.1684)
			(drill 0.762)
			(layers "*.Cu" "*.Mask")
			(remove_unused_layers no)
			(net "P12V")
			(clearance 0.0508)
			(thermal_gap 0.0508)
		)
		(pad "P11" thru_hole circle
			(at 0 25.4)
			(size 1.1684 1.1684)
			(drill 0.762)
			(layers "*.Cu" "*.Mask")
			(remove_unused_layers no)
			(net "P12V")
			(clearance 0.0508)
			(thermal_gap 0.0508)
		)
		(pad "P12" thru_hole circle
			(at 0 27.94)
			(size 1.1684 1.1684)
			(drill 0.762)
			(layers "*.Cu" "*.Mask")
			(remove_unused_layers no)
			(net "P12V")
			(clearance 0.0508)
			(thermal_gap 0.0508)
		)
		(pad "P13" thru_hole circle
			(at 0 30.48)
			(size 1.1684 1.1684)
			(drill 0.762)
			(layers "*.Cu" "*.Mask")
			(remove_unused_layers no)
			(net "P12V")
			(clearance 0.0508)
			(thermal_gap 0.0508)
		)
		(pad "P14" thru_hole circle
			(at 0 33.02)
			(size 1.1684 1.1684)
			(drill 0.762)
			(layers "*.Cu" "*.Mask")
			(remove_unused_layers no)
			(net "P12V")
			(clearance 0.0508)
			(thermal_gap 0.0508)
		)
		(pad "P15" thru_hole circle
			(at 0 35.56)
			(size 1.1684 1.1684)
			(drill 0.762)
			(layers "*.Cu" "*.Mask")
			(remove_unused_layers no)
			(net "P12V")
			(clearance 0.0508)
			(thermal_gap 0.0508)
		)
		(pad "P16" thru_hole circle
			(at 0 38.1)
			(size 1.1684 1.1684)
			(drill 0.762)
			(layers "*.Cu" "*.Mask")
			(remove_unused_layers no)
			(net "P12V")
			(clearance 0.0508)
			(thermal_gap 0.0508)
		)
		(pad "P17" thru_hole circle
			(at -2.70002 38.1)
			(size 1.1684 1.1684)
			(drill 0.762)
			(layers "*.Cu" "*.Mask")
			(remove_unused_layers no)
			(net "P12V")
			(clearance 0.0508)
			(thermal_gap 0.0508)
		)
		(pad "P18" thru_hole circle
			(at -2.70002 35.56)
			(size 1.1684 1.1684)
			(drill 0.762)
			(layers "*.Cu" "*.Mask")
			(remove_unused_layers no)
			(net "P12V")
			(clearance 0.0508)
			(thermal_gap 0.0508)
		)
		(pad "P19" thru_hole circle
			(at -2.70002 33.02)
			(size 1.1684 1.1684)
			(drill 0.762)
			(layers "*.Cu" "*.Mask")
			(remove_unused_layers no)
			(net "P12V")
			(clearance 0.0508)
			(thermal_gap 0.0508)
		)
		(pad "P20" thru_hole circle
			(at -2.70002 30.48)
			(size 1.1684 1.1684)
			(drill 0.762)
			(layers "*.Cu" "*.Mask")
			(remove_unused_layers no)
			(net "P12V")
			(clearance 0.0508)
			(thermal_gap 0.0508)
		)
		(pad "P21" thru_hole circle
			(at -2.70002 27.94)
			(size 1.1684 1.1684)
			(drill 0.762)
			(layers "*.Cu" "*.Mask")
			(remove_unused_layers no)
			(net "P12V")
			(clearance 0.0508)
			(thermal_gap 0.0508)
		)
		(pad "P22" thru_hole circle
			(at -2.70002 25.4)
			(size 1.1684 1.1684)
			(drill 0.762)
			(layers "*.Cu" "*.Mask")
			(remove_unused_layers no)
			(net "P12V")
			(clearance 0.0508)
			(thermal_gap 0.0508)
		)
		(pad "P23" thru_hole circle
			(at -2.70002 22.86)
			(size 1.1684 1.1684)
			(drill 0.762)
			(layers "*.Cu" "*.Mask")
			(remove_unused_layers no)
			(net "P12V")
			(clearance 0.0508)
			(thermal_gap 0.0508)
		)
		(pad "P24" thru_hole circle
			(at -2.70002 20.32)
			(size 1.1684 1.1684)
			(drill 0.762)
			(layers "*.Cu" "*.Mask")
			(remove_unused_layers no)
			(net "P12V")
			(clearance 0.0508)
			(thermal_gap 0.0508)
		)
		(pad "P25" thru_hole circle
			(at -2.70002 17.78)
			(size 1.1684 1.1684)
			(drill 0.762)
			(layers "*.Cu" "*.Mask")
			(remove_unused_layers no)
			(net "GND")
			(clearance 0.0508)
			(thermal_gap 0.0508)
		)
		(pad "P26" thru_hole circle
			(at -2.70002 15.24)
			(size 1.1684 1.1684)
			(drill 0.762)
			(layers "*.Cu" "*.Mask")
			(remove_unused_layers no)
			(net "GND")
			(clearance 0.0508)
			(thermal_gap 0.0508)
		)
		(pad "P27" thru_hole circle
			(at -2.70002 12.7)
			(size 1.1684 1.1684)
			(drill 0.762)
			(layers "*.Cu" "*.Mask")
			(remove_unused_layers no)
			(net "GND")
			(clearance 0.0508)
			(thermal_gap 0.0508)
		)
		(pad "P28" thru_hole circle
			(at -2.70002 10.16)
			(size 1.1684 1.1684)
			(drill 0.762)
			(layers "*.Cu" "*.Mask")
			(remove_unused_layers no)
			(net "GND")
			(clearance 0.0508)
			(thermal_gap 0.0508)
		)
		(pad "P29" thru_hole circle
			(at -2.70002 7.62)
			(size 1.1684 1.1684)
			(drill 0.762)
			(layers "*.Cu" "*.Mask")
			(remove_unused_layers no)
			(net "GND")
			(clearance 0.0508)
			(thermal_gap 0.0508)
		)
		(pad "P30" thru_hole circle
			(at -2.70002 5.08)
			(size 1.1684 1.1684)
			(drill 0.762)
			(layers "*.Cu" "*.Mask")
			(remove_unused_layers no)
			(net "GND")
			(clearance 0.0508)
			(thermal_gap 0.0508)
		)
		(pad "P31" thru_hole circle
			(at -2.70002 2.54)
			(size 1.1684 1.1684)
			(drill 0.762)
			(layers "*.Cu" "*.Mask")
			(remove_unused_layers no)
			(net "GND")
			(clearance 0.0508)
			(thermal_gap 0.0508)
		)
		(pad "P32" thru_hole circle
			(at -2.70002 0)
			(size 1.1684 1.1684)
			(drill 0.762)
			(layers "*.Cu" "*.Mask")
			(remove_unused_layers no)
			(net "GND")
			(clearance 0.0508)
			(thermal_gap 0.0508)
		)
		(pad "S1" thru_hole circle
			(at 0.55499 41.60012)
			(size 1.1684 1.1684)
			(drill 0.762)
			(layers "*.Cu" "*.Mask")
			(remove_unused_layers no)
			(net "T12_BLAD1_TXD")
			(clearance 0.0508)
			(thermal_gap 0.0508)
		)
		(pad "S2" thru_hole circle
			(at -0.71501 42.87012)
			(size 1.1684 1.1684)
			(drill 0.762)
			(layers "*.Cu" "*.Mask")
			(remove_unused_layers no)
			(net "T12_BLAD1_RXD")
			(clearance 0.0508)
			(thermal_gap 0.0508)
		)
		(pad "S3" thru_hole circle
			(at 0.55499 44.14012)
			(size 1.1684 1.1684)
			(drill 0.762)
			(layers "*.Cu" "*.Mask")
			(remove_unused_layers no)
			(net "T12_BLAD1_EN")
			(clearance 0.0508)
			(thermal_gap 0.0508)
		)
		(pad "S4" thru_hole circle
			(at -0.71501 45.41012)
			(size 1.1684 1.1684)
			(drill 0.762)
			(layers "*.Cu" "*.Mask")
			(remove_unused_layers no)
			(net "B23_PSU_ALERT_N")
			(clearance 0.0508)
			(thermal_gap 0.0508)
		)
		(pad "S5" thru_hole circle
			(at 0.55499 46.68012)
			(size 1.1684 1.1684)
			(drill 0.762)
			(layers "*.Cu" "*.Mask")
			(remove_unused_layers no)
			(net "T12_BLAD2_TXD")
			(clearance 0.0508)
			(thermal_gap 0.0508)
		)
		(pad "S6" thru_hole circle
			(at -0.71501 47.95012)
			(size 1.1684 1.1684)
			(drill 0.762)
			(layers "*.Cu" "*.Mask")
			(remove_unused_layers no)
			(net "T12_BLAD2_RXD")
			(clearance 0.0508)
			(thermal_gap 0.0508)
		)
		(pad "S7" thru_hole circle
			(at -3.25501 47.95012)
			(size 1.1684 1.1684)
			(drill 0.762)
			(layers "*.Cu" "*.Mask")
			(remove_unused_layers no)
			(net "T12_BLAD4_RXD")
			(clearance 0.0508)
			(thermal_gap 0.0508)
		)
		(pad "S8" thru_hole circle
			(at -1.98501 46.68012)
			(size 1.1684 1.1684)
			(drill 0.762)
			(layers "*.Cu" "*.Mask")
			(remove_unused_layers no)
			(net "T12_BLAD4_TXD")
			(clearance 0.0508)
			(thermal_gap 0.0508)
		)
		(pad "S9" thru_hole circle
			(at -3.25501 45.41012)
			(size 1.1684 1.1684)
			(drill 0.762)
			(layers "*.Cu" "*.Mask")
			(remove_unused_layers no)
			(net "B24_PSU_ALERT_N")
			(clearance 0.0508)
			(thermal_gap 0.0508)
		)
		(pad "S10" thru_hole circle
			(at -1.98501 44.14012)
			(size 1.1684 1.1684)
			(drill 0.762)
			(layers "*.Cu" "*.Mask")
			(remove_unused_layers no)
			(net "T12_BLAD3_EN")
			(clearance 0.0508)
			(thermal_gap 0.0508)
		)
		(pad "S11" thru_hole circle
			(at -3.25501 42.87012)
			(size 1.1684 1.1684)
			(drill 0.762)
			(layers "*.Cu" "*.Mask")
			(remove_unused_layers no)
			(net "T12_BLAD3_RXD")
			(clearance 0.0508)
			(thermal_gap 0.0508)
		)
		(pad "S12" thru_hole circle
			(at -1.98501 41.60012)
			(size 1.1684 1.1684)
			(drill 0.762)
			(layers "*.Cu" "*.Mask")
			(remove_unused_layers no)
			(net "T12_BLAD3_TXD")
			(clearance 0.0508)
			(thermal_gap 0.0508)
		)
		(zone
			(layer "F.Cu")
			(hatch none 0.5)
			(connect_pads
				(clearance 0)
			)
			(min_thickness 0.25)
			(keepout
				(tracks allowed)
				(vias not_allowed)
				(pads allowed)
				(copperpour not_allowed)
				(footprints allowed)
			)
			(placement
				(enabled no)
				(sheetname "")
			)
			(fill
				(thermal_gap 0.5)
				(thermal_bridge_width 0.5)
				(island_removal_mode 0)
			)
			(polygon
				(pts
					(xy 85.00999 -498.40388) (xy 92.65539 -498.40388) (xy 92.65539 -493.29848) (xy 85.00999 -493.29848)
					(xy 84.98459 -493.29848) (xy 84.98459 -498.40388)
				)
			)
		)
		(zone
			(layer "F.Cu")
			(hatch none 0.5)
			(connect_pads
				(clearance 0)
			)
			(min_thickness 0.25)
			(keepout
				(tracks allowed)
				(vias not_allowed)
				(pads allowed)
				(copperpour not_allowed)
				(footprints allowed)
			)
			(placement
				(enabled no)
				(sheetname "")
			)
			(fill
				(thermal_gap 0.5)
				(thermal_bridge_width 0.5)
				(island_removal_mode 0)
			)
			(polygon
				(pts
					(xy 43.37939 -493.88268) (xy 43.37939 -497.84508) (xy 82.77479 -497.84508) (xy 82.80019 -497.84508)
					(xy 82.80019 -493.88268) (xy 82.80019 -493.85728) (xy 43.37939 -493.85728)
				)
			)
		)
		(zone
			(layers "F.Cu" "B.Cu" "In1.Cu" "In2.Cu" "In3.Cu" "In4.Cu" "In5.Cu" "In6.Cu")
			(hatch none 0.5)
			(connect_pads
				(clearance 0)
			)
			(min_thickness 0.25)
			(keepout
				(tracks not_allowed)
				(vias allowed)
				(pads allowed)
				(copperpour not_allowed)
				(footprints allowed)
			)
			(placement
				(enabled no)
				(sheetname "")
			)
			(fill
				(thermal_gap 0.5)
				(thermal_bridge_width 0.5)
				(island_removal_mode 0)
			)
			(polygon
				(pts
					(arc
						(start 43.18 -495.86007)
						(mid 39.81958 -495.86007)
						(end 43.18 -495.86007)
					)
				)
			)
		)
		(zone
			(layers "F.Cu" "B.Cu" "In1.Cu" "In2.Cu" "In3.Cu" "In4.Cu" "In5.Cu" "In6.Cu")
			(hatch none 0.5)
			(connect_pads
				(clearance 0)
			)
			(min_thickness 0.25)
			(keepout
				(tracks not_allowed)
				(vias allowed)
				(pads allowed)
				(copperpour not_allowed)
				(footprints allowed)
			)
			(placement
				(enabled no)
				(sheetname "")
			)
			(fill
				(thermal_gap 0.5)
				(thermal_bridge_width 0.5)
				(island_removal_mode 0)
			)
			(polygon
				(pts
					(arc
						(start 96.52381 -497.21008)
						(mid 93.15577 -497.21008)
						(end 96.52381 -497.21008)
					)
				)
			)
		)
	)
	(footprint ""
		(layer "B.Cu")
		(at 44.03979 -230.51008 90)
		(property "Reference" "J12"
			(at 6.153658 -3.773932 0)
			(unlocked yes)
			(layer "B.SilkS")
			(effects
				(font
					(size 0.7874 0.5842)
					(thickness 0.1524)
				)
				(justify left mirror)
			)
		)
		(property "Value" ""
			(at 0 0 90)
			(layer "B.Fab")
			(effects
				(font
					(size 1.27 1.27)
				)
				(justify mirror)
			)
		)
		(duplicate_pad_numbers_are_jumpers no)
		(fp_line
			(start 5.275072 -13.910056)
			(end -7.975092 -13.910056)
			(stroke
				(width 0.1524)
				(type default)
			)
			(layer "F.SilkS")
		)
		(fp_line
			(start -7.975092 -13.910056)
			(end -7.975092 62.170056)
			(stroke
				(width 0.1524)
				(type default)
			)
			(layer "F.SilkS")
		)
		(fp_line
			(start 5.275072 62.170056)
			(end 5.275072 -13.910056)
			(stroke
				(width 0.1524)
				(type default)
			)
			(layer "F.SilkS")
		)
		(fp_line
			(start -7.975092 62.170056)
			(end 5.275072 62.170056)
			(stroke
				(width 0.1524)
				(type default)
			)
			(layer "F.SilkS")
		)
		(fp_line
			(start 5.275072 -13.910056)
			(end -7.975092 -13.910056)
			(stroke
				(width 0.1524)
				(type default)
			)
			(layer "B.SilkS")
		)
		(fp_line
			(start -7.975092 -13.910056)
			(end -7.975092 62.170056)
			(stroke
				(width 0.1524)
				(type default)
			)
			(layer "B.SilkS")
		)
		(fp_line
			(start 2.275078 -10.910062)
			(end 2.275078 59.170062)
			(stroke
				(width 0.1524)
				(type default)
			)
			(layer "B.SilkS")
		)
		(fp_line
			(start -4.975098 -10.910062)
			(end 2.275078 -10.910062)
			(stroke
				(width 0.1524)
				(type default)
			)
			(layer "B.SilkS")
		)
		(fp_line
			(start 2.275078 59.170062)
			(end -4.975098 59.170062)
			(stroke
				(width 0.1524)
				(type default)
			)
			(layer "B.SilkS")
		)
		(fp_line
			(start -4.975098 59.170062)
			(end -4.975098 -10.910062)
			(stroke
				(width 0.1524)
				(type default)
			)
			(layer "B.SilkS")
		)
		(fp_line
			(start 5.275072 62.170056)
			(end 5.275072 -13.910056)
			(stroke
				(width 0.1524)
				(type default)
			)
			(layer "B.SilkS")
		)
		(fp_line
			(start -7.975092 62.170056)
			(end 5.275072 62.170056)
			(stroke
				(width 0.1524)
				(type default)
			)
			(layer "B.SilkS")
		)
		(fp_poly
			(pts
				(xy 4.103878 -0.759206) (xy 4.103878 0.764794) (xy 2.579878 0.002794)
			)
			(stroke
				(width 0)
				(type default)
			)
			(fill yes)
			(layer "B.SilkS")
		)
		(fp_poly
			(pts
				(xy 2.275078 -10.910062) (xy 2.275078 59.170062) (xy -4.975098 59.170062) (xy -4.975098 -10.910062)
			)
			(stroke
				(width 0)
				(type default)
			)
			(fill no)
			(layer "B.CrtYd")
		)
		(fp_poly
			(pts
				(xy 1.1938 40.9702) (xy 1.1938 48.6156) (xy -3.9116 48.6156) (xy -3.9116 40.9702) (xy -3.9116 40.9448)
				(xy 1.1938 40.9448)
			)
			(stroke
				(width 0)
				(type default)
			)
			(fill no)
			(layer "F.CrtYd")
		)
		(fp_poly
			(pts
				(xy -3.3274 -0.6604) (xy 0.635 -0.6604) (xy 0.635 38.735) (xy 0.635 38.7604) (xy -3.3274 38.7604)
				(xy -3.3528 38.7604) (xy -3.3528 -0.6604)
			)
			(stroke
				(width 0)
				(type default)
			)
			(fill no)
			(layer "F.CrtYd")
		)
		(fp_poly
			(pts
				(arc
					(start -1.35001 -1.01219)
					(mid -1.35001 -4.06781)
					(end -1.35001 -1.01219)
				)
			)
			(stroke
				(width 0)
				(type default)
			)
			(fill no)
			(layer "F.CrtYd")
		)
		(fp_poly
			(pts
				(arc
					(start 0 52.33162)
					(mid 0 49.26838)
					(end 0 52.33162)
				)
			)
			(stroke
				(width 0)
				(type default)
			)
			(fill no)
			(layer "F.CrtYd")
		)
		(fp_line
			(start 2.275078 -10.910062)
			(end 2.275078 59.170062)
			(stroke
				(width 0.1)
				(type default)
			)
			(layer "B.Fab")
		)
		(fp_line
			(start -4.975098 -10.910062)
			(end 2.275078 -10.910062)
			(stroke
				(width 0.1)
				(type default)
			)
			(layer "B.Fab")
		)
		(fp_line
			(start 2.275078 59.170062)
			(end -4.975098 59.170062)
			(stroke
				(width 0.1)
				(type default)
			)
			(layer "B.Fab")
		)
		(fp_line
			(start -4.975098 59.170062)
			(end -4.975098 -10.910062)
			(stroke
				(width 0.1)
				(type default)
			)
			(layer "B.Fab")
		)
		(fp_poly
			(pts
				(xy 4.103878 -0.759206) (xy 4.103878 0.764794) (xy 2.579878 0.002794)
			)
			(stroke
				(width 0)
				(type default)
			)
			(fill yes)
			(layer "B.Fab")
		)
		(fp_line
			(start 5.275072 -13.910056)
			(end -7.975092 -13.910056)
			(stroke
				(width 0.1)
				(type default)
			)
			(layer "F.Fab")
		)
		(fp_line
			(start -7.975092 -13.910056)
			(end -7.975092 62.170056)
			(stroke
				(width 0.1)
				(type default)
			)
			(layer "F.Fab")
		)
		(fp_line
			(start 5.275072 62.170056)
			(end 5.275072 -13.910056)
			(stroke
				(width 0.1)
				(type default)
			)
			(layer "F.Fab")
		)
		(fp_line
			(start -7.975092 62.170056)
			(end 5.275072 62.170056)
			(stroke
				(width 0.1)
				(type default)
			)
			(layer "F.Fab")
		)
		(fp_text user "P32"
			(at -8.861298 -0.466344 0)
			(unlocked yes)
			(layer "F.SilkS")
			(effects
				(font
					(size 0.7874 0.5842)
					(thickness 0.1524)
				)
			)
		)
		(fp_text user "P1"
			(at 6.37794 -0.065278 0)
			(unlocked yes)
			(layer "F.SilkS")
			(effects
				(font
					(size 0.7874 0.5842)
					(thickness 0.1524)
				)
			)
		)
		(fp_text user "PRESS-FIT"
			(at -9.734296 11.81989 0)
			(unlocked yes)
			(layer "F.SilkS")
			(effects
				(font
					(size 0.7874 0.5842)
					(thickness 0.1524)
				)
				(justify left)
			)
		)
		(fp_text user "P16"
			(at 6.310884 36.695888 0)
			(unlocked yes)
			(layer "F.SilkS")
			(effects
				(font
					(size 0.7874 0.5842)
					(thickness 0.1524)
				)
			)
		)
		(fp_text user "P17"
			(at -8.967216 37.91077 0)
			(unlocked yes)
			(layer "F.SilkS")
			(effects
				(font
					(size 0.7874 0.5842)
					(thickness 0.1524)
				)
			)
		)
		(fp_text user "S12"
			(at -9.073388 41.345104 0)
			(unlocked yes)
			(layer "F.SilkS")
			(effects
				(font
					(size 0.7874 0.5842)
					(thickness 0.1524)
				)
			)
		)
		(fp_text user "S1"
			(at 6.17728 41.508172 0)
			(unlocked yes)
			(layer "F.SilkS")
			(effects
				(font
					(size 0.7874 0.5842)
					(thickness 0.1524)
				)
			)
		)
		(fp_text user "S7"
			(at -9.281922 47.823374 0)
			(unlocked yes)
			(layer "F.SilkS")
			(effects
				(font
					(size 0.7874 0.5842)
					(thickness 0.1524)
				)
			)
		)
		(fp_text user "S6"
			(at 6.043676 48.258984 0)
			(unlocked yes)
			(layer "F.SilkS")
			(effects
				(font
					(size 0.7874 0.5842)
					(thickness 0.1524)
				)
			)
		)
		(fp_text user "P1"
			(at 3.060954 -1.497584 0)
			(unlocked yes)
			(layer "B.SilkS")
			(effects
				(font
					(size 0.7874 0.5842)
					(thickness 0.1524)
				)
				(justify mirror)
			)
		)
		(fp_text user "P32"
			(at -5.927344 0.109474 0)
			(unlocked yes)
			(layer "B.SilkS")
			(effects
				(font
					(size 0.7874 0.5842)
					(thickness 0.1524)
				)
				(justify mirror)
			)
		)
		(fp_text user "PRESS-FIT"
			(at -6.743192 17.254474 0)
			(unlocked yes)
			(layer "B.SilkS")
			(effects
				(font
					(size 0.7874 0.5842)
					(thickness 0.1524)
				)
				(justify left mirror)
			)
		)
		(fp_text user "P17"
			(at -5.677916 37.79774 0)
			(unlocked yes)
			(layer "B.SilkS")
			(effects
				(font
					(size 0.7874 0.5842)
					(thickness 0.1524)
				)
				(justify mirror)
			)
		)
		(fp_text user "P16"
			(at 2.911094 37.867336 0)
			(unlocked yes)
			(layer "B.SilkS")
			(effects
				(font
					(size 0.7874 0.5842)
					(thickness 0.1524)
				)
				(justify mirror)
			)
		)
		(fp_text user "S1"
			(at 2.94005 41.810178 0)
			(unlocked yes)
			(layer "B.SilkS")
			(effects
				(font
					(size 0.7874 0.5842)
					(thickness 0.1524)
				)
				(justify mirror)
			)
		)
		(fp_text user "S12"
			(at -5.724652 41.924732 0)
			(unlocked yes)
			(layer "B.SilkS")
			(effects
				(font
					(size 0.7874 0.5842)
					(thickness 0.1524)
				)
				(justify mirror)
			)
		)
		(fp_text user "S7"
			(at -5.584952 45.016166 0)
			(unlocked yes)
			(layer "B.SilkS")
			(effects
				(font
					(size 0.7874 0.5842)
					(thickness 0.1524)
				)
				(justify mirror)
			)
		)
		(fp_text user "S6"
			(at 2.970276 47.91583 0)
			(unlocked yes)
			(layer "B.SilkS")
			(effects
				(font
					(size 0.7874 0.5842)
					(thickness 0.1524)
				)
				(justify mirror)
			)
		)
		(fp_text user "P1"
			(at 3.108452 -1.27 180)
			(unlocked yes)
			(layer "B.Fab")
			(effects
				(font
					(size 0.7874 0.5842)
					(thickness 0.000001)
				)
				(justify mirror)
			)
		)
		(fp_text user "P32"
			(at -5.781548 -0.0508 180)
			(unlocked yes)
			(layer "B.Fab")
			(effects
				(font
					(size 0.7874 0.5842)
					(thickness 0.000001)
				)
				(justify mirror)
			)
		)
		(fp_text user "PRESS-FIT"
			(at -6.82371 29.8831 0)
			(unlocked yes)
			(layer "B.Fab")
			(effects
				(font
					(size 1.6002 1.1938)
					(thickness 0.000001)
				)
				(justify left mirror)
			)
		)
		(fp_text user "P17"
			(at -5.72135 38.0746 180)
			(unlocked yes)
			(layer "B.Fab")
			(effects
				(font
					(size 0.7874 0.5842)
					(thickness 0.000001)
				)
				(justify mirror)
			)
		)
		(fp_text user "P16"
			(at 3.159252 38.3794 180)
			(unlocked yes)
			(layer "B.Fab")
			(effects
				(font
					(size 0.7874 0.5842)
					(thickness 0.000001)
				)
				(justify mirror)
			)
		)
		(fp_text user "S12"
			(at -5.79374 41.42232 180)
			(unlocked yes)
			(layer "B.Fab")
			(effects
				(font
					(size 0.7874 0.5842)
					(thickness 0.000001)
				)
				(justify mirror)
			)
		)
		(fp_text user "S1"
			(at 3.09626 41.656 180)
			(unlocked yes)
			(layer "B.Fab")
			(effects
				(font
					(size 0.7874 0.5842)
					(thickness 0.000001)
				)
				(justify mirror)
			)
		)
		(fp_text user "S6"
			(at 3.133852 48.0822 180)
			(unlocked yes)
			(layer "B.Fab")
			(effects
				(font
					(size 0.7874 0.5842)
					(thickness 0.000001)
				)
				(justify mirror)
			)
		)
		(fp_text user "S7"
			(at -5.781548 48.0822 180)
			(unlocked yes)
			(layer "B.Fab")
			(effects
				(font
					(size 0.7874 0.5842)
					(thickness 0.000001)
				)
				(justify mirror)
			)
		)
		(fp_text user "P32"
			(at -4.071112 -0.0762 180)
			(unlocked yes)
			(layer "F.Fab")
			(effects
				(font
					(size 0.7874 0.5842)
					(thickness 0.000001)
				)
			)
		)
		(fp_text user "P1"
			(at 1.516888 0 180)
			(unlocked yes)
			(layer "F.Fab")
			(effects
				(font
					(size 0.7874 0.5842)
					(thickness 0.000001)
				)
			)
		)
		(fp_text user "PRESS-FIT"
			(at -6.762496 16.251428 0)
			(unlocked yes)
			(layer "F.Fab")
			(effects
				(font
					(size 1.6002 1.1938)
					(thickness 0.000001)
				)
				(justify left)
			)
		)
		(fp_text user "P17"
			(at -4.366768 38.227 180)
			(unlocked yes)
			(layer "F.Fab")
			(effects
				(font
					(size 0.7874 0.5842)
					(thickness 0.000001)
				)
			)
		)
		(fp_text user "P16"
			(at 2.228088 38.354 180)
			(unlocked yes)
			(layer "F.Fab")
			(effects
				(font
					(size 0.7874 0.5842)
					(thickness 0.000001)
				)
			)
		)
		(fp_text user "S12"
			(at -4.362958 41.09212 180)
			(unlocked yes)
			(layer "F.Fab")
			(effects
				(font
					(size 0.7874 0.5842)
					(thickness 0.000001)
				)
			)
		)
		(fp_text user "S1"
			(at 2.164842 41.6306 180)
			(unlocked yes)
			(layer "F.Fab")
			(effects
				(font
					(size 0.7874 0.5842)
					(thickness 0.000001)
				)
			)
		)
		(fp_text user "S6"
			(at 1.923288 48.133 180)
			(unlocked yes)
			(layer "F.Fab")
			(effects
				(font
					(size 0.7874 0.5842)
					(thickness 0.000001)
				)
			)
		)
		(fp_text user "S7"
			(at -4.426712 48.2346 180)
			(unlocked yes)
			(layer "F.Fab")
			(effects
				(font
					(size 0.7874 0.5842)
					(thickness 0.000001)
				)
			)
		)
		(pad "" np_thru_hole circle
			(at -1.35001 -2.54)
			(size 2.5146 2.5146)
			(drill 2.5146)
			(layers "*.Cu" "*.Mask")
			(clearance 0.381)
			(thermal_gap 0.381)
		)
		(pad "" np_thru_hole circle
			(at 0 50.8)
			(size 2.5146 2.5146)
			(drill 2.5146)
			(layers "*.Cu" "*.Mask")
			(clearance 0.381)
			(thermal_gap 0.381)
		)
		(pad "P1" thru_hole rect
			(at 0 0)
			(size 1.1684 1.1684)
			(drill 0.762)
			(layers "*.Cu" "*.Mask")
			(remove_unused_layers no)
			(net "GND")
			(clearance 0.0508)
			(padstack
				(mode front_inner_back)
				(layer "Inner"
					(shape circle)
					(size 1.1684 1.1684)
					(clearance 0.0508)
				)
				(layer "B.Cu"
					(shape rect)
					(size 1.1684 1.1684)
					(thermal_gap 0.0508)
					(clearance 0.0508)
				)
			)
		)
		(pad "P2" thru_hole circle
			(at 0 2.54)
			(size 1.1684 1.1684)
			(drill 0.762)
			(layers "*.Cu" "*.Mask")
			(remove_unused_layers no)
			(net "GND")
			(clearance 0.0508)
			(thermal_gap 0.0508)
		)
		(pad "P3" thru_hole circle
			(at 0 5.08)
			(size 1.1684 1.1684)
			(drill 0.762)
			(layers "*.Cu" "*.Mask")
			(remove_unused_layers no)
			(net "GND")
			(clearance 0.0508)
			(thermal_gap 0.0508)
		)
		(pad "P4" thru_hole circle
			(at 0 7.62)
			(size 1.1684 1.1684)
			(drill 0.762)
			(layers "*.Cu" "*.Mask")
			(remove_unused_layers no)
			(net "GND")
			(clearance 0.0508)
			(thermal_gap 0.0508)
		)
		(pad "P5" thru_hole circle
			(at 0 10.16)
			(size 1.1684 1.1684)
			(drill 0.762)
			(layers "*.Cu" "*.Mask")
			(remove_unused_layers no)
			(net "GND")
			(clearance 0.0508)
			(thermal_gap 0.0508)
		)
		(pad "P6" thru_hole circle
			(at 0 12.7)
			(size 1.1684 1.1684)
			(drill 0.762)
			(layers "*.Cu" "*.Mask")
			(remove_unused_layers no)
			(net "GND")
			(clearance 0.0508)
			(thermal_gap 0.0508)
		)
		(pad "P7" thru_hole circle
			(at 0 15.24)
			(size 1.1684 1.1684)
			(drill 0.762)
			(layers "*.Cu" "*.Mask")
			(remove_unused_layers no)
			(net "GND")
			(clearance 0.0508)
			(thermal_gap 0.0508)
		)
		(pad "P8" thru_hole circle
			(at 0 17.78)
			(size 1.1684 1.1684)
			(drill 0.762)
			(layers "*.Cu" "*.Mask")
			(remove_unused_layers no)
			(net "GND")
			(clearance 0.0508)
			(thermal_gap 0.0508)
		)
		(pad "P9" thru_hole circle
			(at 0 20.32)
			(size 1.1684 1.1684)
			(drill 0.762)
			(layers "*.Cu" "*.Mask")
			(remove_unused_layers no)
			(net "P12V")
			(clearance 0.0508)
			(thermal_gap 0.0508)
		)
		(pad "P10" thru_hole circle
			(at 0 22.86)
			(size 1.1684 1.1684)
			(drill 0.762)
			(layers "*.Cu" "*.Mask")
			(remove_unused_layers no)
			(net "P12V")
			(clearance 0.0508)
			(thermal_gap 0.0508)
		)
		(pad "P11" thru_hole circle
			(at 0 25.4)
			(size 1.1684 1.1684)
			(drill 0.762)
			(layers "*.Cu" "*.Mask")
			(remove_unused_layers no)
			(net "P12V")
			(clearance 0.0508)
			(thermal_gap 0.0508)
		)
		(pad "P12" thru_hole circle
			(at 0 27.94)
			(size 1.1684 1.1684)
			(drill 0.762)
			(layers "*.Cu" "*.Mask")
			(remove_unused_layers no)
			(net "P12V")
			(clearance 0.0508)
			(thermal_gap 0.0508)
		)
		(pad "P13" thru_hole circle
			(at 0 30.48)
			(size 1.1684 1.1684)
			(drill 0.762)
			(layers "*.Cu" "*.Mask")
			(remove_unused_layers no)
			(net "P12V")
			(clearance 0.0508)
			(thermal_gap 0.0508)
		)
		(pad "P14" thru_hole circle
			(at 0 33.02)
			(size 1.1684 1.1684)
			(drill 0.762)
			(layers "*.Cu" "*.Mask")
			(remove_unused_layers no)
			(net "P12V")
			(clearance 0.0508)
			(thermal_gap 0.0508)
		)
		(pad "P15" thru_hole circle
			(at 0 35.56)
			(size 1.1684 1.1684)
			(drill 0.762)
			(layers "*.Cu" "*.Mask")
			(remove_unused_layers no)
			(net "P12V")
			(clearance 0.0508)
			(thermal_gap 0.0508)
		)
		(pad "P16" thru_hole circle
			(at 0 38.1)
			(size 1.1684 1.1684)
			(drill 0.762)
			(layers "*.Cu" "*.Mask")
			(remove_unused_layers no)
			(net "P12V")
			(clearance 0.0508)
			(thermal_gap 0.0508)
		)
		(pad "P17" thru_hole circle
			(at -2.70002 38.1)
			(size 1.1684 1.1684)
			(drill 0.762)
			(layers "*.Cu" "*.Mask")
			(remove_unused_layers no)
			(net "P12V")
			(clearance 0.0508)
			(thermal_gap 0.0508)
		)
		(pad "P18" thru_hole circle
			(at -2.70002 35.56)
			(size 1.1684 1.1684)
			(drill 0.762)
			(layers "*.Cu" "*.Mask")
			(remove_unused_layers no)
			(net "P12V")
			(clearance 0.0508)
			(thermal_gap 0.0508)
		)
		(pad "P19" thru_hole circle
			(at -2.70002 33.02)
			(size 1.1684 1.1684)
			(drill 0.762)
			(layers "*.Cu" "*.Mask")
			(remove_unused_layers no)
			(net "P12V")
			(clearance 0.0508)
			(thermal_gap 0.0508)
		)
		(pad "P20" thru_hole circle
			(at -2.70002 30.48)
			(size 1.1684 1.1684)
			(drill 0.762)
			(layers "*.Cu" "*.Mask")
			(remove_unused_layers no)
			(net "P12V")
			(clearance 0.0508)
			(thermal_gap 0.0508)
		)
		(pad "P21" thru_hole circle
			(at -2.70002 27.94)
			(size 1.1684 1.1684)
			(drill 0.762)
			(layers "*.Cu" "*.Mask")
			(remove_unused_layers no)
			(net "P12V")
			(clearance 0.0508)
			(thermal_gap 0.0508)
		)
		(pad "P22" thru_hole circle
			(at -2.70002 25.4)
			(size 1.1684 1.1684)
			(drill 0.762)
			(layers "*.Cu" "*.Mask")
			(remove_unused_layers no)
			(net "P12V")
			(clearance 0.0508)
			(thermal_gap 0.0508)
		)
		(pad "P23" thru_hole circle
			(at -2.70002 22.86)
			(size 1.1684 1.1684)
			(drill 0.762)
			(layers "*.Cu" "*.Mask")
			(remove_unused_layers no)
			(net "P12V")
			(clearance 0.0508)
			(thermal_gap 0.0508)
		)
		(pad "P24" thru_hole circle
			(at -2.70002 20.32)
			(size 1.1684 1.1684)
			(drill 0.762)
			(layers "*.Cu" "*.Mask")
			(remove_unused_layers no)
			(net "P12V")
			(clearance 0.0508)
			(thermal_gap 0.0508)
		)
		(pad "P25" thru_hole circle
			(at -2.70002 17.78)
			(size 1.1684 1.1684)
			(drill 0.762)
			(layers "*.Cu" "*.Mask")
			(remove_unused_layers no)
			(net "GND")
			(clearance 0.0508)
			(thermal_gap 0.0508)
		)
		(pad "P26" thru_hole circle
			(at -2.70002 15.24)
			(size 1.1684 1.1684)
			(drill 0.762)
			(layers "*.Cu" "*.Mask")
			(remove_unused_layers no)
			(net "GND")
			(clearance 0.0508)
			(thermal_gap 0.0508)
		)
		(pad "P27" thru_hole circle
			(at -2.70002 12.7)
			(size 1.1684 1.1684)
			(drill 0.762)
			(layers "*.Cu" "*.Mask")
			(remove_unused_layers no)
			(net "GND")
			(clearance 0.0508)
			(thermal_gap 0.0508)
		)
		(pad "P28" thru_hole circle
			(at -2.70002 10.16)
			(size 1.1684 1.1684)
			(drill 0.762)
			(layers "*.Cu" "*.Mask")
			(remove_unused_layers no)
			(net "GND")
			(clearance 0.0508)
			(thermal_gap 0.0508)
		)
		(pad "P29" thru_hole circle
			(at -2.70002 7.62)
			(size 1.1684 1.1684)
			(drill 0.762)
			(layers "*.Cu" "*.Mask")
			(remove_unused_layers no)
			(net "GND")
			(clearance 0.0508)
			(thermal_gap 0.0508)
		)
		(pad "P30" thru_hole circle
			(at -2.70002 5.08)
			(size 1.1684 1.1684)
			(drill 0.762)
			(layers "*.Cu" "*.Mask")
			(remove_unused_layers no)
			(net "GND")
			(clearance 0.0508)
			(thermal_gap 0.0508)
		)
		(pad "P31" thru_hole circle
			(at -2.70002 2.54)
			(size 1.1684 1.1684)
			(drill 0.762)
			(layers "*.Cu" "*.Mask")
			(remove_unused_layers no)
			(net "GND")
			(clearance 0.0508)
			(thermal_gap 0.0508)
		)
		(pad "P32" thru_hole circle
			(at -2.70002 0)
			(size 1.1684 1.1684)
			(drill 0.762)
			(layers "*.Cu" "*.Mask")
			(remove_unused_layers no)
			(net "GND")
			(clearance 0.0508)
			(thermal_gap 0.0508)
		)
		(pad "S1" thru_hole circle
			(at 0.55499 41.60012)
			(size 1.1684 1.1684)
			(drill 0.762)
			(layers "*.Cu" "*.Mask")
			(remove_unused_layers no)
			(net "T6_BLAD1_TXD")
			(clearance 0.0508)
			(thermal_gap 0.0508)
		)
		(pad "S2" thru_hole circle
			(at -0.71501 42.87012)
			(size 1.1684 1.1684)
			(drill 0.762)
			(layers "*.Cu" "*.Mask")
			(remove_unused_layers no)
			(net "T6_BLAD1_RXD")
			(clearance 0.0508)
			(thermal_gap 0.0508)
		)
		(pad "S3" thru_hole circle
			(at 0.55499 44.14012)
			(size 1.1684 1.1684)
			(drill 0.762)
			(layers "*.Cu" "*.Mask")
			(remove_unused_layers no)
			(net "T6_BLAD1_EN")
			(clearance 0.0508)
			(thermal_gap 0.0508)
		)
		(pad "S4" thru_hole circle
			(at -0.71501 45.41012)
			(size 1.1684 1.1684)
			(drill 0.762)
			(layers "*.Cu" "*.Mask")
			(remove_unused_layers no)
			(net "B11_PSU_ALERT_N")
			(clearance 0.0508)
			(thermal_gap 0.0508)
		)
		(pad "S5" thru_hole circle
			(at 0.55499 46.68012)
			(size 1.1684 1.1684)
			(drill 0.762)
			(layers "*.Cu" "*.Mask")
			(remove_unused_layers no)
			(net "T6_BLAD2_TXD")
			(clearance 0.0508)
			(thermal_gap 0.0508)
		)
		(pad "S6" thru_hole circle
			(at -0.71501 47.95012)
			(size 1.1684 1.1684)
			(drill 0.762)
			(layers "*.Cu" "*.Mask")
			(remove_unused_layers no)
			(net "T6_BLAD2_RXD")
			(clearance 0.0508)
			(thermal_gap 0.0508)
		)
		(pad "S7" thru_hole circle
			(at -3.25501 47.95012)
			(size 1.1684 1.1684)
			(drill 0.762)
			(layers "*.Cu" "*.Mask")
			(remove_unused_layers no)
			(net "T6_BLAD4_RXD")
			(clearance 0.0508)
			(thermal_gap 0.0508)
		)
		(pad "S8" thru_hole circle
			(at -1.98501 46.68012)
			(size 1.1684 1.1684)
			(drill 0.762)
			(layers "*.Cu" "*.Mask")
			(remove_unused_layers no)
			(net "T6_BLAD4_TXD")
			(clearance 0.0508)
			(thermal_gap 0.0508)
		)
		(pad "S9" thru_hole circle
			(at -3.25501 45.41012)
			(size 1.1684 1.1684)
			(drill 0.762)
			(layers "*.Cu" "*.Mask")
			(remove_unused_layers no)
			(net "B12_PSU_ALERT_N")
			(clearance 0.0508)
			(thermal_gap 0.0508)
		)
		(pad "S10" thru_hole circle
			(at -1.98501 44.14012)
			(size 1.1684 1.1684)
			(drill 0.762)
			(layers "*.Cu" "*.Mask")
			(remove_unused_layers no)
			(net "T6_BLAD3_EN")
			(clearance 0.0508)
			(thermal_gap 0.0508)
		)
		(pad "S11" thru_hole circle
			(at -3.25501 42.87012)
			(size 1.1684 1.1684)
			(drill 0.762)
			(layers "*.Cu" "*.Mask")
			(remove_unused_layers no)
			(net "T6_BLAD3_RXD")
			(clearance 0.0508)
			(thermal_gap 0.0508)
		)
		(pad "S12" thru_hole circle
			(at -1.98501 41.60012)
			(size 1.1684 1.1684)
			(drill 0.762)
			(layers "*.Cu" "*.Mask")
			(remove_unused_layers no)
			(net "T6_BLAD3_TXD")
			(clearance 0.0508)
			(thermal_gap 0.0508)
		)
		(zone
			(layer "F.Cu")
			(hatch none 0.5)
			(connect_pads
				(clearance 0)
			)
			(min_thickness 0.25)
			(keepout
				(tracks allowed)
				(vias not_allowed)
				(pads allowed)
				(copperpour not_allowed)
				(footprints allowed)
			)
			(placement
				(enabled no)
				(sheetname "")
			)
			(fill
				(thermal_gap 0.5)
				(thermal_bridge_width 0.5)
				(island_removal_mode 0)
			)
			(polygon
				(pts
					(xy 85.00999 -231.70388) (xy 92.65539 -231.70388) (xy 92.65539 -226.59848) (xy 85.00999 -226.59848)
					(xy 84.98459 -226.59848) (xy 84.98459 -231.70388)
				)
			)
		)
		(zone
			(layer "F.Cu")
			(hatch none 0.5)
			(connect_pads
				(clearance 0)
			)
			(min_thickness 0.25)
			(keepout
				(tracks allowed)
				(vias not_allowed)
				(pads allowed)
				(copperpour not_allowed)
				(footprints allowed)
			)
			(placement
				(enabled no)
				(sheetname "")
			)
			(fill
				(thermal_gap 0.5)
				(thermal_bridge_width 0.5)
				(island_removal_mode 0)
			)
			(polygon
				(pts
					(xy 43.37939 -227.18268) (xy 43.37939 -231.14508) (xy 82.77479 -231.14508) (xy 82.80019 -231.14508)
					(xy 82.80019 -227.18268) (xy 82.80019 -227.15728) (xy 43.37939 -227.15728)
				)
			)
		)
		(zone
			(layers "F.Cu" "B.Cu" "In1.Cu" "In2.Cu" "In3.Cu" "In4.Cu" "In5.Cu" "In6.Cu")
			(hatch none 0.5)
			(connect_pads
				(clearance 0)
			)
			(min_thickness 0.25)
			(keepout
				(tracks not_allowed)
				(vias allowed)
				(pads allowed)
				(copperpour not_allowed)
				(footprints allowed)
			)
			(placement
				(enabled no)
				(sheetname "")
			)
			(fill
				(thermal_gap 0.5)
				(thermal_bridge_width 0.5)
				(island_removal_mode 0)
			)
			(polygon
				(pts
					(arc
						(start 43.18 -229.16007)
						(mid 39.81958 -229.16007)
						(end 43.18 -229.16007)
					)
				)
			)
		)
		(zone
			(layers "F.Cu" "B.Cu" "In1.Cu" "In2.Cu" "In3.Cu" "In4.Cu" "In5.Cu" "In6.Cu")
			(hatch none 0.5)
			(connect_pads
				(clearance 0)
			)
			(min_thickness 0.25)
			(keepout
				(tracks not_allowed)
				(vias allowed)
				(pads allowed)
				(copperpour not_allowed)
				(footprints allowed)
			)
			(placement
				(enabled no)
				(sheetname "")
			)
			(fill
				(thermal_gap 0.5)
				(thermal_bridge_width 0.5)
				(island_removal_mode 0)
			)
			(polygon
				(pts
					(arc
						(start 96.52381 -230.51008)
						(mid 93.15577 -230.51008)
						(end 96.52381 -230.51008)
					)
				)
			)
		)
	)
	(footprint ""
		(layer "B.Cu")
		(at 98.156268 -349.954596 180)
		(property "Reference" "C95"
			(at -1.279906 1.42621 0)
			(unlocked yes)
			(layer "B.SilkS")
			(effects
				(font
					(size 0.7874 0.5842)
					(thickness 0.1524)
				)
				(justify left mirror)
			)
		)
		(property "Value" ""
			(at 0 0 0)
			(layer "B.Fab")
			(effects
				(font
					(size 1.27 1.27)
				)
				(justify mirror)
			)
		)
		(duplicate_pad_numbers_are_jumpers no)
		(fp_line
			(start 0.7874 0.4064)
			(end 0.7874 -0.4064)
			(stroke
				(width 0.1524)
				(type default)
			)
			(layer "B.SilkS")
		)
		(fp_line
			(start 0.7874 -0.4064)
			(end -0.7874 -0.4064)
			(stroke
				(width 0.1524)
				(type default)
			)
			(layer "B.SilkS")
		)
		(fp_line
			(start 0 0.381)
			(end 0 -0.381)
			(stroke
				(width 0.1524)
				(type default)
			)
			(layer "B.SilkS")
		)
		(fp_line
			(start -0.7874 0.4064)
			(end 0.7874 0.4064)
			(stroke
				(width 0.1524)
				(type default)
			)
			(layer "B.SilkS")
		)
		(fp_line
			(start -0.7874 -0.4064)
			(end -0.7874 0.4064)
			(stroke
				(width 0.1524)
				(type default)
			)
			(layer "B.SilkS")
		)
		(fp_poly
			(pts
				(xy 0.5334 0.254) (xy 0.635 0.254) (xy 0.635 0.2286) (xy 0.635 -0.254) (xy 0.5334 -0.254) (xy 0.5334 -0.2794)
				(xy -0.5334 -0.2794) (xy -0.5334 -0.254) (xy -0.635 -0.254) (xy -0.635 0.254) (xy -0.5334 0.254)
				(xy -0.5334 0.2794) (xy 0.508 0.2794) (xy 0.5334 0.2794)
			)
			(stroke
				(width 0)
				(type default)
			)
			(fill no)
			(layer "B.CrtYd")
		)
		(pad "1" smd rect
			(at -0.40005 0)
			(size 0.4572 0.508)
			(layers "B.Cu" "B.Mask" "B.Paste")
			(net "P3V3_BUF")
		)
		(pad "2" smd rect
			(at 0.40005 0)
			(size 0.4572 0.508)
			(layers "B.Cu" "B.Mask" "B.Paste")
			(net "GND")
		)
	)
	(footprint ""
		(layer "B.Cu")
		(at 96.75241 -84.351622 90)
		(property "Reference" "R162"
			(at -1.935988 2.417318 270)
			(unlocked yes)
			(layer "B.SilkS")
			(effects
				(font
					(size 0.7874 0.5842)
					(thickness 0.1524)
				)
				(justify left mirror)
			)
		)
		(property "Value" ""
			(at 0 0 90)
			(layer "B.Fab")
			(effects
				(font
					(size 1.27 1.27)
				)
				(justify mirror)
			)
		)
		(duplicate_pad_numbers_are_jumpers no)
		(fp_line
			(start 0.7874 -0.4064)
			(end -0.7874 -0.4064)
			(stroke
				(width 0.1524)
				(type default)
			)
			(layer "B.SilkS")
		)
		(fp_line
			(start -0.7874 -0.4064)
			(end -0.7874 0.4064)
			(stroke
				(width 0.1524)
				(type default)
			)
			(layer "B.SilkS")
		)
		(fp_line
			(start 0.7874 0.4064)
			(end 0.7874 -0.4064)
			(stroke
				(width 0.1524)
				(type default)
			)
			(layer "B.SilkS")
		)
		(fp_line
			(start -0.7874 0.4064)
			(end 0.7874 0.4064)
			(stroke
				(width 0.1524)
				(type default)
			)
			(layer "B.SilkS")
		)
		(fp_poly
			(pts
				(xy 0.508 0.2794) (xy 0.508 0.2286) (xy 0.635 0.2286) (xy 0.635 -0.254) (xy 0.5334 -0.254) (xy 0.5334 -0.2794)
				(xy -0.5334 -0.2794) (xy -0.5334 -0.254) (xy -0.635 -0.254) (xy -0.635 0.254) (xy -0.5334 0.254)
				(xy -0.5334 0.2794)
			)
			(stroke
				(width 0)
				(type default)
			)
			(fill no)
			(layer "B.CrtYd")
		)
		(pad "1" smd rect
			(at -0.40005 0 270)
			(size 0.4572 0.508)
			(layers "B.Cu" "B.Mask" "B.Paste")
			(net "P3V3_BUF")
		)
		(pad "2" smd rect
			(at 0.40005 0 270)
			(size 0.4572 0.508)
			(layers "B.Cu" "B.Mask" "B.Paste")
			(net "PSU_ALERT_N")
		)
	)
	(footprint ""
		(layer "B.Cu")
		(at 44.03979 -319.41008 90)
		(property "Reference" "J14"
			(at 6.291834 -4.21005 0)
			(unlocked yes)
			(layer "B.SilkS")
			(effects
				(font
					(size 0.7874 0.5842)
					(thickness 0.1524)
				)
				(justify left mirror)
			)
		)
		(property "Value" ""
			(at 0 0 90)
			(layer "B.Fab")
			(effects
				(font
					(size 1.27 1.27)
				)
				(justify mirror)
			)
		)
		(duplicate_pad_numbers_are_jumpers no)
		(fp_line
			(start 5.275072 -13.910056)
			(end -7.975092 -13.910056)
			(stroke
				(width 0.1524)
				(type default)
			)
			(layer "F.SilkS")
		)
		(fp_line
			(start -7.975092 -13.910056)
			(end -7.975092 62.170056)
			(stroke
				(width 0.1524)
				(type default)
			)
			(layer "F.SilkS")
		)
		(fp_line
			(start 5.275072 62.170056)
			(end 5.275072 -13.910056)
			(stroke
				(width 0.1524)
				(type default)
			)
			(layer "F.SilkS")
		)
		(fp_line
			(start -7.975092 62.170056)
			(end 5.275072 62.170056)
			(stroke
				(width 0.1524)
				(type default)
			)
			(layer "F.SilkS")
		)
		(fp_line
			(start 5.275072 -13.910056)
			(end -7.975092 -13.910056)
			(stroke
				(width 0.1524)
				(type default)
			)
			(layer "B.SilkS")
		)
		(fp_line
			(start -7.975092 -13.910056)
			(end -7.975092 62.170056)
			(stroke
				(width 0.1524)
				(type default)
			)
			(layer "B.SilkS")
		)
		(fp_line
			(start 2.275078 -10.910062)
			(end 2.275078 59.170062)
			(stroke
				(width 0.1524)
				(type default)
			)
			(layer "B.SilkS")
		)
		(fp_line
			(start -4.975098 -10.910062)
			(end 2.275078 -10.910062)
			(stroke
				(width 0.1524)
				(type default)
			)
			(layer "B.SilkS")
		)
		(fp_line
			(start 2.275078 59.170062)
			(end -4.975098 59.170062)
			(stroke
				(width 0.1524)
				(type default)
			)
			(layer "B.SilkS")
		)
		(fp_line
			(start -4.975098 59.170062)
			(end -4.975098 -10.910062)
			(stroke
				(width 0.1524)
				(type default)
			)
			(layer "B.SilkS")
		)
		(fp_line
			(start 5.275072 62.170056)
			(end 5.275072 -13.910056)
			(stroke
				(width 0.1524)
				(type default)
			)
			(layer "B.SilkS")
		)
		(fp_line
			(start -7.975092 62.170056)
			(end 5.275072 62.170056)
			(stroke
				(width 0.1524)
				(type default)
			)
			(layer "B.SilkS")
		)
		(fp_poly
			(pts
				(xy 4.103878 -0.759206) (xy 4.103878 0.764794) (xy 2.579878 0.002794)
			)
			(stroke
				(width 0)
				(type default)
			)
			(fill yes)
			(layer "B.SilkS")
		)
		(fp_poly
			(pts
				(xy 2.275078 -10.910062) (xy 2.275078 59.170062) (xy -4.975098 59.170062) (xy -4.975098 -10.910062)
			)
			(stroke
				(width 0)
				(type default)
			)
			(fill no)
			(layer "B.CrtYd")
		)
		(fp_poly
			(pts
				(xy 1.1938 40.9702) (xy 1.1938 48.6156) (xy -3.9116 48.6156) (xy -3.9116 40.9702) (xy -3.9116 40.9448)
				(xy 1.1938 40.9448)
			)
			(stroke
				(width 0)
				(type default)
			)
			(fill no)
			(layer "F.CrtYd")
		)
		(fp_poly
			(pts
				(xy -3.3274 -0.6604) (xy 0.635 -0.6604) (xy 0.635 38.735) (xy 0.635 38.7604) (xy -3.3274 38.7604)
				(xy -3.3528 38.7604) (xy -3.3528 -0.6604)
			)
			(stroke
				(width 0)
				(type default)
			)
			(fill no)
			(layer "F.CrtYd")
		)
		(fp_poly
			(pts
				(arc
					(start -1.35001 -1.01219)
					(mid -1.35001 -4.06781)
					(end -1.35001 -1.01219)
				)
			)
			(stroke
				(width 0)
				(type default)
			)
			(fill no)
			(layer "F.CrtYd")
		)
		(fp_poly
			(pts
				(arc
					(start 0 52.33162)
					(mid 0 49.26838)
					(end 0 52.33162)
				)
			)
			(stroke
				(width 0)
				(type default)
			)
			(fill no)
			(layer "F.CrtYd")
		)
		(fp_line
			(start 2.275078 -10.910062)
			(end 2.275078 59.170062)
			(stroke
				(width 0.1)
				(type default)
			)
			(layer "B.Fab")
		)
		(fp_line
			(start -4.975098 -10.910062)
			(end 2.275078 -10.910062)
			(stroke
				(width 0.1)
				(type default)
			)
			(layer "B.Fab")
		)
		(fp_line
			(start 2.275078 59.170062)
			(end -4.975098 59.170062)
			(stroke
				(width 0.1)
				(type default)
			)
			(layer "B.Fab")
		)
		(fp_line
			(start -4.975098 59.170062)
			(end -4.975098 -10.910062)
			(stroke
				(width 0.1)
				(type default)
			)
			(layer "B.Fab")
		)
		(fp_poly
			(pts
				(xy 4.103878 -0.759206) (xy 4.103878 0.764794) (xy 2.579878 0.002794)
			)
			(stroke
				(width 0)
				(type default)
			)
			(fill yes)
			(layer "B.Fab")
		)
		(fp_line
			(start 5.275072 -13.910056)
			(end -7.975092 -13.910056)
			(stroke
				(width 0.1)
				(type default)
			)
			(layer "F.Fab")
		)
		(fp_line
			(start -7.975092 -13.910056)
			(end -7.975092 62.170056)
			(stroke
				(width 0.1)
				(type default)
			)
			(layer "F.Fab")
		)
		(fp_line
			(start 5.275072 62.170056)
			(end 5.275072 -13.910056)
			(stroke
				(width 0.1)
				(type default)
			)
			(layer "F.Fab")
		)
		(fp_line
			(start -7.975092 62.170056)
			(end 5.275072 62.170056)
			(stroke
				(width 0.1)
				(type default)
			)
			(layer "F.Fab")
		)
		(fp_text user "P32"
			(at -9.100312 -0.1651 0)
			(unlocked yes)
			(layer "F.SilkS")
			(effects
				(font
					(size 0.7874 0.5842)
					(thickness 0.1524)
				)
			)
		)
		(fp_text user "P1"
			(at 6.27253 -0.031496 0)
			(unlocked yes)
			(layer "F.SilkS")
			(effects
				(font
					(size 0.7874 0.5842)
					(thickness 0.1524)
				)
			)
		)
		(fp_text user "PRESS-FIT"
			(at -9.03351 9.860534 0)
			(unlocked yes)
			(layer "F.SilkS")
			(effects
				(font
					(size 0.7874 0.5842)
					(thickness 0.1524)
				)
				(justify left)
			)
		)
		(fp_text user "P17"
			(at -9.28243 37.648896 0)
			(unlocked yes)
			(layer "F.SilkS")
			(effects
				(font
					(size 0.7874 0.5842)
					(thickness 0.1524)
				)
			)
		)
		(fp_text user "P16"
			(at 7.168642 38.070282 0)
			(unlocked yes)
			(layer "F.SilkS")
			(effects
				(font
					(size 0.7874 0.5842)
					(thickness 0.1524)
				)
			)
		)
		(fp_text user "S12"
			(at -9.044178 40.92067 0)
			(unlocked yes)
			(layer "F.SilkS")
			(effects
				(font
					(size 0.7874 0.5842)
					(thickness 0.1524)
				)
			)
		)
		(fp_text user "S1"
			(at 7.168642 41.691814 0)
			(unlocked yes)
			(layer "F.SilkS")
			(effects
				(font
					(size 0.7874 0.5842)
					(thickness 0.1524)
				)
			)
		)
		(fp_text user "S6"
			(at 6.11251 47.855886 0)
			(unlocked yes)
			(layer "F.SilkS")
			(effects
				(font
					(size 0.7874 0.5842)
					(thickness 0.1524)
				)
			)
		)
		(fp_text user "S7"
			(at -8.957818 47.91075 0)
			(unlocked yes)
			(layer "F.SilkS")
			(effects
				(font
					(size 0.7874 0.5842)
					(thickness 0.1524)
				)
			)
		)
		(fp_text user "P1"
			(at 3.191764 -1.633982 0)
			(unlocked yes)
			(layer "B.SilkS")
			(effects
				(font
					(size 0.7874 0.5842)
					(thickness 0.1524)
				)
				(justify mirror)
			)
		)
		(fp_text user "P32"
			(at -5.830316 -0.19685 0)
			(unlocked yes)
			(layer "B.SilkS")
			(effects
				(font
					(size 0.7874 0.5842)
					(thickness 0.1524)
				)
				(justify mirror)
			)
		)
		(fp_text user "PRESS-FIT"
			(at -7.18947 29.8831 0)
			(unlocked yes)
			(layer "B.SilkS")
			(effects
				(font
					(size 0.7874 0.5842)
					(thickness 0.1524)
				)
				(justify left mirror)
			)
		)
		(fp_text user "P17"
			(at -5.822696 37.797994 0)
			(unlocked yes)
			(layer "B.SilkS")
			(effects
				(font
					(size 0.7874 0.5842)
					(thickness 0.1524)
				)
				(justify mirror)
			)
		)
		(fp_text user "P16"
			(at 3.175254 37.799518 0)
			(unlocked yes)
			(layer "B.SilkS")
			(effects
				(font
					(size 0.7874 0.5842)
					(thickness 0.1524)
				)
				(justify mirror)
			)
		)
		(fp_text user "S1"
			(at 3.136138 41.77665 0)
			(unlocked yes)
			(layer "B.SilkS")
			(effects
				(font
					(size 0.7874 0.5842)
					(thickness 0.1524)
				)
				(justify mirror)
			)
		)
		(fp_text user "S12"
			(at -5.818378 42.38498 0)
			(unlocked yes)
			(layer "B.SilkS")
			(effects
				(font
					(size 0.7874 0.5842)
					(thickness 0.1524)
				)
				(justify mirror)
			)
		)
		(fp_text user "S6"
			(at 3.268726 47.303182 0)
			(unlocked yes)
			(layer "B.SilkS")
			(effects
				(font
					(size 0.7874 0.5842)
					(thickness 0.1524)
				)
				(justify mirror)
			)
		)
		(fp_text user "S7"
			(at -5.830316 48.392842 0)
			(unlocked yes)
			(layer "B.SilkS")
			(effects
				(font
					(size 0.7874 0.5842)
					(thickness 0.1524)
				)
				(justify mirror)
			)
		)
		(fp_text user "P1"
			(at 3.108452 -1.27 180)
			(unlocked yes)
			(layer "B.Fab")
			(effects
				(font
					(size 0.7874 0.5842)
					(thickness 0.000001)
				)
				(justify mirror)
			)
		)
		(fp_text user "P32"
			(at -5.781548 -0.0508 180)
			(unlocked yes)
			(layer "B.Fab")
			(effects
				(font
					(size 0.7874 0.5842)
					(thickness 0.000001)
				)
				(justify mirror)
			)
		)
		(fp_text user "PRESS-FIT"
			(at -6.82371 29.8831 0)
			(unlocked yes)
			(layer "B.Fab")
			(effects
				(font
					(size 1.6002 1.1938)
					(thickness 0.000001)
				)
				(justify left mirror)
			)
		)
		(fp_text user "P17"
			(at -5.72135 38.0746 180)
			(unlocked yes)
			(layer "B.Fab")
			(effects
				(font
					(size 0.7874 0.5842)
					(thickness 0.000001)
				)
				(justify mirror)
			)
		)
		(fp_text user "P16"
			(at 3.159252 38.3794 180)
			(unlocked yes)
			(layer "B.Fab")
			(effects
				(font
					(size 0.7874 0.5842)
					(thickness 0.000001)
				)
				(justify mirror)
			)
		)
		(fp_text user "S12"
			(at -5.79374 41.42232 180)
			(unlocked yes)
			(layer "B.Fab")
			(effects
				(font
					(size 0.7874 0.5842)
					(thickness 0.000001)
				)
				(justify mirror)
			)
		)
		(fp_text user "S1"
			(at 3.09626 41.656 180)
			(unlocked yes)
			(layer "B.Fab")
			(effects
				(font
					(size 0.7874 0.5842)
					(thickness 0.000001)
				)
				(justify mirror)
			)
		)
		(fp_text user "S6"
			(at 3.133852 48.0822 180)
			(unlocked yes)
			(layer "B.Fab")
			(effects
				(font
					(size 0.7874 0.5842)
					(thickness 0.000001)
				)
				(justify mirror)
			)
		)
		(fp_text user "S7"
			(at -5.781548 48.0822 180)
			(unlocked yes)
			(layer "B.Fab")
			(effects
				(font
					(size 0.7874 0.5842)
					(thickness 0.000001)
				)
				(justify mirror)
			)
		)
		(fp_text user "P32"
			(at -4.071112 -0.0762 180)
			(unlocked yes)
			(layer "F.Fab")
			(effects
				(font
					(size 0.7874 0.5842)
					(thickness 0.000001)
				)
			)
		)
		(fp_text user "P1"
			(at 1.516888 0 180)
			(unlocked yes)
			(layer "F.Fab")
			(effects
				(font
					(size 0.7874 0.5842)
					(thickness 0.000001)
				)
			)
		)
		(fp_text user "PRESS-FIT"
			(at -6.762496 16.251428 0)
			(unlocked yes)
			(layer "F.Fab")
			(effects
				(font
					(size 1.6002 1.1938)
					(thickness 0.000001)
				)
				(justify left)
			)
		)
		(fp_text user "P17"
			(at -4.366768 38.227 180)
			(unlocked yes)
			(layer "F.Fab")
			(effects
				(font
					(size 0.7874 0.5842)
					(thickness 0.000001)
				)
			)
		)
		(fp_text user "P16"
			(at 2.228088 38.354 180)
			(unlocked yes)
			(layer "F.Fab")
			(effects
				(font
					(size 0.7874 0.5842)
					(thickness 0.000001)
				)
			)
		)
		(fp_text user "S12"
			(at -4.362958 41.09212 180)
			(unlocked yes)
			(layer "F.Fab")
			(effects
				(font
					(size 0.7874 0.5842)
					(thickness 0.000001)
				)
			)
		)
		(fp_text user "S1"
			(at 2.164842 41.6306 180)
			(unlocked yes)
			(layer "F.Fab")
			(effects
				(font
					(size 0.7874 0.5842)
					(thickness 0.000001)
				)
			)
		)
		(fp_text user "S6"
			(at 1.923288 48.133 180)
			(unlocked yes)
			(layer "F.Fab")
			(effects
				(font
					(size 0.7874 0.5842)
					(thickness 0.000001)
				)
			)
		)
		(fp_text user "S7"
			(at -4.426712 48.2346 180)
			(unlocked yes)
			(layer "F.Fab")
			(effects
				(font
					(size 0.7874 0.5842)
					(thickness 0.000001)
				)
			)
		)
		(pad "" np_thru_hole circle
			(at -1.35001 -2.54)
			(size 2.5146 2.5146)
			(drill 2.5146)
			(layers "*.Cu" "*.Mask")
			(clearance 0.381)
			(thermal_gap 0.381)
		)
		(pad "" np_thru_hole circle
			(at 0 50.8)
			(size 2.5146 2.5146)
			(drill 2.5146)
			(layers "*.Cu" "*.Mask")
			(clearance 0.381)
			(thermal_gap 0.381)
		)
		(pad "P1" thru_hole rect
			(at 0 0)
			(size 1.1684 1.1684)
			(drill 0.762)
			(layers "*.Cu" "*.Mask")
			(remove_unused_layers no)
			(net "GND")
			(clearance 0.0508)
			(padstack
				(mode front_inner_back)
				(layer "Inner"
					(shape circle)
					(size 1.1684 1.1684)
					(clearance 0.0508)
				)
				(layer "B.Cu"
					(shape rect)
					(size 1.1684 1.1684)
					(thermal_gap 0.0508)
					(clearance 0.0508)
				)
			)
		)
		(pad "P2" thru_hole circle
			(at 0 2.54)
			(size 1.1684 1.1684)
			(drill 0.762)
			(layers "*.Cu" "*.Mask")
			(remove_unused_layers no)
			(net "GND")
			(clearance 0.0508)
			(thermal_gap 0.0508)
		)
		(pad "P3" thru_hole circle
			(at 0 5.08)
			(size 1.1684 1.1684)
			(drill 0.762)
			(layers "*.Cu" "*.Mask")
			(remove_unused_layers no)
			(net "GND")
			(clearance 0.0508)
			(thermal_gap 0.0508)
		)
		(pad "P4" thru_hole circle
			(at 0 7.62)
			(size 1.1684 1.1684)
			(drill 0.762)
			(layers "*.Cu" "*.Mask")
			(remove_unused_layers no)
			(net "GND")
			(clearance 0.0508)
			(thermal_gap 0.0508)
		)
		(pad "P5" thru_hole circle
			(at 0 10.16)
			(size 1.1684 1.1684)
			(drill 0.762)
			(layers "*.Cu" "*.Mask")
			(remove_unused_layers no)
			(net "GND")
			(clearance 0.0508)
			(thermal_gap 0.0508)
		)
		(pad "P6" thru_hole circle
			(at 0 12.7)
			(size 1.1684 1.1684)
			(drill 0.762)
			(layers "*.Cu" "*.Mask")
			(remove_unused_layers no)
			(net "GND")
			(clearance 0.0508)
			(thermal_gap 0.0508)
		)
		(pad "P7" thru_hole circle
			(at 0 15.24)
			(size 1.1684 1.1684)
			(drill 0.762)
			(layers "*.Cu" "*.Mask")
			(remove_unused_layers no)
			(net "GND")
			(clearance 0.0508)
			(thermal_gap 0.0508)
		)
		(pad "P8" thru_hole circle
			(at 0 17.78)
			(size 1.1684 1.1684)
			(drill 0.762)
			(layers "*.Cu" "*.Mask")
			(remove_unused_layers no)
			(net "GND")
			(clearance 0.0508)
			(thermal_gap 0.0508)
		)
		(pad "P9" thru_hole circle
			(at 0 20.32)
			(size 1.1684 1.1684)
			(drill 0.762)
			(layers "*.Cu" "*.Mask")
			(remove_unused_layers no)
			(net "P12V")
			(clearance 0.0508)
			(thermal_gap 0.0508)
		)
		(pad "P10" thru_hole circle
			(at 0 22.86)
			(size 1.1684 1.1684)
			(drill 0.762)
			(layers "*.Cu" "*.Mask")
			(remove_unused_layers no)
			(net "P12V")
			(clearance 0.0508)
			(thermal_gap 0.0508)
		)
		(pad "P11" thru_hole circle
			(at 0 25.4)
			(size 1.1684 1.1684)
			(drill 0.762)
			(layers "*.Cu" "*.Mask")
			(remove_unused_layers no)
			(net "P12V")
			(clearance 0.0508)
			(thermal_gap 0.0508)
		)
		(pad "P12" thru_hole circle
			(at 0 27.94)
			(size 1.1684 1.1684)
			(drill 0.762)
			(layers "*.Cu" "*.Mask")
			(remove_unused_layers no)
			(net "P12V")
			(clearance 0.0508)
			(thermal_gap 0.0508)
		)
		(pad "P13" thru_hole circle
			(at 0 30.48)
			(size 1.1684 1.1684)
			(drill 0.762)
			(layers "*.Cu" "*.Mask")
			(remove_unused_layers no)
			(net "P12V")
			(clearance 0.0508)
			(thermal_gap 0.0508)
		)
		(pad "P14" thru_hole circle
			(at 0 33.02)
			(size 1.1684 1.1684)
			(drill 0.762)
			(layers "*.Cu" "*.Mask")
			(remove_unused_layers no)
			(net "P12V")
			(clearance 0.0508)
			(thermal_gap 0.0508)
		)
		(pad "P15" thru_hole circle
			(at 0 35.56)
			(size 1.1684 1.1684)
			(drill 0.762)
			(layers "*.Cu" "*.Mask")
			(remove_unused_layers no)
			(net "P12V")
			(clearance 0.0508)
			(thermal_gap 0.0508)
		)
		(pad "P16" thru_hole circle
			(at 0 38.1)
			(size 1.1684 1.1684)
			(drill 0.762)
			(layers "*.Cu" "*.Mask")
			(remove_unused_layers no)
			(net "P12V")
			(clearance 0.0508)
			(thermal_gap 0.0508)
		)
		(pad "P17" thru_hole circle
			(at -2.70002 38.1)
			(size 1.1684 1.1684)
			(drill 0.762)
			(layers "*.Cu" "*.Mask")
			(remove_unused_layers no)
			(net "P12V")
			(clearance 0.0508)
			(thermal_gap 0.0508)
		)
		(pad "P18" thru_hole circle
			(at -2.70002 35.56)
			(size 1.1684 1.1684)
			(drill 0.762)
			(layers "*.Cu" "*.Mask")
			(remove_unused_layers no)
			(net "P12V")
			(clearance 0.0508)
			(thermal_gap 0.0508)
		)
		(pad "P19" thru_hole circle
			(at -2.70002 33.02)
			(size 1.1684 1.1684)
			(drill 0.762)
			(layers "*.Cu" "*.Mask")
			(remove_unused_layers no)
			(net "P12V")
			(clearance 0.0508)
			(thermal_gap 0.0508)
		)
		(pad "P20" thru_hole circle
			(at -2.70002 30.48)
			(size 1.1684 1.1684)
			(drill 0.762)
			(layers "*.Cu" "*.Mask")
			(remove_unused_layers no)
			(net "P12V")
			(clearance 0.0508)
			(thermal_gap 0.0508)
		)
		(pad "P21" thru_hole circle
			(at -2.70002 27.94)
			(size 1.1684 1.1684)
			(drill 0.762)
			(layers "*.Cu" "*.Mask")
			(remove_unused_layers no)
			(net "P12V")
			(clearance 0.0508)
			(thermal_gap 0.0508)
		)
		(pad "P22" thru_hole circle
			(at -2.70002 25.4)
			(size 1.1684 1.1684)
			(drill 0.762)
			(layers "*.Cu" "*.Mask")
			(remove_unused_layers no)
			(net "P12V")
			(clearance 0.0508)
			(thermal_gap 0.0508)
		)
		(pad "P23" thru_hole circle
			(at -2.70002 22.86)
			(size 1.1684 1.1684)
			(drill 0.762)
			(layers "*.Cu" "*.Mask")
			(remove_unused_layers no)
			(net "P12V")
			(clearance 0.0508)
			(thermal_gap 0.0508)
		)
		(pad "P24" thru_hole circle
			(at -2.70002 20.32)
			(size 1.1684 1.1684)
			(drill 0.762)
			(layers "*.Cu" "*.Mask")
			(remove_unused_layers no)
			(net "P12V")
			(clearance 0.0508)
			(thermal_gap 0.0508)
		)
		(pad "P25" thru_hole circle
			(at -2.70002 17.78)
			(size 1.1684 1.1684)
			(drill 0.762)
			(layers "*.Cu" "*.Mask")
			(remove_unused_layers no)
			(net "GND")
			(clearance 0.0508)
			(thermal_gap 0.0508)
		)
		(pad "P26" thru_hole circle
			(at -2.70002 15.24)
			(size 1.1684 1.1684)
			(drill 0.762)
			(layers "*.Cu" "*.Mask")
			(remove_unused_layers no)
			(net "GND")
			(clearance 0.0508)
			(thermal_gap 0.0508)
		)
		(pad "P27" thru_hole circle
			(at -2.70002 12.7)
			(size 1.1684 1.1684)
			(drill 0.762)
			(layers "*.Cu" "*.Mask")
			(remove_unused_layers no)
			(net "GND")
			(clearance 0.0508)
			(thermal_gap 0.0508)
		)
		(pad "P28" thru_hole circle
			(at -2.70002 10.16)
			(size 1.1684 1.1684)
			(drill 0.762)
			(layers "*.Cu" "*.Mask")
			(remove_unused_layers no)
			(net "GND")
			(clearance 0.0508)
			(thermal_gap 0.0508)
		)
		(pad "P29" thru_hole circle
			(at -2.70002 7.62)
			(size 1.1684 1.1684)
			(drill 0.762)
			(layers "*.Cu" "*.Mask")
			(remove_unused_layers no)
			(net "GND")
			(clearance 0.0508)
			(thermal_gap 0.0508)
		)
		(pad "P30" thru_hole circle
			(at -2.70002 5.08)
			(size 1.1684 1.1684)
			(drill 0.762)
			(layers "*.Cu" "*.Mask")
			(remove_unused_layers no)
			(net "GND")
			(clearance 0.0508)
			(thermal_gap 0.0508)
		)
		(pad "P31" thru_hole circle
			(at -2.70002 2.54)
			(size 1.1684 1.1684)
			(drill 0.762)
			(layers "*.Cu" "*.Mask")
			(remove_unused_layers no)
			(net "GND")
			(clearance 0.0508)
			(thermal_gap 0.0508)
		)
		(pad "P32" thru_hole circle
			(at -2.70002 0)
			(size 1.1684 1.1684)
			(drill 0.762)
			(layers "*.Cu" "*.Mask")
			(remove_unused_layers no)
			(net "GND")
			(clearance 0.0508)
			(thermal_gap 0.0508)
		)
		(pad "S1" thru_hole circle
			(at 0.55499 41.60012)
			(size 1.1684 1.1684)
			(drill 0.762)
			(layers "*.Cu" "*.Mask")
			(remove_unused_layers no)
			(net "T8_BLAD1_TXD")
			(clearance 0.0508)
			(thermal_gap 0.0508)
		)
		(pad "S2" thru_hole circle
			(at -0.71501 42.87012)
			(size 1.1684 1.1684)
			(drill 0.762)
			(layers "*.Cu" "*.Mask")
			(remove_unused_layers no)
			(net "T8_BLAD1_RXD")
			(clearance 0.0508)
			(thermal_gap 0.0508)
		)
		(pad "S3" thru_hole circle
			(at 0.55499 44.14012)
			(size 1.1684 1.1684)
			(drill 0.762)
			(layers "*.Cu" "*.Mask")
			(remove_unused_layers no)
			(net "T8_BLAD1_EN")
			(clearance 0.0508)
			(thermal_gap 0.0508)
		)
		(pad "S4" thru_hole circle
			(at -0.71501 45.41012)
			(size 1.1684 1.1684)
			(drill 0.762)
			(layers "*.Cu" "*.Mask")
			(remove_unused_layers no)
			(net "B15_PSU_ALERT_N")
			(clearance 0.0508)
			(thermal_gap 0.0508)
		)
		(pad "S5" thru_hole circle
			(at 0.55499 46.68012)
			(size 1.1684 1.1684)
			(drill 0.762)
			(layers "*.Cu" "*.Mask")
			(remove_unused_layers no)
			(net "T8_BLAD2_TXD")
			(clearance 0.0508)
			(thermal_gap 0.0508)
		)
		(pad "S6" thru_hole circle
			(at -0.71501 47.95012)
			(size 1.1684 1.1684)
			(drill 0.762)
			(layers "*.Cu" "*.Mask")
			(remove_unused_layers no)
			(net "T8_BLAD2_RXD")
			(clearance 0.0508)
			(thermal_gap 0.0508)
		)
		(pad "S7" thru_hole circle
			(at -3.25501 47.95012)
			(size 1.1684 1.1684)
			(drill 0.762)
			(layers "*.Cu" "*.Mask")
			(remove_unused_layers no)
			(net "T8_BLAD4_RXD")
			(clearance 0.0508)
			(thermal_gap 0.0508)
		)
		(pad "S8" thru_hole circle
			(at -1.98501 46.68012)
			(size 1.1684 1.1684)
			(drill 0.762)
			(layers "*.Cu" "*.Mask")
			(remove_unused_layers no)
			(net "T8_BLAD4_TXD")
			(clearance 0.0508)
			(thermal_gap 0.0508)
		)
		(pad "S9" thru_hole circle
			(at -3.25501 45.41012)
			(size 1.1684 1.1684)
			(drill 0.762)
			(layers "*.Cu" "*.Mask")
			(remove_unused_layers no)
			(net "B16_PSU_ALERT_N")
			(clearance 0.0508)
			(thermal_gap 0.0508)
		)
		(pad "S10" thru_hole circle
			(at -1.98501 44.14012)
			(size 1.1684 1.1684)
			(drill 0.762)
			(layers "*.Cu" "*.Mask")
			(remove_unused_layers no)
			(net "T8_BLAD3_EN")
			(clearance 0.0508)
			(thermal_gap 0.0508)
		)
		(pad "S11" thru_hole circle
			(at -3.25501 42.87012)
			(size 1.1684 1.1684)
			(drill 0.762)
			(layers "*.Cu" "*.Mask")
			(remove_unused_layers no)
			(net "T8_BLAD3_RXD")
			(clearance 0.0508)
			(thermal_gap 0.0508)
		)
		(pad "S12" thru_hole circle
			(at -1.98501 41.60012)
			(size 1.1684 1.1684)
			(drill 0.762)
			(layers "*.Cu" "*.Mask")
			(remove_unused_layers no)
			(net "T8_BLAD3_TXD")
			(clearance 0.0508)
			(thermal_gap 0.0508)
		)
		(zone
			(layer "F.Cu")
			(hatch none 0.5)
			(connect_pads
				(clearance 0)
			)
			(min_thickness 0.25)
			(keepout
				(tracks allowed)
				(vias not_allowed)
				(pads allowed)
				(copperpour not_allowed)
				(footprints allowed)
			)
			(placement
				(enabled no)
				(sheetname "")
			)
			(fill
				(thermal_gap 0.5)
				(thermal_bridge_width 0.5)
				(island_removal_mode 0)
			)
			(polygon
				(pts
					(xy 85.00999 -320.60388) (xy 92.65539 -320.60388) (xy 92.65539 -315.49848) (xy 85.00999 -315.49848)
					(xy 84.98459 -315.49848) (xy 84.98459 -320.60388)
				)
			)
		)
		(zone
			(layer "F.Cu")
			(hatch none 0.5)
			(connect_pads
				(clearance 0)
			)
			(min_thickness 0.25)
			(keepout
				(tracks allowed)
				(vias not_allowed)
				(pads allowed)
				(copperpour not_allowed)
				(footprints allowed)
			)
			(placement
				(enabled no)
				(sheetname "")
			)
			(fill
				(thermal_gap 0.5)
				(thermal_bridge_width 0.5)
				(island_removal_mode 0)
			)
			(polygon
				(pts
					(xy 43.37939 -316.08268) (xy 43.37939 -320.04508) (xy 82.77479 -320.04508) (xy 82.80019 -320.04508)
					(xy 82.80019 -316.08268) (xy 82.80019 -316.05728) (xy 43.37939 -316.05728)
				)
			)
		)
		(zone
			(layers "F.Cu" "B.Cu" "In1.Cu" "In2.Cu" "In3.Cu" "In4.Cu" "In5.Cu" "In6.Cu")
			(hatch none 0.5)
			(connect_pads
				(clearance 0)
			)
			(min_thickness 0.25)
			(keepout
				(tracks not_allowed)
				(vias allowed)
				(pads allowed)
				(copperpour not_allowed)
				(footprints allowed)
			)
			(placement
				(enabled no)
				(sheetname "")
			)
			(fill
				(thermal_gap 0.5)
				(thermal_bridge_width 0.5)
				(island_removal_mode 0)
			)
			(polygon
				(pts
					(arc
						(start 43.18 -318.06007)
						(mid 39.81958 -318.06007)
						(end 43.18 -318.06007)
					)
				)
			)
		)
		(zone
			(layers "F.Cu" "B.Cu" "In1.Cu" "In2.Cu" "In3.Cu" "In4.Cu" "In5.Cu" "In6.Cu")
			(hatch none 0.5)
			(connect_pads
				(clearance 0)
			)
			(min_thickness 0.25)
			(keepout
				(tracks not_allowed)
				(vias allowed)
				(pads allowed)
				(copperpour not_allowed)
				(footprints allowed)
			)
			(placement
				(enabled no)
				(sheetname "")
			)
			(fill
				(thermal_gap 0.5)
				(thermal_bridge_width 0.5)
				(island_removal_mode 0)
			)
			(polygon
				(pts
					(arc
						(start 96.52381 -319.41008)
						(mid 93.15577 -319.41008)
						(end 96.52381 -319.41008)
					)
				)
			)
		)
	)
	(footprint ""
		(layer "B.Cu")
		(at 97.827084 -84.356956 90)
		(property "Reference" "C93"
			(at -1.839214 2.474468 270)
			(unlocked yes)
			(layer "B.SilkS")
			(effects
				(font
					(size 0.7874 0.5842)
					(thickness 0.1524)
				)
				(justify left mirror)
			)
		)
		(property "Value" ""
			(at 0 0 90)
			(layer "B.Fab")
			(effects
				(font
					(size 1.27 1.27)
				)
				(justify mirror)
			)
		)
		(duplicate_pad_numbers_are_jumpers no)
		(fp_line
			(start 0.7874 -0.4064)
			(end -0.7874 -0.4064)
			(stroke
				(width 0.1524)
				(type default)
			)
			(layer "B.SilkS")
		)
		(fp_line
			(start -0.7874 -0.4064)
			(end -0.7874 0.4064)
			(stroke
				(width 0.1524)
				(type default)
			)
			(layer "B.SilkS")
		)
		(fp_line
			(start 0 0.381)
			(end 0 -0.381)
			(stroke
				(width 0.1524)
				(type default)
			)
			(layer "B.SilkS")
		)
		(fp_line
			(start 0.7874 0.4064)
			(end 0.7874 -0.4064)
			(stroke
				(width 0.1524)
				(type default)
			)
			(layer "B.SilkS")
		)
		(fp_line
			(start -0.7874 0.4064)
			(end 0.7874 0.4064)
			(stroke
				(width 0.1524)
				(type default)
			)
			(layer "B.SilkS")
		)
		(fp_poly
			(pts
				(xy 0.5334 0.254) (xy 0.635 0.254) (xy 0.635 0.2286) (xy 0.635 -0.254) (xy 0.5334 -0.254) (xy 0.5334 -0.2794)
				(xy -0.5334 -0.2794) (xy -0.5334 -0.254) (xy -0.635 -0.254) (xy -0.635 0.254) (xy -0.5334 0.254)
				(xy -0.5334 0.2794) (xy 0.508 0.2794) (xy 0.5334 0.2794)
			)
			(stroke
				(width 0)
				(type default)
			)
			(fill no)
			(layer "B.CrtYd")
		)
		(pad "1" smd rect
			(at -0.40005 0 270)
			(size 0.4572 0.508)
			(layers "B.Cu" "B.Mask" "B.Paste")
			(net "P3V3_BUF")
		)
		(pad "2" smd rect
			(at 0.40005 0 270)
			(size 0.4572 0.508)
			(layers "B.Cu" "B.Mask" "B.Paste")
			(net "GND")
		)
	)
	(footprint ""
		(layer "B.Cu")
		(at 96.609408 -483.043992)
		(property "Reference" "C96"
			(at 2.285238 1.540764 0)
			(unlocked yes)
			(layer "B.SilkS")
			(effects
				(font
					(size 0.7874 0.5842)
					(thickness 0.1524)
				)
				(justify left mirror)
			)
		)
		(property "Value" ""
			(at 0 0 0)
			(layer "B.Fab")
			(effects
				(font
					(size 1.27 1.27)
				)
				(justify mirror)
			)
		)
		(duplicate_pad_numbers_are_jumpers no)
		(fp_line
			(start -0.7874 -0.4064)
			(end -0.7874 0.4064)
			(stroke
				(width 0.1524)
				(type default)
			)
			(layer "B.SilkS")
		)
		(fp_line
			(start -0.7874 0.4064)
			(end 0.7874 0.4064)
			(stroke
				(width 0.1524)
				(type default)
			)
			(layer "B.SilkS")
		)
		(fp_line
			(start 0 0.381)
			(end 0 -0.381)
			(stroke
				(width 0.1524)
				(type default)
			)
			(layer "B.SilkS")
		)
		(fp_line
			(start 0.7874 -0.4064)
			(end -0.7874 -0.4064)
			(stroke
				(width 0.1524)
				(type default)
			)
			(layer "B.SilkS")
		)
		(fp_line
			(start 0.7874 0.4064)
			(end 0.7874 -0.4064)
			(stroke
				(width 0.1524)
				(type default)
			)
			(layer "B.SilkS")
		)
		(fp_poly
			(pts
				(xy 0.5334 0.254) (xy 0.635 0.254) (xy 0.635 0.2286) (xy 0.635 -0.254) (xy 0.5334 -0.254) (xy 0.5334 -0.2794)
				(xy -0.5334 -0.2794) (xy -0.5334 -0.254) (xy -0.635 -0.254) (xy -0.635 0.254) (xy -0.5334 0.254)
				(xy -0.5334 0.2794) (xy 0.508 0.2794) (xy 0.5334 0.2794)
			)
			(stroke
				(width 0)
				(type default)
			)
			(fill no)
			(layer "B.CrtYd")
		)
		(pad "1" smd rect
			(at -0.40005 0 180)
			(size 0.4572 0.508)
			(layers "B.Cu" "B.Mask" "B.Paste")
			(net "P3V3_BUF")
		)
		(pad "2" smd rect
			(at 0.40005 0 180)
			(size 0.4572 0.508)
			(layers "B.Cu" "B.Mask" "B.Paste")
			(net "GND")
		)
	)
	(footprint ""
		(layer "B.Cu")
		(at 14.010132 -224.098358)
		(property "Reference" ""
			(at 0 0 0)
			(layer "B.SilkS")
			(hide yes)
			(effects
				(font
					(size 1.27 1.27)
				)
				(justify mirror)
			)
		)
		(property "Value" ""
			(at 0 0 0)
			(layer "B.Fab")
			(effects
				(font
					(size 1.27 1.27)
				)
				(justify mirror)
			)
		)
		(duplicate_pad_numbers_are_jumpers no)
		(fp_poly
			(pts
				(arc
					(start 1.4986 0)
					(mid -1.4986 0)
					(end 1.4986 0)
				)
			)
			(stroke
				(width 0)
				(type default)
			)
			(fill no)
			(layer "B.CrtYd")
		)
		(pad "1" smd circle
			(at 0 0 180)
			(size 0.9906 0.9906)
			(layers "B.Cu" "B.Mask" "B.Paste")
			(net "Net_72")
		)
		(zone
			(layer "B.Cu")
			(hatch none 0.5)
			(connect_pads
				(clearance 0)
			)
			(min_thickness 0.25)
			(keepout
				(tracks not_allowed)
				(vias allowed)
				(pads allowed)
				(copperpour not_allowed)
				(footprints allowed)
			)
			(placement
				(enabled no)
				(sheetname "")
			)
			(fill
				(thermal_gap 0.5)
				(thermal_bridge_width 0.5)
				(island_removal_mode 0)
			)
			(polygon
				(pts
					(arc
						(start 15.635732 -224.098358)
						(mid 12.384532 -224.098358)
						(end 15.635732 -224.098358)
					)
				)
			)
		)
	)
	(footprint ""
		(layer "B.Cu")
		(at 91.35364 -480.950524)
		(property "Reference" "U7"
			(at 4.463034 -0.439928 0)
			(unlocked yes)
			(layer "B.SilkS")
			(effects
				(font
					(size 0.7874 0.5842)
					(thickness 0.1524)
				)
				(justify left mirror)
			)
		)
		(property "Value" ""
			(at 0 0 0)
			(layer "B.Fab")
			(effects
				(font
					(size 1.27 1.27)
				)
				(justify mirror)
			)
		)
		(duplicate_pad_numbers_are_jumpers no)
		(fp_line
			(start -2.5527 -2.0066)
			(end -2.5527 2.0066)
			(stroke
				(width 0.1524)
				(type default)
			)
			(layer "B.SilkS")
		)
		(fp_line
			(start -2.5527 2.0066)
			(end 2.5527 2.0066)
			(stroke
				(width 0.1524)
				(type default)
			)
			(layer "B.SilkS")
		)
		(fp_line
			(start 1.9812 0)
			(end 2.5527 -0.5715)
			(stroke
				(width 0.1524)
				(type default)
			)
			(layer "B.SilkS")
		)
		(fp_line
			(start 2.5527 -2.0066)
			(end -2.5527 -2.0066)
			(stroke
				(width 0.1524)
				(type default)
			)
			(layer "B.SilkS")
		)
		(fp_line
			(start 2.5527 -0.5715)
			(end 2.5527 -2.0066)
			(stroke
				(width 0.1524)
				(type default)
			)
			(layer "B.SilkS")
		)
		(fp_line
			(start 2.5527 0.5715)
			(end 1.9812 0)
			(stroke
				(width 0.1524)
				(type default)
			)
			(layer "B.SilkS")
		)
		(fp_line
			(start 2.5527 2.0066)
			(end 2.5527 0.5715)
			(stroke
				(width 0.1524)
				(type default)
			)
			(layer "B.SilkS")
		)
		(fp_circle
			(center 2.032 1.524)
			(end 2.286 1.524)
			(stroke
				(width 0.1524)
				(type default)
			)
			(fill no)
			(layer "B.SilkS")
		)
		(fp_rect
			(start 2.5527 3.6703)
			(end -2.5527 -3.6703)
			(stroke
				(width 0)
				(type default)
			)
			(fill no)
			(layer "B.CrtYd")
		)
		(fp_line
			(start -2.549906 -2.249932)
			(end -2.549906 2.249932)
			(stroke
				(width 0.1)
				(type default)
			)
			(layer "B.Fab")
		)
		(fp_line
			(start -2.549906 2.249932)
			(end 2.549906 2.249932)
			(stroke
				(width 0.1)
				(type default)
			)
			(layer "B.Fab")
		)
		(fp_line
			(start 2.549906 -2.249932)
			(end -2.549906 -2.249932)
			(stroke
				(width 0.1)
				(type default)
			)
			(layer "B.Fab")
		)
		(fp_line
			(start 2.549906 2.249932)
			(end 2.549906 -2.249932)
			(stroke
				(width 0.1)
				(type default)
			)
			(layer "B.Fab")
		)
		(pad "1" smd rect
			(at 1.949958 2.921 180)
			(size 0.3556 1.4986)
			(layers "B.Cu" "B.Mask" "B.Paste")
			(net "PSU_ALERT_N")
		)
		(pad "2" smd rect
			(at 1.299972 2.921 180)
			(size 0.3556 1.4986)
			(layers "B.Cu" "B.Mask" "B.Paste")
			(net "B19_PSU_ALERT_N")
		)
		(pad "3" smd rect
			(at 0.649986 2.921 180)
			(size 0.3556 1.4986)
			(layers "B.Cu" "B.Mask" "B.Paste")
			(net "PSU_ALERT_N")
		)
		(pad "4" smd rect
			(at 0 2.921 180)
			(size 0.3556 1.4986)
			(layers "B.Cu" "B.Mask" "B.Paste")
			(net "B20_PSU_ALERT_N")
		)
		(pad "5" smd rect
			(at -0.649986 2.921 180)
			(size 0.3556 1.4986)
			(layers "B.Cu" "B.Mask" "B.Paste")
			(net "PSU_ALERT_N")
		)
		(pad "6" smd rect
			(at -1.299972 2.921 180)
			(size 0.3556 1.4986)
			(layers "B.Cu" "B.Mask" "B.Paste")
			(net "B21_PSU_ALERT_N")
		)
		(pad "7" smd rect
			(at -1.949958 2.921 180)
			(size 0.3556 1.4986)
			(layers "B.Cu" "B.Mask" "B.Paste")
			(net "GND")
		)
		(pad "8" smd rect
			(at -1.949958 -2.921 180)
			(size 0.3556 1.4986)
			(layers "B.Cu" "B.Mask" "B.Paste")
			(net "B22_PSU_ALERT_N")
		)
		(pad "9" smd rect
			(at -1.299972 -2.921 180)
			(size 0.3556 1.4986)
			(layers "B.Cu" "B.Mask" "B.Paste")
			(net "PSU_ALERT_N")
		)
		(pad "10" smd rect
			(at -0.649986 -2.921 180)
			(size 0.3556 1.4986)
			(layers "B.Cu" "B.Mask" "B.Paste")
			(net "B23_PSU_ALERT_N")
		)
		(pad "11" smd rect
			(at 0 -2.921 180)
			(size 0.3556 1.4986)
			(layers "B.Cu" "B.Mask" "B.Paste")
			(net "PSU_ALERT_N")
		)
		(pad "12" smd rect
			(at 0.649986 -2.921 180)
			(size 0.3556 1.4986)
			(layers "B.Cu" "B.Mask" "B.Paste")
			(net "B24_PSU_ALERT_N")
		)
		(pad "13" smd rect
			(at 1.299972 -2.921 180)
			(size 0.3556 1.4986)
			(layers "B.Cu" "B.Mask" "B.Paste")
			(net "PSU_ALERT_N")
		)
		(pad "14" smd rect
			(at 1.949958 -2.921 180)
			(size 0.3556 1.4986)
			(layers "B.Cu" "B.Mask" "B.Paste")
			(net "P3V3_BUF")
		)
	)
	(footprint ""
		(layer "B.Cu")
		(at 95.86595 -170.91787)
		(property "Reference" "C94"
			(at 1.284478 -1.115568 0)
			(unlocked yes)
			(layer "B.SilkS")
			(effects
				(font
					(size 0.7874 0.5842)
					(thickness 0.1524)
				)
				(justify left mirror)
			)
		)
		(property "Value" ""
			(at 0 0 0)
			(layer "B.Fab")
			(effects
				(font
					(size 1.27 1.27)
				)
				(justify mirror)
			)
		)
		(duplicate_pad_numbers_are_jumpers no)
		(fp_line
			(start -0.7874 -0.4064)
			(end -0.7874 0.4064)
			(stroke
				(width 0.1524)
				(type default)
			)
			(layer "B.SilkS")
		)
		(fp_line
			(start -0.7874 0.4064)
			(end 0.7874 0.4064)
			(stroke
				(width 0.1524)
				(type default)
			)
			(layer "B.SilkS")
		)
		(fp_line
			(start 0 0.381)
			(end 0 -0.381)
			(stroke
				(width 0.1524)
				(type default)
			)
			(layer "B.SilkS")
		)
		(fp_line
			(start 0.7874 -0.4064)
			(end -0.7874 -0.4064)
			(stroke
				(width 0.1524)
				(type default)
			)
			(layer "B.SilkS")
		)
		(fp_line
			(start 0.7874 0.4064)
			(end 0.7874 -0.4064)
			(stroke
				(width 0.1524)
				(type default)
			)
			(layer "B.SilkS")
		)
		(fp_poly
			(pts
				(xy 0.5334 0.254) (xy 0.635 0.254) (xy 0.635 0.2286) (xy 0.635 -0.254) (xy 0.5334 -0.254) (xy 0.5334 -0.2794)
				(xy -0.5334 -0.2794) (xy -0.5334 -0.254) (xy -0.635 -0.254) (xy -0.635 0.254) (xy -0.5334 0.254)
				(xy -0.5334 0.2794) (xy 0.508 0.2794) (xy 0.5334 0.2794)
			)
			(stroke
				(width 0)
				(type default)
			)
			(fill no)
			(layer "B.CrtYd")
		)
		(pad "1" smd rect
			(at -0.40005 0 180)
			(size 0.4572 0.508)
			(layers "B.Cu" "B.Mask" "B.Paste")
			(net "P3V3_BUF")
		)
		(pad "2" smd rect
			(at 0.40005 0 180)
			(size 0.4572 0.508)
			(layers "B.Cu" "B.Mask" "B.Paste")
			(net "GND")
		)
	)
	(footprint ""
		(layer "B.Cu")
		(at 44.03979 -274.96008 90)
		(property "Reference" "J13"
			(at 6.540246 -4.559808 0)
			(unlocked yes)
			(layer "B.SilkS")
			(effects
				(font
					(size 0.7874 0.5842)
					(thickness 0.1524)
				)
				(justify left mirror)
			)
		)
		(property "Value" ""
			(at 0 0 90)
			(layer "B.Fab")
			(effects
				(font
					(size 1.27 1.27)
				)
				(justify mirror)
			)
		)
		(duplicate_pad_numbers_are_jumpers no)
		(fp_line
			(start 5.275072 -13.910056)
			(end -7.975092 -13.910056)
			(stroke
				(width 0.1524)
				(type default)
			)
			(layer "F.SilkS")
		)
		(fp_line
			(start -7.975092 -13.910056)
			(end -7.975092 62.170056)
			(stroke
				(width 0.1524)
				(type default)
			)
			(layer "F.SilkS")
		)
		(fp_line
			(start 5.275072 62.170056)
			(end 5.275072 -13.910056)
			(stroke
				(width 0.1524)
				(type default)
			)
			(layer "F.SilkS")
		)
		(fp_line
			(start -7.975092 62.170056)
			(end 5.275072 62.170056)
			(stroke
				(width 0.1524)
				(type default)
			)
			(layer "F.SilkS")
		)
		(fp_line
			(start 5.275072 -13.910056)
			(end -7.975092 -13.910056)
			(stroke
				(width 0.1524)
				(type default)
			)
			(layer "B.SilkS")
		)
		(fp_line
			(start -7.975092 -13.910056)
			(end -7.975092 62.170056)
			(stroke
				(width 0.1524)
				(type default)
			)
			(layer "B.SilkS")
		)
		(fp_line
			(start 2.275078 -10.910062)
			(end 2.275078 59.170062)
			(stroke
				(width 0.1524)
				(type default)
			)
			(layer "B.SilkS")
		)
		(fp_line
			(start -4.975098 -10.910062)
			(end 2.275078 -10.910062)
			(stroke
				(width 0.1524)
				(type default)
			)
			(layer "B.SilkS")
		)
		(fp_line
			(start 2.275078 59.170062)
			(end -4.975098 59.170062)
			(stroke
				(width 0.1524)
				(type default)
			)
			(layer "B.SilkS")
		)
		(fp_line
			(start -4.975098 59.170062)
			(end -4.975098 -10.910062)
			(stroke
				(width 0.1524)
				(type default)
			)
			(layer "B.SilkS")
		)
		(fp_line
			(start 5.275072 62.170056)
			(end 5.275072 -13.910056)
			(stroke
				(width 0.1524)
				(type default)
			)
			(layer "B.SilkS")
		)
		(fp_line
			(start -7.975092 62.170056)
			(end 5.275072 62.170056)
			(stroke
				(width 0.1524)
				(type default)
			)
			(layer "B.SilkS")
		)
		(fp_poly
			(pts
				(xy 4.103878 -0.759206) (xy 4.103878 0.764794) (xy 2.579878 0.002794)
			)
			(stroke
				(width 0)
				(type default)
			)
			(fill yes)
			(layer "B.SilkS")
		)
		(fp_poly
			(pts
				(xy 2.275078 -10.910062) (xy 2.275078 59.170062) (xy -4.975098 59.170062) (xy -4.975098 -10.910062)
			)
			(stroke
				(width 0)
				(type default)
			)
			(fill no)
			(layer "B.CrtYd")
		)
		(fp_poly
			(pts
				(xy 1.1938 40.9702) (xy 1.1938 48.6156) (xy -3.9116 48.6156) (xy -3.9116 40.9702) (xy -3.9116 40.9448)
				(xy 1.1938 40.9448)
			)
			(stroke
				(width 0)
				(type default)
			)
			(fill no)
			(layer "F.CrtYd")
		)
		(fp_poly
			(pts
				(xy -3.3274 -0.6604) (xy 0.635 -0.6604) (xy 0.635 38.735) (xy 0.635 38.7604) (xy -3.3274 38.7604)
				(xy -3.3528 38.7604) (xy -3.3528 -0.6604)
			)
			(stroke
				(width 0)
				(type default)
			)
			(fill no)
			(layer "F.CrtYd")
		)
		(fp_poly
			(pts
				(arc
					(start -1.35001 -1.01219)
					(mid -1.35001 -4.06781)
					(end -1.35001 -1.01219)
				)
			)
			(stroke
				(width 0)
				(type default)
			)
			(fill no)
			(layer "F.CrtYd")
		)
		(fp_poly
			(pts
				(arc
					(start 0 52.33162)
					(mid 0 49.26838)
					(end 0 52.33162)
				)
			)
			(stroke
				(width 0)
				(type default)
			)
			(fill no)
			(layer "F.CrtYd")
		)
		(fp_line
			(start 2.275078 -10.910062)
			(end 2.275078 59.170062)
			(stroke
				(width 0.1)
				(type default)
			)
			(layer "B.Fab")
		)
		(fp_line
			(start -4.975098 -10.910062)
			(end 2.275078 -10.910062)
			(stroke
				(width 0.1)
				(type default)
			)
			(layer "B.Fab")
		)
		(fp_line
			(start 2.275078 59.170062)
			(end -4.975098 59.170062)
			(stroke
				(width 0.1)
				(type default)
			)
			(layer "B.Fab")
		)
		(fp_line
			(start -4.975098 59.170062)
			(end -4.975098 -10.910062)
			(stroke
				(width 0.1)
				(type default)
			)
			(layer "B.Fab")
		)
		(fp_poly
			(pts
				(xy 4.103878 -0.759206) (xy 4.103878 0.764794) (xy 2.579878 0.002794)
			)
			(stroke
				(width 0)
				(type default)
			)
			(fill yes)
			(layer "B.Fab")
		)
		(fp_line
			(start 5.275072 -13.910056)
			(end -7.975092 -13.910056)
			(stroke
				(width 0.1)
				(type default)
			)
			(layer "F.Fab")
		)
		(fp_line
			(start -7.975092 -13.910056)
			(end -7.975092 62.170056)
			(stroke
				(width 0.1)
				(type default)
			)
			(layer "F.Fab")
		)
		(fp_line
			(start 5.275072 62.170056)
			(end 5.275072 -13.910056)
			(stroke
				(width 0.1)
				(type default)
			)
			(layer "F.Fab")
		)
		(fp_line
			(start -7.975092 62.170056)
			(end 5.275072 62.170056)
			(stroke
				(width 0.1)
				(type default)
			)
			(layer "F.Fab")
		)
		(fp_text user "P32"
			(at -9.264904 -0.265684 0)
			(unlocked yes)
			(layer "F.SilkS")
			(effects
				(font
					(size 0.7874 0.5842)
					(thickness 0.1524)
				)
			)
		)
		(fp_text user "P1"
			(at 6.17474 1.605788 0)
			(unlocked yes)
			(layer "F.SilkS")
			(effects
				(font
					(size 0.7874 0.5842)
					(thickness 0.1524)
				)
			)
		)
		(fp_text user "PRESS-FIT"
			(at -9.065768 15.80388 0)
			(unlocked yes)
			(layer "F.SilkS")
			(effects
				(font
					(size 0.7874 0.5842)
					(thickness 0.1524)
				)
				(justify left)
			)
		)
		(fp_text user "P17"
			(at -8.998966 37.492686 0)
			(unlocked yes)
			(layer "F.SilkS")
			(effects
				(font
					(size 0.7874 0.5842)
					(thickness 0.1524)
				)
			)
		)
		(fp_text user "P16"
			(at 6.1341 38.192456 0)
			(unlocked yes)
			(layer "F.SilkS")
			(effects
				(font
					(size 0.7874 0.5842)
					(thickness 0.1524)
				)
			)
		)
		(fp_text user "S12"
			(at -9.2329 40.032432 0)
			(unlocked yes)
			(layer "F.SilkS")
			(effects
				(font
					(size 0.7874 0.5842)
					(thickness 0.1524)
				)
			)
		)
		(fp_text user "S1"
			(at 5.97281 41.268904 0)
			(unlocked yes)
			(layer "F.SilkS")
			(effects
				(font
					(size 0.7874 0.5842)
					(thickness 0.1524)
				)
			)
		)
		(fp_text user "S7"
			(at -9.019286 47.64278 0)
			(unlocked yes)
			(layer "F.SilkS")
			(effects
				(font
					(size 0.7874 0.5842)
					(thickness 0.1524)
				)
			)
		)
		(fp_text user "S6"
			(at 6.006338 47.919386 0)
			(unlocked yes)
			(layer "F.SilkS")
			(effects
				(font
					(size 0.7874 0.5842)
					(thickness 0.1524)
				)
			)
		)
		(fp_text user "P1"
			(at 3.075178 -1.464056 0)
			(unlocked yes)
			(layer "B.SilkS")
			(effects
				(font
					(size 0.7874 0.5842)
					(thickness 0.1524)
				)
				(justify mirror)
			)
		)
		(fp_text user "P32"
			(at -6.014974 -0.09525 0)
			(unlocked yes)
			(layer "B.SilkS")
			(effects
				(font
					(size 0.7874 0.5842)
					(thickness 0.1524)
				)
				(justify mirror)
			)
		)
		(fp_text user "PRESS-FIT"
			(at -7.155434 24.40051 0)
			(unlocked yes)
			(layer "B.SilkS")
			(effects
				(font
					(size 0.7874 0.5842)
					(thickness 0.1524)
				)
				(justify left mirror)
			)
		)
		(fp_text user "P16"
			(at 3.024124 37.789104 0)
			(unlocked yes)
			(layer "B.SilkS")
			(effects
				(font
					(size 0.7874 0.5842)
					(thickness 0.1524)
				)
				(justify mirror)
			)
		)
		(fp_text user "P17"
			(at -5.734558 37.889942 0)
			(unlocked yes)
			(layer "B.SilkS")
			(effects
				(font
					(size 0.7874 0.5842)
					(thickness 0.1524)
				)
				(justify mirror)
			)
		)
		(fp_text user "S1"
			(at 3.05308 41.69791 0)
			(unlocked yes)
			(layer "B.SilkS")
			(effects
				(font
					(size 0.7874 0.5842)
					(thickness 0.1524)
				)
				(justify mirror)
			)
		)
		(fp_text user "S12"
			(at -5.832602 42.374566 0)
			(unlocked yes)
			(layer "B.SilkS")
			(effects
				(font
					(size 0.7874 0.5842)
					(thickness 0.1524)
				)
				(justify mirror)
			)
		)
		(fp_text user "S6"
			(at 3.015488 47.565056 0)
			(unlocked yes)
			(layer "B.SilkS")
			(effects
				(font
					(size 0.7874 0.5842)
					(thickness 0.1524)
				)
				(justify mirror)
			)
		)
		(fp_text user "S7"
			(at -5.810758 47.56531 0)
			(unlocked yes)
			(layer "B.SilkS")
			(effects
				(font
					(size 0.7874 0.5842)
					(thickness 0.1524)
				)
				(justify mirror)
			)
		)
		(fp_text user "P1"
			(at 3.108452 -1.27 180)
			(unlocked yes)
			(layer "B.Fab")
			(effects
				(font
					(size 0.7874 0.5842)
					(thickness 0.000001)
				)
				(justify mirror)
			)
		)
		(fp_text user "P32"
			(at -5.781548 -0.0508 180)
			(unlocked yes)
			(layer "B.Fab")
			(effects
				(font
					(size 0.7874 0.5842)
					(thickness 0.000001)
				)
				(justify mirror)
			)
		)
		(fp_text user "PRESS-FIT"
			(at -6.82371 29.8831 0)
			(unlocked yes)
			(layer "B.Fab")
			(effects
				(font
					(size 1.6002 1.1938)
					(thickness 0.000001)
				)
				(justify left mirror)
			)
		)
		(fp_text user "P17"
			(at -5.72135 38.0746 180)
			(unlocked yes)
			(layer "B.Fab")
			(effects
				(font
					(size 0.7874 0.5842)
					(thickness 0.000001)
				)
				(justify mirror)
			)
		)
		(fp_text user "P16"
			(at 3.159252 38.3794 180)
			(unlocked yes)
			(layer "B.Fab")
			(effects
				(font
					(size 0.7874 0.5842)
					(thickness 0.000001)
				)
				(justify mirror)
			)
		)
		(fp_text user "S12"
			(at -5.79374 41.42232 180)
			(unlocked yes)
			(layer "B.Fab")
			(effects
				(font
					(size 0.7874 0.5842)
					(thickness 0.000001)
				)
				(justify mirror)
			)
		)
		(fp_text user "S1"
			(at 3.09626 41.656 180)
			(unlocked yes)
			(layer "B.Fab")
			(effects
				(font
					(size 0.7874 0.5842)
					(thickness 0.000001)
				)
				(justify mirror)
			)
		)
		(fp_text user "S6"
			(at 3.133852 48.0822 180)
			(unlocked yes)
			(layer "B.Fab")
			(effects
				(font
					(size 0.7874 0.5842)
					(thickness 0.000001)
				)
				(justify mirror)
			)
		)
		(fp_text user "S7"
			(at -5.781548 48.0822 180)
			(unlocked yes)
			(layer "B.Fab")
			(effects
				(font
					(size 0.7874 0.5842)
					(thickness 0.000001)
				)
				(justify mirror)
			)
		)
		(fp_text user "P32"
			(at -4.071112 -0.0762 180)
			(unlocked yes)
			(layer "F.Fab")
			(effects
				(font
					(size 0.7874 0.5842)
					(thickness 0.000001)
				)
			)
		)
		(fp_text user "P1"
			(at 1.516888 0 180)
			(unlocked yes)
			(layer "F.Fab")
			(effects
				(font
					(size 0.7874 0.5842)
					(thickness 0.000001)
				)
			)
		)
		(fp_text user "PRESS-FIT"
			(at -6.762496 16.251428 0)
			(unlocked yes)
			(layer "F.Fab")
			(effects
				(font
					(size 1.6002 1.1938)
					(thickness 0.000001)
				)
				(justify left)
			)
		)
		(fp_text user "P17"
			(at -4.366768 38.227 180)
			(unlocked yes)
			(layer "F.Fab")
			(effects
				(font
					(size 0.7874 0.5842)
					(thickness 0.000001)
				)
			)
		)
		(fp_text user "P16"
			(at 2.228088 38.354 180)
			(unlocked yes)
			(layer "F.Fab")
			(effects
				(font
					(size 0.7874 0.5842)
					(thickness 0.000001)
				)
			)
		)
		(fp_text user "S12"
			(at -4.362958 41.09212 180)
			(unlocked yes)
			(layer "F.Fab")
			(effects
				(font
					(size 0.7874 0.5842)
					(thickness 0.000001)
				)
			)
		)
		(fp_text user "S1"
			(at 2.164842 41.6306 180)
			(unlocked yes)
			(layer "F.Fab")
			(effects
				(font
					(size 0.7874 0.5842)
					(thickness 0.000001)
				)
			)
		)
		(fp_text user "S6"
			(at 1.923288 48.133 180)
			(unlocked yes)
			(layer "F.Fab")
			(effects
				(font
					(size 0.7874 0.5842)
					(thickness 0.000001)
				)
			)
		)
		(fp_text user "S7"
			(at -4.426712 48.2346 180)
			(unlocked yes)
			(layer "F.Fab")
			(effects
				(font
					(size 0.7874 0.5842)
					(thickness 0.000001)
				)
			)
		)
		(pad "" np_thru_hole circle
			(at -1.35001 -2.54)
			(size 2.5146 2.5146)
			(drill 2.5146)
			(layers "*.Cu" "*.Mask")
			(clearance 0.381)
			(thermal_gap 0.381)
		)
		(pad "" np_thru_hole circle
			(at 0 50.8)
			(size 2.5146 2.5146)
			(drill 2.5146)
			(layers "*.Cu" "*.Mask")
			(clearance 0.381)
			(thermal_gap 0.381)
		)
		(pad "P1" thru_hole rect
			(at 0 0)
			(size 1.1684 1.1684)
			(drill 0.762)
			(layers "*.Cu" "*.Mask")
			(remove_unused_layers no)
			(net "GND")
			(clearance 0.0508)
			(padstack
				(mode front_inner_back)
				(layer "Inner"
					(shape circle)
					(size 1.1684 1.1684)
					(clearance 0.0508)
				)
				(layer "B.Cu"
					(shape rect)
					(size 1.1684 1.1684)
					(thermal_gap 0.0508)
					(clearance 0.0508)
				)
			)
		)
		(pad "P2" thru_hole circle
			(at 0 2.54)
			(size 1.1684 1.1684)
			(drill 0.762)
			(layers "*.Cu" "*.Mask")
			(remove_unused_layers no)
			(net "GND")
			(clearance 0.0508)
			(thermal_gap 0.0508)
		)
		(pad "P3" thru_hole circle
			(at 0 5.08)
			(size 1.1684 1.1684)
			(drill 0.762)
			(layers "*.Cu" "*.Mask")
			(remove_unused_layers no)
			(net "GND")
			(clearance 0.0508)
			(thermal_gap 0.0508)
		)
		(pad "P4" thru_hole circle
			(at 0 7.62)
			(size 1.1684 1.1684)
			(drill 0.762)
			(layers "*.Cu" "*.Mask")
			(remove_unused_layers no)
			(net "GND")
			(clearance 0.0508)
			(thermal_gap 0.0508)
		)
		(pad "P5" thru_hole circle
			(at 0 10.16)
			(size 1.1684 1.1684)
			(drill 0.762)
			(layers "*.Cu" "*.Mask")
			(remove_unused_layers no)
			(net "GND")
			(clearance 0.0508)
			(thermal_gap 0.0508)
		)
		(pad "P6" thru_hole circle
			(at 0 12.7)
			(size 1.1684 1.1684)
			(drill 0.762)
			(layers "*.Cu" "*.Mask")
			(remove_unused_layers no)
			(net "GND")
			(clearance 0.0508)
			(thermal_gap 0.0508)
		)
		(pad "P7" thru_hole circle
			(at 0 15.24)
			(size 1.1684 1.1684)
			(drill 0.762)
			(layers "*.Cu" "*.Mask")
			(remove_unused_layers no)
			(net "GND")
			(clearance 0.0508)
			(thermal_gap 0.0508)
		)
		(pad "P8" thru_hole circle
			(at 0 17.78)
			(size 1.1684 1.1684)
			(drill 0.762)
			(layers "*.Cu" "*.Mask")
			(remove_unused_layers no)
			(net "GND")
			(clearance 0.0508)
			(thermal_gap 0.0508)
		)
		(pad "P9" thru_hole circle
			(at 0 20.32)
			(size 1.1684 1.1684)
			(drill 0.762)
			(layers "*.Cu" "*.Mask")
			(remove_unused_layers no)
			(net "P12V")
			(clearance 0.0508)
			(thermal_gap 0.0508)
		)
		(pad "P10" thru_hole circle
			(at 0 22.86)
			(size 1.1684 1.1684)
			(drill 0.762)
			(layers "*.Cu" "*.Mask")
			(remove_unused_layers no)
			(net "P12V")
			(clearance 0.0508)
			(thermal_gap 0.0508)
		)
		(pad "P11" thru_hole circle
			(at 0 25.4)
			(size 1.1684 1.1684)
			(drill 0.762)
			(layers "*.Cu" "*.Mask")
			(remove_unused_layers no)
			(net "P12V")
			(clearance 0.0508)
			(thermal_gap 0.0508)
		)
		(pad "P12" thru_hole circle
			(at 0 27.94)
			(size 1.1684 1.1684)
			(drill 0.762)
			(layers "*.Cu" "*.Mask")
			(remove_unused_layers no)
			(net "P12V")
			(clearance 0.0508)
			(thermal_gap 0.0508)
		)
		(pad "P13" thru_hole circle
			(at 0 30.48)
			(size 1.1684 1.1684)
			(drill 0.762)
			(layers "*.Cu" "*.Mask")
			(remove_unused_layers no)
			(net "P12V")
			(clearance 0.0508)
			(thermal_gap 0.0508)
		)
		(pad "P14" thru_hole circle
			(at 0 33.02)
			(size 1.1684 1.1684)
			(drill 0.762)
			(layers "*.Cu" "*.Mask")
			(remove_unused_layers no)
			(net "P12V")
			(clearance 0.0508)
			(thermal_gap 0.0508)
		)
		(pad "P15" thru_hole circle
			(at 0 35.56)
			(size 1.1684 1.1684)
			(drill 0.762)
			(layers "*.Cu" "*.Mask")
			(remove_unused_layers no)
			(net "P12V")
			(clearance 0.0508)
			(thermal_gap 0.0508)
		)
		(pad "P16" thru_hole circle
			(at 0 38.1)
			(size 1.1684 1.1684)
			(drill 0.762)
			(layers "*.Cu" "*.Mask")
			(remove_unused_layers no)
			(net "P12V")
			(clearance 0.0508)
			(thermal_gap 0.0508)
		)
		(pad "P17" thru_hole circle
			(at -2.70002 38.1)
			(size 1.1684 1.1684)
			(drill 0.762)
			(layers "*.Cu" "*.Mask")
			(remove_unused_layers no)
			(net "P12V")
			(clearance 0.0508)
			(thermal_gap 0.0508)
		)
		(pad "P18" thru_hole circle
			(at -2.70002 35.56)
			(size 1.1684 1.1684)
			(drill 0.762)
			(layers "*.Cu" "*.Mask")
			(remove_unused_layers no)
			(net "P12V")
			(clearance 0.0508)
			(thermal_gap 0.0508)
		)
		(pad "P19" thru_hole circle
			(at -2.70002 33.02)
			(size 1.1684 1.1684)
			(drill 0.762)
			(layers "*.Cu" "*.Mask")
			(remove_unused_layers no)
			(net "P12V")
			(clearance 0.0508)
			(thermal_gap 0.0508)
		)
		(pad "P20" thru_hole circle
			(at -2.70002 30.48)
			(size 1.1684 1.1684)
			(drill 0.762)
			(layers "*.Cu" "*.Mask")
			(remove_unused_layers no)
			(net "P12V")
			(clearance 0.0508)
			(thermal_gap 0.0508)
		)
		(pad "P21" thru_hole circle
			(at -2.70002 27.94)
			(size 1.1684 1.1684)
			(drill 0.762)
			(layers "*.Cu" "*.Mask")
			(remove_unused_layers no)
			(net "P12V")
			(clearance 0.0508)
			(thermal_gap 0.0508)
		)
		(pad "P22" thru_hole circle
			(at -2.70002 25.4)
			(size 1.1684 1.1684)
			(drill 0.762)
			(layers "*.Cu" "*.Mask")
			(remove_unused_layers no)
			(net "P12V")
			(clearance 0.0508)
			(thermal_gap 0.0508)
		)
		(pad "P23" thru_hole circle
			(at -2.70002 22.86)
			(size 1.1684 1.1684)
			(drill 0.762)
			(layers "*.Cu" "*.Mask")
			(remove_unused_layers no)
			(net "P12V")
			(clearance 0.0508)
			(thermal_gap 0.0508)
		)
		(pad "P24" thru_hole circle
			(at -2.70002 20.32)
			(size 1.1684 1.1684)
			(drill 0.762)
			(layers "*.Cu" "*.Mask")
			(remove_unused_layers no)
			(net "P12V")
			(clearance 0.0508)
			(thermal_gap 0.0508)
		)
		(pad "P25" thru_hole circle
			(at -2.70002 17.78)
			(size 1.1684 1.1684)
			(drill 0.762)
			(layers "*.Cu" "*.Mask")
			(remove_unused_layers no)
			(net "GND")
			(clearance 0.0508)
			(thermal_gap 0.0508)
		)
		(pad "P26" thru_hole circle
			(at -2.70002 15.24)
			(size 1.1684 1.1684)
			(drill 0.762)
			(layers "*.Cu" "*.Mask")
			(remove_unused_layers no)
			(net "GND")
			(clearance 0.0508)
			(thermal_gap 0.0508)
		)
		(pad "P27" thru_hole circle
			(at -2.70002 12.7)
			(size 1.1684 1.1684)
			(drill 0.762)
			(layers "*.Cu" "*.Mask")
			(remove_unused_layers no)
			(net "GND")
			(clearance 0.0508)
			(thermal_gap 0.0508)
		)
		(pad "P28" thru_hole circle
			(at -2.70002 10.16)
			(size 1.1684 1.1684)
			(drill 0.762)
			(layers "*.Cu" "*.Mask")
			(remove_unused_layers no)
			(net "GND")
			(clearance 0.0508)
			(thermal_gap 0.0508)
		)
		(pad "P29" thru_hole circle
			(at -2.70002 7.62)
			(size 1.1684 1.1684)
			(drill 0.762)
			(layers "*.Cu" "*.Mask")
			(remove_unused_layers no)
			(net "GND")
			(clearance 0.0508)
			(thermal_gap 0.0508)
		)
		(pad "P30" thru_hole circle
			(at -2.70002 5.08)
			(size 1.1684 1.1684)
			(drill 0.762)
			(layers "*.Cu" "*.Mask")
			(remove_unused_layers no)
			(net "GND")
			(clearance 0.0508)
			(thermal_gap 0.0508)
		)
		(pad "P31" thru_hole circle
			(at -2.70002 2.54)
			(size 1.1684 1.1684)
			(drill 0.762)
			(layers "*.Cu" "*.Mask")
			(remove_unused_layers no)
			(net "GND")
			(clearance 0.0508)
			(thermal_gap 0.0508)
		)
		(pad "P32" thru_hole circle
			(at -2.70002 0)
			(size 1.1684 1.1684)
			(drill 0.762)
			(layers "*.Cu" "*.Mask")
			(remove_unused_layers no)
			(net "GND")
			(clearance 0.0508)
			(thermal_gap 0.0508)
		)
		(pad "S1" thru_hole circle
			(at 0.55499 41.60012)
			(size 1.1684 1.1684)
			(drill 0.762)
			(layers "*.Cu" "*.Mask")
			(remove_unused_layers no)
			(net "T7_BLAD1_TXD")
			(clearance 0.0508)
			(thermal_gap 0.0508)
		)
		(pad "S2" thru_hole circle
			(at -0.71501 42.87012)
			(size 1.1684 1.1684)
			(drill 0.762)
			(layers "*.Cu" "*.Mask")
			(remove_unused_layers no)
			(net "T7_BLAD1_RXD")
			(clearance 0.0508)
			(thermal_gap 0.0508)
		)
		(pad "S3" thru_hole circle
			(at 0.55499 44.14012)
			(size 1.1684 1.1684)
			(drill 0.762)
			(layers "*.Cu" "*.Mask")
			(remove_unused_layers no)
			(net "T7_BLAD1_EN")
			(clearance 0.0508)
			(thermal_gap 0.0508)
		)
		(pad "S4" thru_hole circle
			(at -0.71501 45.41012)
			(size 1.1684 1.1684)
			(drill 0.762)
			(layers "*.Cu" "*.Mask")
			(remove_unused_layers no)
			(net "B13_PSU_ALERT_N")
			(clearance 0.0508)
			(thermal_gap 0.0508)
		)
		(pad "S5" thru_hole circle
			(at 0.55499 46.68012)
			(size 1.1684 1.1684)
			(drill 0.762)
			(layers "*.Cu" "*.Mask")
			(remove_unused_layers no)
			(net "T7_BLAD2_TXD")
			(clearance 0.0508)
			(thermal_gap 0.0508)
		)
		(pad "S6" thru_hole circle
			(at -0.71501 47.95012)
			(size 1.1684 1.1684)
			(drill 0.762)
			(layers "*.Cu" "*.Mask")
			(remove_unused_layers no)
			(net "T7_BLAD2_RXD")
			(clearance 0.0508)
			(thermal_gap 0.0508)
		)
		(pad "S7" thru_hole circle
			(at -3.25501 47.95012)
			(size 1.1684 1.1684)
			(drill 0.762)
			(layers "*.Cu" "*.Mask")
			(remove_unused_layers no)
			(net "T7_BLAD4_RXD")
			(clearance 0.0508)
			(thermal_gap 0.0508)
		)
		(pad "S8" thru_hole circle
			(at -1.98501 46.68012)
			(size 1.1684 1.1684)
			(drill 0.762)
			(layers "*.Cu" "*.Mask")
			(remove_unused_layers no)
			(net "T7_BLAD4_TXD")
			(clearance 0.0508)
			(thermal_gap 0.0508)
		)
		(pad "S9" thru_hole circle
			(at -3.25501 45.41012)
			(size 1.1684 1.1684)
			(drill 0.762)
			(layers "*.Cu" "*.Mask")
			(remove_unused_layers no)
			(net "B14_PSU_ALERT_N")
			(clearance 0.0508)
			(thermal_gap 0.0508)
		)
		(pad "S10" thru_hole circle
			(at -1.98501 44.14012)
			(size 1.1684 1.1684)
			(drill 0.762)
			(layers "*.Cu" "*.Mask")
			(remove_unused_layers no)
			(net "T7_BLAD3_EN")
			(clearance 0.0508)
			(thermal_gap 0.0508)
		)
		(pad "S11" thru_hole circle
			(at -3.25501 42.87012)
			(size 1.1684 1.1684)
			(drill 0.762)
			(layers "*.Cu" "*.Mask")
			(remove_unused_layers no)
			(net "T7_BLAD3_RXD")
			(clearance 0.0508)
			(thermal_gap 0.0508)
		)
		(pad "S12" thru_hole circle
			(at -1.98501 41.60012)
			(size 1.1684 1.1684)
			(drill 0.762)
			(layers "*.Cu" "*.Mask")
			(remove_unused_layers no)
			(net "T7_BLAD3_TXD")
			(clearance 0.0508)
			(thermal_gap 0.0508)
		)
		(zone
			(layer "F.Cu")
			(hatch none 0.5)
			(connect_pads
				(clearance 0)
			)
			(min_thickness 0.25)
			(keepout
				(tracks allowed)
				(vias not_allowed)
				(pads allowed)
				(copperpour not_allowed)
				(footprints allowed)
			)
			(placement
				(enabled no)
				(sheetname "")
			)
			(fill
				(thermal_gap 0.5)
				(thermal_bridge_width 0.5)
				(island_removal_mode 0)
			)
			(polygon
				(pts
					(xy 85.00999 -276.15388) (xy 92.65539 -276.15388) (xy 92.65539 -271.04848) (xy 85.00999 -271.04848)
					(xy 84.98459 -271.04848) (xy 84.98459 -276.15388)
				)
			)
		)
		(zone
			(layer "F.Cu")
			(hatch none 0.5)
			(connect_pads
				(clearance 0)
			)
			(min_thickness 0.25)
			(keepout
				(tracks allowed)
				(vias not_allowed)
				(pads allowed)
				(copperpour not_allowed)
				(footprints allowed)
			)
			(placement
				(enabled no)
				(sheetname "")
			)
			(fill
				(thermal_gap 0.5)
				(thermal_bridge_width 0.5)
				(island_removal_mode 0)
			)
			(polygon
				(pts
					(xy 43.37939 -271.63268) (xy 43.37939 -275.59508) (xy 82.77479 -275.59508) (xy 82.80019 -275.59508)
					(xy 82.80019 -271.63268) (xy 82.80019 -271.60728) (xy 43.37939 -271.60728)
				)
			)
		)
		(zone
			(layers "F.Cu" "B.Cu" "In1.Cu" "In2.Cu" "In3.Cu" "In4.Cu" "In5.Cu" "In6.Cu")
			(hatch none 0.5)
			(connect_pads
				(clearance 0)
			)
			(min_thickness 0.25)
			(keepout
				(tracks not_allowed)
				(vias allowed)
				(pads allowed)
				(copperpour not_allowed)
				(footprints allowed)
			)
			(placement
				(enabled no)
				(sheetname "")
			)
			(fill
				(thermal_gap 0.5)
				(thermal_bridge_width 0.5)
				(island_removal_mode 0)
			)
			(polygon
				(pts
					(arc
						(start 43.18 -273.61007)
						(mid 39.81958 -273.61007)
						(end 43.18 -273.61007)
					)
				)
			)
		)
		(zone
			(layers "F.Cu" "B.Cu" "In1.Cu" "In2.Cu" "In3.Cu" "In4.Cu" "In5.Cu" "In6.Cu")
			(hatch none 0.5)
			(connect_pads
				(clearance 0)
			)
			(min_thickness 0.25)
			(keepout
				(tracks not_allowed)
				(vias allowed)
				(pads allowed)
				(copperpour not_allowed)
				(footprints allowed)
			)
			(placement
				(enabled no)
				(sheetname "")
			)
			(fill
				(thermal_gap 0.5)
				(thermal_bridge_width 0.5)
				(island_removal_mode 0)
			)
			(polygon
				(pts
					(arc
						(start 96.52381 -274.96008)
						(mid 93.15577 -274.96008)
						(end 96.52381 -274.96008)
					)
				)
			)
		)
	)
	(footprint ""
		(layer "B.Cu")
		(at 98.951288 -16.810228)
		(property "Reference" ""
			(at 0 0 0)
			(layer "B.SilkS")
			(hide yes)
			(effects
				(font
					(size 1.27 1.27)
				)
				(justify mirror)
			)
		)
		(property "Value" ""
			(at 0 0 0)
			(layer "B.Fab")
			(effects
				(font
					(size 1.27 1.27)
				)
				(justify mirror)
			)
		)
		(duplicate_pad_numbers_are_jumpers no)
		(fp_poly
			(pts
				(arc
					(start 1.4986 0)
					(mid -1.4986 0)
					(end 1.4986 0)
				)
			)
			(stroke
				(width 0)
				(type default)
			)
			(fill no)
			(layer "B.CrtYd")
		)
		(pad "1" smd circle
			(at 0 0 180)
			(size 0.9906 0.9906)
			(layers "B.Cu" "B.Mask" "B.Paste")
			(net "Net_70")
		)
		(zone
			(layer "B.Cu")
			(hatch none 0.5)
			(connect_pads
				(clearance 0)
			)
			(min_thickness 0.25)
			(keepout
				(tracks not_allowed)
				(vias allowed)
				(pads allowed)
				(copperpour not_allowed)
				(footprints allowed)
			)
			(placement
				(enabled no)
				(sheetname "")
			)
			(fill
				(thermal_gap 0.5)
				(thermal_bridge_width 0.5)
				(island_removal_mode 0)
			)
			(polygon
				(pts
					(arc
						(start 100.576888 -16.810228)
						(mid 97.325688 -16.810228)
						(end 100.576888 -16.810228)
					)
				)
			)
		)
	)
	(gr_poly
		(pts
			(xy 14.568932 -328.07656) (xy 15.251176 -328.07656) (xy 17.832324 -328.07656) (xy 21.457666 -328.07656)
			(xy 21.936456 -327.59777) (xy 21.936456 -320.261742) (xy 19.476974 -317.80226) (xy 15.26667 -317.80226)
			(xy 15.151608 -317.917322) (xy 15.151608 -318.720216) (xy 14.938248 -318.933576) (xy 13.675106 -318.933576)
			(xy 13.523976 -319.084706) (xy 13.523976 -320.07175) (xy 13.523976 -326.502776) (xy 13.523976 -327.757028)
			(xy 13.844016 -328.077068) (xy 14.568424 -328.077068)
		)
		(stroke
			(width 0)
			(type solid)
		)
		(fill yes)
		(layer "F.Cu")
		(net "P12V")
	)
	(gr_poly
		(pts
			(xy 21.243036 -451.027038) (xy 21.243036 -450.547994) (xy 21.41982 -450.37121) (xy 21.41982 -449.989956)
			(arc
				(start 21.416518 -449.975732)
				(mid 21.403207 -449.860162)
				(end 21.416518 -449.744592)
			)
			(xy 21.41982 -449.730368) (xy 21.41982 -447.374518) (xy 21.426424 -447.368168) (xy 21.426424 -447.290952)
			(xy 21.503132 -447.290952) (xy 21.86305 -446.931288) (xy 21.86305 -446.29324) (xy 21.725382 -446.155572)
			(xy 19.332448 -446.155572) (xy 18.950178 -446.537842) (xy 18.950178 -449.452492)
			(arc
				(start 19.684492 -450.18706)
				(mid 19.876101 -450.508692)
				(end 19.891502 -450.882766)
			)
			(arc
				(start 19.891502 -450.882766)
				(mid 19.942969 -451.095019)
				(end 20.140168 -451.188836)
			)
			(xy 21.081238 -451.188836)
		)
		(stroke
			(width 0)
			(type solid)
		)
		(fill yes)
		(layer "F.Cu")
		(net "P3V3_BUF")
	)
	(gr_poly
		(pts
			(xy 83.003644 -430.150016) (xy 83.003143 -430.049886) (xy 82.995131 -429.849786) (xy 82.979119 -429.650167)
			(xy 82.955133 -429.451348) (xy 82.923212 -429.253649) (xy 82.883407 -429.057384) (xy 82.835781 -428.86287)
			(xy 82.78041 -428.670416) (xy 82.717384 -428.480333) (xy 82.646804 -428.292923) (xy 82.568781 -428.108487)
			(xy 82.483442 -427.92732) (xy 82.390923 -427.749713) (xy 82.291372 -427.575949) (xy 82.184948 -427.406308)
			(xy 82.071822 -427.24106) (xy 81.952176 -427.080471) (xy 81.8262 -426.924798) (xy 81.694096 -426.774289)
			(xy 81.556077 -426.629187) (xy 81.412362 -426.489723) (xy 81.263183 -426.35612) (xy 81.108778 -426.228593)
			(xy 80.949394 -426.107345) (xy 80.785286 -425.992572) (xy 80.616718 -425.884457) (xy 80.44396 -425.783172)
			(xy 80.267287 -425.68888) (xy 80.086983 -425.601733) (xy 79.903337 -425.521869) (xy 79.716642 -425.449417)
			(xy 79.527199 -425.384492) (xy 79.335309 -425.327199) (xy 79.141281 -425.277629) (xy 78.945424 -425.235862)
			(xy 78.748054 -425.201965) (xy 78.549485 -425.175991) (xy 78.350036 -425.157983) (xy 78.150027 -425.147969)
			(xy 77.949776 -425.145965) (xy 77.749606 -425.151975) (xy 77.549837 -425.165989) (xy 77.350789 -425.187985)
			(xy 77.152779 -425.217926) (xy 76.956127 -425.255766) (xy 76.761145 -425.301444) (xy 76.568148 -425.354886)
			(xy 76.377443 -425.416007) (xy 76.189336 -425.484709) (xy 76.004129 -425.560882) (xy 75.822117 -425.644405)
			(xy 75.643593 -425.735142) (xy 75.468842 -425.83295) (xy 75.298145 -425.937671) (xy 75.131774 -426.049138)
			(xy 74.969996 -426.167172) (xy 74.81307 -426.291584) (xy 74.661247 -426.422175) (xy 74.514771 -426.558736)
			(xy 74.373876 -426.701048) (xy 74.238787 -426.848883) (xy 74.109722 -427.002005) (xy 73.986886 -427.160167)
			(xy 73.870476 -427.323118) (xy 73.76068 -427.490596) (xy 73.657672 -427.662333) (xy 73.561617 -427.838053)
			(xy 73.47267 -428.017476) (xy 73.390973 -428.200314) (xy 73.316657 -428.386275) (xy 73.24984 -428.575059)
			(xy 73.19063 -428.766366) (xy 73.139121 -428.959889) (xy 73.095397 -429.155317) (xy 73.059526 -429.352339)
			(xy 73.031567 -429.550638) (xy 73.011564 -429.749896) (xy 72.99955 -429.949796) (xy 72.995543 -430.150016)
			(xy 75.484741 -430.150016) (xy 75.488769 -430.007724) (xy 75.500841 -429.865888) (xy 75.520918 -429.724961)
			(xy 75.548936 -429.585397) (xy 75.584805 -429.447641) (xy 75.62841 -429.312135) (xy 75.679611 -429.179313)
			(xy 75.738245 -429.0496) (xy 75.804123 -428.923413) (xy 75.877035 -428.801154) (xy 75.956747 -428.683217)
			(xy 76.043004 -428.569978) (xy 76.135528 -428.4618) (xy 76.234025 -428.35903) (xy 76.338179 -428.261997)
			(xy 76.447655 -428.171013) (xy 76.562103 -428.086367) (xy 76.681157 -428.008332) (xy 76.804435 -427.937158)
			(xy 76.931542 -427.873071) (xy 77.062071 -427.816279) (xy 77.195605 -427.766962) (xy 77.331714 -427.725279)
			(xy 77.469964 -427.691363) (xy 77.609911 -427.665323) (xy 77.751107 -427.647242) (xy 77.8931 -427.637179)
			(xy 78.035435 -427.635164) (xy 78.177656 -427.641206) (xy 78.319307 -427.655284) (xy 78.459935 -427.677353)
			(xy 78.599089 -427.707343) (xy 78.736324 -427.745158) (xy 78.871199 -427.790676) (xy 79.003283 -427.843752)
			(xy 79.132153 -427.904215) (xy 79.257396 -427.971872) (xy 79.37861 -428.046507) (xy 79.495408 -428.12788)
			(xy 79.607415 -428.21573) (xy 79.714273 -428.309777) (xy 79.815638 -428.409718) (xy 79.911187 -428.515234)
			(xy 80.000614 -428.625987) (xy 80.083632 -428.741621) (xy 80.159974 -428.861768) (xy 80.229397 -428.98604)
			(xy 80.291678 -429.114042) (xy 80.346618 -429.245362) (xy 80.39404 -429.379579) (xy 80.433793 -429.516265)
			(xy 80.465749 -429.654981) (xy 80.489806 -429.795282) (xy 80.505887 -429.93672) (xy 80.51394 -430.078841)
			(xy 80.514444 -430.150016) (xy 80.51394 -430.221191) (xy 80.505887 -430.363312) (xy 80.489806 -430.50475)
			(xy 80.465749 -430.645051) (xy 80.433793 -430.783767) (xy 80.39404 -430.920453) (xy 80.346618 -431.05467)
			(xy 80.291678 -431.18599) (xy 80.229397 -431.313992) (xy 80.159974 -431.438264) (xy 80.083632 -431.558411)
			(xy 80.000614 -431.674045) (xy 79.911187 -431.784798) (xy 79.815638 -431.890314) (xy 79.714273 -431.990255)
			(xy 79.607415 -432.084302) (xy 79.495408 -432.172152) (xy 79.37861 -432.253525) (xy 79.257396 -432.32816)
			(xy 79.132153 -432.395817) (xy 79.003283 -432.45628) (xy 78.871199 -432.509356) (xy 78.736324 -432.554874)
			(xy 78.599089 -432.592689) (xy 78.459935 -432.622679) (xy 78.319307 -432.644748) (xy 78.177656 -432.658826)
			(xy 78.035435 -432.664868) (xy 77.8931 -432.662853) (xy 77.751107 -432.65279) (xy 77.609911 -432.634709)
			(xy 77.469964 -432.608669) (xy 77.331714 -432.574753) (xy 77.195605 -432.53307) (xy 77.062071 -432.483753)
			(xy 76.931542 -432.426961) (xy 76.804435 -432.362874) (xy 76.681157 -432.2917) (xy 76.562103 -432.213665)
			(xy 76.447655 -432.129019) (xy 76.338179 -432.038035) (xy 76.234025 -431.941002) (xy 76.135528 -431.838232)
			(xy 76.043004 -431.730054) (xy 75.956747 -431.616815) (xy 75.877035 -431.498878) (xy 75.804123 -431.376619)
			(xy 75.738245 -431.250432) (xy 75.679611 -431.120719) (xy 75.62841 -430.987897) (xy 75.584805 -430.852391)
			(xy 75.548936 -430.714635) (xy 75.520918 -430.575071) (xy 75.500841 -430.434144) (xy 75.488769 -430.292308)
			(xy 75.484741 -430.150016) (xy 72.995543 -430.150016) (xy 72.99955 -430.350236) (xy 73.011564 -430.550136)
			(xy 73.031567 -430.749394) (xy 73.059526 -430.947693) (xy 73.095397 -431.144715) (xy 73.139121 -431.340143)
			(xy 73.19063 -431.533666) (xy 73.24984 -431.724973) (xy 73.316657 -431.913757) (xy 73.390973 -432.099718)
			(xy 73.47267 -432.282556) (xy 73.561617 -432.461979) (xy 73.657672 -432.637699) (xy 73.76068 -432.809436)
			(xy 73.870476 -432.976914) (xy 73.986886 -433.139865) (xy 74.109722 -433.298027) (xy 74.238787 -433.451149)
			(xy 74.373876 -433.598984) (xy 74.514771 -433.741296) (xy 74.661247 -433.877857) (xy 74.81307 -434.008448)
			(xy 74.969996 -434.13286) (xy 75.131774 -434.250894) (xy 75.298145 -434.362361) (xy 75.468842 -434.467082)
			(xy 75.643593 -434.56489) (xy 75.822117 -434.655627) (xy 76.004129 -434.73915) (xy 76.189336 -434.815323)
			(xy 76.377443 -434.884025) (xy 76.568148 -434.945146) (xy 76.761145 -434.998588) (xy 76.956127 -435.044266)
			(xy 77.152779 -435.082106) (xy 77.350789 -435.112047) (xy 77.549837 -435.134043) (xy 77.749606 -435.148057)
			(xy 77.949776 -435.154067) (xy 78.150027 -435.152063) (xy 78.350036 -435.142049) (xy 78.549485 -435.124041)
			(xy 78.748054 -435.098067) (xy 78.945424 -435.06417) (xy 79.141281 -435.022403) (xy 79.335309 -434.972833)
			(xy 79.527199 -434.91554) (xy 79.716642 -434.850615) (xy 79.903337 -434.778163) (xy 80.086983 -434.698299)
			(xy 80.267287 -434.611152) (xy 80.44396 -434.51686) (xy 80.616718 -434.415575) (xy 80.785286 -434.30746)
			(xy 80.949394 -434.192687) (xy 81.108778 -434.071439) (xy 81.263183 -433.943912) (xy 81.412362 -433.810309)
			(xy 81.556077 -433.670845) (xy 81.694096 -433.525743) (xy 81.8262 -433.375234) (xy 81.952176 -433.219561)
			(xy 82.071822 -433.058972) (xy 82.184948 -432.893724) (xy 82.291372 -432.724083) (xy 82.390923 -432.550319)
			(xy 82.483442 -432.372712) (xy 82.568781 -432.191545) (xy 82.646804 -432.007109) (xy 82.717384 -431.819699)
			(xy 82.78041 -431.629616) (xy 82.835781 -431.437162) (xy 82.883407 -431.242648) (xy 82.923212 -431.046383)
			(xy 82.955133 -430.848684) (xy 82.979119 -430.649865) (xy 82.995131 -430.450246) (xy 83.003143 -430.250146)
		)
		(stroke
			(width 0)
			(type solid)
		)
		(fill yes)
		(layer "F.Cu")
		(net "GND")
	)
	(gr_poly
		(pts
			(xy 83.003644 -341.250016) (xy 83.003143 -341.149886) (xy 82.995131 -340.949786) (xy 82.979119 -340.750167)
			(xy 82.955133 -340.551348) (xy 82.923212 -340.353649) (xy 82.883407 -340.157384) (xy 82.835781 -339.96287)
			(xy 82.78041 -339.770416) (xy 82.717384 -339.580333) (xy 82.646804 -339.392923) (xy 82.568781 -339.208487)
			(xy 82.483442 -339.02732) (xy 82.390923 -338.849713) (xy 82.291372 -338.675949) (xy 82.184948 -338.506308)
			(xy 82.071822 -338.34106) (xy 81.952176 -338.180471) (xy 81.8262 -338.024798) (xy 81.694096 -337.874289)
			(xy 81.556077 -337.729187) (xy 81.412362 -337.589723) (xy 81.263183 -337.45612) (xy 81.108778 -337.328593)
			(xy 80.949394 -337.207345) (xy 80.785286 -337.092572) (xy 80.616718 -336.984457) (xy 80.44396 -336.883172)
			(xy 80.267287 -336.78888) (xy 80.086983 -336.701733) (xy 79.903337 -336.621869) (xy 79.716642 -336.549417)
			(xy 79.527199 -336.484492) (xy 79.335309 -336.427199) (xy 79.141281 -336.377629) (xy 78.945424 -336.335862)
			(xy 78.748054 -336.301965) (xy 78.549485 -336.275991) (xy 78.350036 -336.257983) (xy 78.150027 -336.247969)
			(xy 77.949776 -336.245965) (xy 77.749606 -336.251975) (xy 77.549837 -336.265989) (xy 77.350789 -336.287985)
			(xy 77.152779 -336.317926) (xy 76.956127 -336.355766) (xy 76.761145 -336.401444) (xy 76.568148 -336.454886)
			(xy 76.377443 -336.516007) (xy 76.189336 -336.584709) (xy 76.004129 -336.660882) (xy 75.822117 -336.744405)
			(xy 75.643593 -336.835142) (xy 75.468842 -336.93295) (xy 75.298145 -337.037671) (xy 75.131774 -337.149138)
			(xy 74.969996 -337.267172) (xy 74.81307 -337.391584) (xy 74.661247 -337.522175) (xy 74.514771 -337.658736)
			(xy 74.373876 -337.801048) (xy 74.238787 -337.948883) (xy 74.109722 -338.102005) (xy 73.986886 -338.260167)
			(xy 73.870476 -338.423118) (xy 73.76068 -338.590596) (xy 73.657672 -338.762333) (xy 73.561617 -338.938053)
			(xy 73.47267 -339.117476) (xy 73.390973 -339.300314) (xy 73.316657 -339.486275) (xy 73.24984 -339.675059)
			(xy 73.19063 -339.866366) (xy 73.139121 -340.059889) (xy 73.095397 -340.255317) (xy 73.059526 -340.452339)
			(xy 73.031567 -340.650638) (xy 73.011564 -340.849896) (xy 72.99955 -341.049796) (xy 72.995543 -341.250016)
			(xy 75.484741 -341.250016) (xy 75.488769 -341.107724) (xy 75.500841 -340.965888) (xy 75.520918 -340.824961)
			(xy 75.548936 -340.685397) (xy 75.584805 -340.547641) (xy 75.62841 -340.412135) (xy 75.679611 -340.279313)
			(xy 75.738245 -340.1496) (xy 75.804123 -340.023413) (xy 75.877035 -339.901154) (xy 75.956747 -339.783217)
			(xy 76.043004 -339.669978) (xy 76.135528 -339.5618) (xy 76.234025 -339.45903) (xy 76.338179 -339.361997)
			(xy 76.447655 -339.271013) (xy 76.562103 -339.186367) (xy 76.681157 -339.108332) (xy 76.804435 -339.037158)
			(xy 76.931542 -338.973071) (xy 77.062071 -338.916279) (xy 77.195605 -338.866962) (xy 77.331714 -338.825279)
			(xy 77.469964 -338.791363) (xy 77.609911 -338.765323) (xy 77.751107 -338.747242) (xy 77.8931 -338.737179)
			(xy 78.035435 -338.735164) (xy 78.177656 -338.741206) (xy 78.319307 -338.755284) (xy 78.459935 -338.777353)
			(xy 78.599089 -338.807343) (xy 78.736324 -338.845158) (xy 78.871199 -338.890676) (xy 79.003283 -338.943752)
			(xy 79.132153 -339.004215) (xy 79.257396 -339.071872) (xy 79.37861 -339.146507) (xy 79.495408 -339.22788)
			(xy 79.607415 -339.31573) (xy 79.714273 -339.409777) (xy 79.815638 -339.509718) (xy 79.911187 -339.615234)
			(xy 80.000614 -339.725987) (xy 80.083632 -339.841621) (xy 80.159974 -339.961768) (xy 80.229397 -340.08604)
			(xy 80.291678 -340.214042) (xy 80.346618 -340.345362) (xy 80.39404 -340.479579) (xy 80.433793 -340.616265)
			(xy 80.465749 -340.754981) (xy 80.489806 -340.895282) (xy 80.505887 -341.03672) (xy 80.51394 -341.178841)
			(xy 80.514444 -341.250016) (xy 80.51394 -341.321191) (xy 80.505887 -341.463312) (xy 80.489806 -341.60475)
			(xy 80.465749 -341.745051) (xy 80.433793 -341.883767) (xy 80.39404 -342.020453) (xy 80.346618 -342.15467)
			(xy 80.291678 -342.28599) (xy 80.229397 -342.413992) (xy 80.159974 -342.538264) (xy 80.083632 -342.658411)
			(xy 80.000614 -342.774045) (xy 79.911187 -342.884798) (xy 79.815638 -342.990314) (xy 79.714273 -343.090255)
			(xy 79.607415 -343.184302) (xy 79.495408 -343.272152) (xy 79.37861 -343.353525) (xy 79.257396 -343.42816)
			(xy 79.132153 -343.495817) (xy 79.003283 -343.55628) (xy 78.871199 -343.609356) (xy 78.736324 -343.654874)
			(xy 78.599089 -343.692689) (xy 78.459935 -343.722679) (xy 78.319307 -343.744748) (xy 78.177656 -343.758826)
			(xy 78.035435 -343.764868) (xy 77.8931 -343.762853) (xy 77.751107 -343.75279) (xy 77.609911 -343.734709)
			(xy 77.469964 -343.708669) (xy 77.331714 -343.674753) (xy 77.195605 -343.63307) (xy 77.062071 -343.583753)
			(xy 76.931542 -343.526961) (xy 76.804435 -343.462874) (xy 76.681157 -343.3917) (xy 76.562103 -343.313665)
			(xy 76.447655 -343.229019) (xy 76.338179 -343.138035) (xy 76.234025 -343.041002) (xy 76.135528 -342.938232)
			(xy 76.043004 -342.830054) (xy 75.956747 -342.716815) (xy 75.877035 -342.598878) (xy 75.804123 -342.476619)
			(xy 75.738245 -342.350432) (xy 75.679611 -342.220719) (xy 75.62841 -342.087897) (xy 75.584805 -341.952391)
			(xy 75.548936 -341.814635) (xy 75.520918 -341.675071) (xy 75.500841 -341.534144) (xy 75.488769 -341.392308)
			(xy 75.484741 -341.250016) (xy 72.995543 -341.250016) (xy 72.99955 -341.450236) (xy 73.011564 -341.650136)
			(xy 73.031567 -341.849394) (xy 73.059526 -342.047693) (xy 73.095397 -342.244715) (xy 73.139121 -342.440143)
			(xy 73.19063 -342.633666) (xy 73.24984 -342.824973) (xy 73.316657 -343.013757) (xy 73.390973 -343.199718)
			(xy 73.47267 -343.382556) (xy 73.561617 -343.561979) (xy 73.657672 -343.737699) (xy 73.76068 -343.909436)
			(xy 73.870476 -344.076914) (xy 73.986886 -344.239865) (xy 74.109722 -344.398027) (xy 74.238787 -344.551149)
			(xy 74.373876 -344.698984) (xy 74.514771 -344.841296) (xy 74.661247 -344.977857) (xy 74.81307 -345.108448)
			(xy 74.969996 -345.23286) (xy 75.131774 -345.350894) (xy 75.298145 -345.462361) (xy 75.468842 -345.567082)
			(xy 75.643593 -345.66489) (xy 75.822117 -345.755627) (xy 76.004129 -345.83915) (xy 76.189336 -345.915323)
			(xy 76.377443 -345.984025) (xy 76.568148 -346.045146) (xy 76.761145 -346.098588) (xy 76.956127 -346.144266)
			(xy 77.152779 -346.182106) (xy 77.350789 -346.212047) (xy 77.549837 -346.234043) (xy 77.749606 -346.248057)
			(xy 77.949776 -346.254067) (xy 78.150027 -346.252063) (xy 78.350036 -346.242049) (xy 78.549485 -346.224041)
			(xy 78.748054 -346.198067) (xy 78.945424 -346.16417) (xy 79.141281 -346.122403) (xy 79.335309 -346.072833)
			(xy 79.527199 -346.01554) (xy 79.716642 -345.950615) (xy 79.903337 -345.878163) (xy 80.086983 -345.798299)
			(xy 80.267287 -345.711152) (xy 80.44396 -345.61686) (xy 80.616718 -345.515575) (xy 80.785286 -345.40746)
			(xy 80.949394 -345.292687) (xy 81.108778 -345.171439) (xy 81.263183 -345.043912) (xy 81.412362 -344.910309)
			(xy 81.556077 -344.770845) (xy 81.694096 -344.625743) (xy 81.8262 -344.475234) (xy 81.952176 -344.319561)
			(xy 82.071822 -344.158972) (xy 82.184948 -343.993724) (xy 82.291372 -343.824083) (xy 82.390923 -343.650319)
			(xy 82.483442 -343.472712) (xy 82.568781 -343.291545) (xy 82.646804 -343.107109) (xy 82.717384 -342.919699)
			(xy 82.78041 -342.729616) (xy 82.835781 -342.537162) (xy 82.883407 -342.342648) (xy 82.923212 -342.146383)
			(xy 82.955133 -341.948684) (xy 82.979119 -341.749865) (xy 82.995131 -341.550246) (xy 83.003143 -341.350146)
		)
		(stroke
			(width 0)
			(type solid)
		)
		(fill yes)
		(layer "F.Cu")
		(net "GND")
	)
	(gr_poly
		(pts
			(xy 83.003644 -210.09991) (xy 83.003143 -209.99978) (xy 82.995131 -209.79968) (xy 82.979119 -209.600061)
			(xy 82.955133 -209.401242) (xy 82.923212 -209.203543) (xy 82.883407 -209.007278) (xy 82.835781 -208.812764)
			(xy 82.78041 -208.62031) (xy 82.717384 -208.430227) (xy 82.646804 -208.242817) (xy 82.568781 -208.058381)
			(xy 82.483442 -207.877214) (xy 82.390923 -207.699607) (xy 82.291372 -207.525843) (xy 82.184948 -207.356202)
			(xy 82.071822 -207.190954) (xy 81.952176 -207.030365) (xy 81.8262 -206.874692) (xy 81.694096 -206.724183)
			(xy 81.556077 -206.579081) (xy 81.412362 -206.439617) (xy 81.263183 -206.306014) (xy 81.108778 -206.178487)
			(xy 80.949394 -206.057239) (xy 80.785286 -205.942466) (xy 80.616718 -205.834351) (xy 80.44396 -205.733066)
			(xy 80.267287 -205.638774) (xy 80.086983 -205.551627) (xy 79.903337 -205.471763) (xy 79.716642 -205.399311)
			(xy 79.527199 -205.334386) (xy 79.335309 -205.277093) (xy 79.141281 -205.227523) (xy 78.945424 -205.185756)
			(xy 78.748054 -205.151859) (xy 78.549485 -205.125885) (xy 78.350036 -205.107877) (xy 78.150027 -205.097863)
			(xy 77.949776 -205.095859) (xy 77.749606 -205.101869) (xy 77.549837 -205.115883) (xy 77.350789 -205.137879)
			(xy 77.152779 -205.16782) (xy 76.956127 -205.20566) (xy 76.761145 -205.251338) (xy 76.568148 -205.30478)
			(xy 76.377443 -205.365901) (xy 76.189336 -205.434603) (xy 76.004129 -205.510776) (xy 75.822117 -205.594299)
			(xy 75.643593 -205.685036) (xy 75.468842 -205.782844) (xy 75.298145 -205.887565) (xy 75.131774 -205.999032)
			(xy 74.969996 -206.117066) (xy 74.81307 -206.241478) (xy 74.661247 -206.372069) (xy 74.514771 -206.50863)
			(xy 74.373876 -206.650942) (xy 74.238787 -206.798777) (xy 74.109722 -206.951899) (xy 73.986886 -207.110061)
			(xy 73.870476 -207.273012) (xy 73.76068 -207.44049) (xy 73.657672 -207.612227) (xy 73.561617 -207.787947)
			(xy 73.47267 -207.96737) (xy 73.390973 -208.150208) (xy 73.316657 -208.336169) (xy 73.24984 -208.524953)
			(xy 73.19063 -208.71626) (xy 73.139121 -208.909783) (xy 73.095397 -209.105211) (xy 73.059526 -209.302233)
			(xy 73.031567 -209.500532) (xy 73.011564 -209.69979) (xy 72.99955 -209.89969) (xy 72.995543 -210.09991)
			(xy 75.484741 -210.09991) (xy 75.488769 -209.957618) (xy 75.500841 -209.815782) (xy 75.520918 -209.674855)
			(xy 75.548936 -209.535291) (xy 75.584805 -209.397535) (xy 75.62841 -209.262029) (xy 75.679611 -209.129207)
			(xy 75.738245 -208.999494) (xy 75.804123 -208.873307) (xy 75.877035 -208.751048) (xy 75.956747 -208.633111)
			(xy 76.043004 -208.519872) (xy 76.135528 -208.411694) (xy 76.234025 -208.308924) (xy 76.338179 -208.211891)
			(xy 76.447655 -208.120907) (xy 76.562103 -208.036261) (xy 76.681157 -207.958226) (xy 76.804435 -207.887052)
			(xy 76.931542 -207.822965) (xy 77.062071 -207.766173) (xy 77.195605 -207.716856) (xy 77.331714 -207.675173)
			(xy 77.469964 -207.641257) (xy 77.609911 -207.615217) (xy 77.751107 -207.597136) (xy 77.8931 -207.587073)
			(xy 78.035435 -207.585058) (xy 78.177656 -207.5911) (xy 78.319307 -207.605178) (xy 78.459935 -207.627247)
			(xy 78.599089 -207.657237) (xy 78.736324 -207.695052) (xy 78.871199 -207.74057) (xy 79.003283 -207.793646)
			(xy 79.132153 -207.854109) (xy 79.257396 -207.921766) (xy 79.37861 -207.996401) (xy 79.495408 -208.077774)
			(xy 79.607415 -208.165624) (xy 79.714273 -208.259671) (xy 79.815638 -208.359612) (xy 79.911187 -208.465128)
			(xy 80.000614 -208.575881) (xy 80.083632 -208.691515) (xy 80.159974 -208.811662) (xy 80.229397 -208.935934)
			(xy 80.291678 -209.063936) (xy 80.346618 -209.195256) (xy 80.39404 -209.329473) (xy 80.433793 -209.466159)
			(xy 80.465749 -209.604875) (xy 80.489806 -209.745176) (xy 80.505887 -209.886614) (xy 80.51394 -210.028735)
			(xy 80.514444 -210.09991) (xy 80.51394 -210.171085) (xy 80.505887 -210.313206) (xy 80.489806 -210.454644)
			(xy 80.465749 -210.594945) (xy 80.433793 -210.733661) (xy 80.39404 -210.870347) (xy 80.346618 -211.004564)
			(xy 80.291678 -211.135884) (xy 80.229397 -211.263886) (xy 80.159974 -211.388158) (xy 80.083632 -211.508305)
			(xy 80.000614 -211.623939) (xy 79.911187 -211.734692) (xy 79.815638 -211.840208) (xy 79.714273 -211.940149)
			(xy 79.607415 -212.034196) (xy 79.495408 -212.122046) (xy 79.37861 -212.203419) (xy 79.257396 -212.278054)
			(xy 79.132153 -212.345711) (xy 79.003283 -212.406174) (xy 78.871199 -212.45925) (xy 78.736324 -212.504768)
			(xy 78.599089 -212.542583) (xy 78.459935 -212.572573) (xy 78.319307 -212.594642) (xy 78.177656 -212.60872)
			(xy 78.035435 -212.614762) (xy 77.8931 -212.612747) (xy 77.751107 -212.602684) (xy 77.609911 -212.584603)
			(xy 77.469964 -212.558563) (xy 77.331714 -212.524647) (xy 77.195605 -212.482964) (xy 77.062071 -212.433647)
			(xy 76.931542 -212.376855) (xy 76.804435 -212.312768) (xy 76.681157 -212.241594) (xy 76.562103 -212.163559)
			(xy 76.447655 -212.078913) (xy 76.338179 -211.987929) (xy 76.234025 -211.890896) (xy 76.135528 -211.788126)
			(xy 76.043004 -211.679948) (xy 75.956747 -211.566709) (xy 75.877035 -211.448772) (xy 75.804123 -211.326513)
			(xy 75.738245 -211.200326) (xy 75.679611 -211.070613) (xy 75.62841 -210.937791) (xy 75.584805 -210.802285)
			(xy 75.548936 -210.664529) (xy 75.520918 -210.524965) (xy 75.500841 -210.384038) (xy 75.488769 -210.242202)
			(xy 75.484741 -210.09991) (xy 72.995543 -210.09991) (xy 72.99955 -210.30013) (xy 73.011564 -210.50003)
			(xy 73.031567 -210.699288) (xy 73.059526 -210.897587) (xy 73.095397 -211.094609) (xy 73.139121 -211.290037)
			(xy 73.19063 -211.48356) (xy 73.24984 -211.674867) (xy 73.316657 -211.863651) (xy 73.390973 -212.049612)
			(xy 73.47267 -212.23245) (xy 73.561617 -212.411873) (xy 73.657672 -212.587593) (xy 73.76068 -212.75933)
			(xy 73.870476 -212.926808) (xy 73.986886 -213.089759) (xy 74.109722 -213.247921) (xy 74.238787 -213.401043)
			(xy 74.373876 -213.548878) (xy 74.514771 -213.69119) (xy 74.661247 -213.827751) (xy 74.81307 -213.958342)
			(xy 74.969996 -214.082754) (xy 75.131774 -214.200788) (xy 75.298145 -214.312255) (xy 75.468842 -214.416976)
			(xy 75.643593 -214.514784) (xy 75.822117 -214.605521) (xy 76.004129 -214.689044) (xy 76.189336 -214.765217)
			(xy 76.377443 -214.833919) (xy 76.568148 -214.89504) (xy 76.761145 -214.948482) (xy 76.956127 -214.99416)
			(xy 77.152779 -215.032) (xy 77.350789 -215.061941) (xy 77.549837 -215.083937) (xy 77.749606 -215.097951)
			(xy 77.949776 -215.103961) (xy 78.150027 -215.101957) (xy 78.350036 -215.091943) (xy 78.549485 -215.073935)
			(xy 78.748054 -215.047961) (xy 78.945424 -215.014064) (xy 79.141281 -214.972297) (xy 79.335309 -214.922727)
			(xy 79.527199 -214.865434) (xy 79.716642 -214.800509) (xy 79.903337 -214.728057) (xy 80.086983 -214.648193)
			(xy 80.267287 -214.561046) (xy 80.44396 -214.466754) (xy 80.616718 -214.365469) (xy 80.785286 -214.257354)
			(xy 80.949394 -214.142581) (xy 81.108778 -214.021333) (xy 81.263183 -213.893806) (xy 81.412362 -213.760203)
			(xy 81.556077 -213.620739) (xy 81.694096 -213.475637) (xy 81.8262 -213.325128) (xy 81.952176 -213.169455)
			(xy 82.071822 -213.008866) (xy 82.184948 -212.843618) (xy 82.291372 -212.673977) (xy 82.390923 -212.500213)
			(xy 82.483442 -212.322606) (xy 82.568781 -212.141439) (xy 82.646804 -211.957003) (xy 82.717384 -211.769593)
			(xy 82.78041 -211.57951) (xy 82.835781 -211.387056) (xy 82.883407 -211.192542) (xy 82.923212 -210.996277)
			(xy 82.955133 -210.798578) (xy 82.979119 -210.599759) (xy 82.995131 -210.40014) (xy 83.003143 -210.20004)
		)
		(stroke
			(width 0)
			(type solid)
		)
		(fill yes)
		(layer "F.Cu")
		(net "GND")
	)
	(gr_poly
		(pts
			(xy 83.003644 -121.19991) (xy 83.003143 -121.09978) (xy 82.995131 -120.89968) (xy 82.979119 -120.700061)
			(xy 82.955133 -120.501242) (xy 82.923212 -120.303543) (xy 82.883407 -120.107278) (xy 82.835781 -119.912764)
			(xy 82.78041 -119.72031) (xy 82.717384 -119.530227) (xy 82.646804 -119.342817) (xy 82.568781 -119.158381)
			(xy 82.483442 -118.977214) (xy 82.390923 -118.799607) (xy 82.291372 -118.625843) (xy 82.184948 -118.456202)
			(xy 82.071822 -118.290954) (xy 81.952176 -118.130365) (xy 81.8262 -117.974692) (xy 81.694096 -117.824183)
			(xy 81.556077 -117.679081) (xy 81.412362 -117.539617) (xy 81.263183 -117.406014) (xy 81.108778 -117.278487)
			(xy 80.949394 -117.157239) (xy 80.785286 -117.042466) (xy 80.616718 -116.934351) (xy 80.44396 -116.833066)
			(xy 80.267287 -116.738774) (xy 80.086983 -116.651627) (xy 79.903337 -116.571763) (xy 79.716642 -116.499311)
			(xy 79.527199 -116.434386) (xy 79.335309 -116.377093) (xy 79.141281 -116.327523) (xy 78.945424 -116.285756)
			(xy 78.748054 -116.251859) (xy 78.549485 -116.225885) (xy 78.350036 -116.207877) (xy 78.150027 -116.197863)
			(xy 77.949776 -116.195859) (xy 77.749606 -116.201869) (xy 77.549837 -116.215883) (xy 77.350789 -116.237879)
			(xy 77.152779 -116.26782) (xy 76.956127 -116.30566) (xy 76.761145 -116.351338) (xy 76.568148 -116.40478)
			(xy 76.377443 -116.465901) (xy 76.189336 -116.534603) (xy 76.004129 -116.610776) (xy 75.822117 -116.694299)
			(xy 75.643593 -116.785036) (xy 75.468842 -116.882844) (xy 75.298145 -116.987565) (xy 75.131774 -117.099032)
			(xy 74.969996 -117.217066) (xy 74.81307 -117.341478) (xy 74.661247 -117.472069) (xy 74.514771 -117.60863)
			(xy 74.373876 -117.750942) (xy 74.238787 -117.898777) (xy 74.109722 -118.051899) (xy 73.986886 -118.210061)
			(xy 73.870476 -118.373012) (xy 73.76068 -118.54049) (xy 73.657672 -118.712227) (xy 73.561617 -118.887947)
			(xy 73.47267 -119.06737) (xy 73.390973 -119.250208) (xy 73.316657 -119.436169) (xy 73.24984 -119.624953)
			(xy 73.19063 -119.81626) (xy 73.139121 -120.009783) (xy 73.095397 -120.205211) (xy 73.059526 -120.402233)
			(xy 73.031567 -120.600532) (xy 73.011564 -120.79979) (xy 72.99955 -120.99969) (xy 72.995543 -121.19991)
			(xy 75.484741 -121.19991) (xy 75.488769 -121.057618) (xy 75.500841 -120.915782) (xy 75.520918 -120.774855)
			(xy 75.548936 -120.635291) (xy 75.584805 -120.497535) (xy 75.62841 -120.362029) (xy 75.679611 -120.229207)
			(xy 75.738245 -120.099494) (xy 75.804123 -119.973307) (xy 75.877035 -119.851048) (xy 75.956747 -119.733111)
			(xy 76.043004 -119.619872) (xy 76.135528 -119.511694) (xy 76.234025 -119.408924) (xy 76.338179 -119.311891)
			(xy 76.447655 -119.220907) (xy 76.562103 -119.136261) (xy 76.681157 -119.058226) (xy 76.804435 -118.987052)
			(xy 76.931542 -118.922965) (xy 77.062071 -118.866173) (xy 77.195605 -118.816856) (xy 77.331714 -118.775173)
			(xy 77.469964 -118.741257) (xy 77.609911 -118.715217) (xy 77.751107 -118.697136) (xy 77.8931 -118.687073)
			(xy 78.035435 -118.685058) (xy 78.177656 -118.6911) (xy 78.319307 -118.705178) (xy 78.459935 -118.727247)
			(xy 78.599089 -118.757237) (xy 78.736324 -118.795052) (xy 78.871199 -118.84057) (xy 79.003283 -118.893646)
			(xy 79.132153 -118.954109) (xy 79.257396 -119.021766) (xy 79.37861 -119.096401) (xy 79.495408 -119.177774)
			(xy 79.607415 -119.265624) (xy 79.714273 -119.359671) (xy 79.815638 -119.459612) (xy 79.911187 -119.565128)
			(xy 80.000614 -119.675881) (xy 80.083632 -119.791515) (xy 80.159974 -119.911662) (xy 80.229397 -120.035934)
			(xy 80.291678 -120.163936) (xy 80.346618 -120.295256) (xy 80.39404 -120.429473) (xy 80.433793 -120.566159)
			(xy 80.465749 -120.704875) (xy 80.489806 -120.845176) (xy 80.505887 -120.986614) (xy 80.51394 -121.128735)
			(xy 80.514444 -121.19991) (xy 80.51394 -121.271085) (xy 80.505887 -121.413206) (xy 80.489806 -121.554644)
			(xy 80.465749 -121.694945) (xy 80.433793 -121.833661) (xy 80.39404 -121.970347) (xy 80.346618 -122.104564)
			(xy 80.291678 -122.235884) (xy 80.229397 -122.363886) (xy 80.159974 -122.488158) (xy 80.083632 -122.608305)
			(xy 80.000614 -122.723939) (xy 79.911187 -122.834692) (xy 79.815638 -122.940208) (xy 79.714273 -123.040149)
			(xy 79.607415 -123.134196) (xy 79.495408 -123.222046) (xy 79.37861 -123.303419) (xy 79.257396 -123.378054)
			(xy 79.132153 -123.445711) (xy 79.003283 -123.506174) (xy 78.871199 -123.55925) (xy 78.736324 -123.604768)
			(xy 78.599089 -123.642583) (xy 78.459935 -123.672573) (xy 78.319307 -123.694642) (xy 78.177656 -123.70872)
			(xy 78.035435 -123.714762) (xy 77.8931 -123.712747) (xy 77.751107 -123.702684) (xy 77.609911 -123.684603)
			(xy 77.469964 -123.658563) (xy 77.331714 -123.624647) (xy 77.195605 -123.582964) (xy 77.062071 -123.533647)
			(xy 76.931542 -123.476855) (xy 76.804435 -123.412768) (xy 76.681157 -123.341594) (xy 76.562103 -123.263559)
			(xy 76.447655 -123.178913) (xy 76.338179 -123.087929) (xy 76.234025 -122.990896) (xy 76.135528 -122.888126)
			(xy 76.043004 -122.779948) (xy 75.956747 -122.666709) (xy 75.877035 -122.548772) (xy 75.804123 -122.426513)
			(xy 75.738245 -122.300326) (xy 75.679611 -122.170613) (xy 75.62841 -122.037791) (xy 75.584805 -121.902285)
			(xy 75.548936 -121.764529) (xy 75.520918 -121.624965) (xy 75.500841 -121.484038) (xy 75.488769 -121.342202)
			(xy 75.484741 -121.19991) (xy 72.995543 -121.19991) (xy 72.99955 -121.40013) (xy 73.011564 -121.60003)
			(xy 73.031567 -121.799288) (xy 73.059526 -121.997587) (xy 73.095397 -122.194609) (xy 73.139121 -122.390037)
			(xy 73.19063 -122.58356) (xy 73.24984 -122.774867) (xy 73.316657 -122.963651) (xy 73.390973 -123.149612)
			(xy 73.47267 -123.33245) (xy 73.561617 -123.511873) (xy 73.657672 -123.687593) (xy 73.76068 -123.85933)
			(xy 73.870476 -124.026808) (xy 73.986886 -124.189759) (xy 74.109722 -124.347921) (xy 74.238787 -124.501043)
			(xy 74.373876 -124.648878) (xy 74.514771 -124.79119) (xy 74.661247 -124.927751) (xy 74.81307 -125.058342)
			(xy 74.969996 -125.182754) (xy 75.131774 -125.300788) (xy 75.298145 -125.412255) (xy 75.468842 -125.516976)
			(xy 75.643593 -125.614784) (xy 75.822117 -125.705521) (xy 76.004129 -125.789044) (xy 76.189336 -125.865217)
			(xy 76.377443 -125.933919) (xy 76.568148 -125.99504) (xy 76.761145 -126.048482) (xy 76.956127 -126.09416)
			(xy 77.152779 -126.132) (xy 77.350789 -126.161941) (xy 77.549837 -126.183937) (xy 77.749606 -126.197951)
			(xy 77.949776 -126.203961) (xy 78.150027 -126.201957) (xy 78.350036 -126.191943) (xy 78.549485 -126.173935)
			(xy 78.748054 -126.147961) (xy 78.945424 -126.114064) (xy 79.141281 -126.072297) (xy 79.335309 -126.022727)
			(xy 79.527199 -125.965434) (xy 79.716642 -125.900509) (xy 79.903337 -125.828057) (xy 80.086983 -125.748193)
			(xy 80.267287 -125.661046) (xy 80.44396 -125.566754) (xy 80.616718 -125.465469) (xy 80.785286 -125.357354)
			(xy 80.949394 -125.242581) (xy 81.108778 -125.121333) (xy 81.263183 -124.993806) (xy 81.412362 -124.860203)
			(xy 81.556077 -124.720739) (xy 81.694096 -124.575637) (xy 81.8262 -124.425128) (xy 81.952176 -124.269455)
			(xy 82.071822 -124.108866) (xy 82.184948 -123.943618) (xy 82.291372 -123.773977) (xy 82.390923 -123.600213)
			(xy 82.483442 -123.422606) (xy 82.568781 -123.241439) (xy 82.646804 -123.057003) (xy 82.717384 -122.869593)
			(xy 82.78041 -122.67951) (xy 82.835781 -122.487056) (xy 82.883407 -122.292542) (xy 82.923212 -122.096277)
			(xy 82.955133 -121.898578) (xy 82.979119 -121.699759) (xy 82.995131 -121.50014) (xy 83.003143 -121.30004)
		)
		(stroke
			(width 0)
			(type solid)
		)
		(fill yes)
		(layer "F.Cu")
		(net "GND")
	)
	(gr_poly
		(pts
			(xy 83.003644 -32.29991) (xy 83.003143 -32.19978) (xy 82.995131 -31.99968) (xy 82.979119 -31.800061)
			(xy 82.955133 -31.601242) (xy 82.923212 -31.403543) (xy 82.883407 -31.207278) (xy 82.835781 -31.012764)
			(xy 82.78041 -30.82031) (xy 82.717384 -30.630227) (xy 82.646804 -30.442817) (xy 82.568781 -30.258381)
			(xy 82.483442 -30.077214) (xy 82.390923 -29.899607) (xy 82.291372 -29.725843) (xy 82.184948 -29.556202)
			(xy 82.071822 -29.390954) (xy 81.952176 -29.230365) (xy 81.8262 -29.074692) (xy 81.694096 -28.924183)
			(xy 81.556077 -28.779081) (xy 81.412362 -28.639617) (xy 81.263183 -28.506014) (xy 81.108778 -28.378487)
			(xy 80.949394 -28.257239) (xy 80.785286 -28.142466) (xy 80.616718 -28.034351) (xy 80.44396 -27.933066)
			(xy 80.267287 -27.838774) (xy 80.086983 -27.751627) (xy 79.903337 -27.671763) (xy 79.716642 -27.599311)
			(xy 79.527199 -27.534386) (xy 79.335309 -27.477093) (xy 79.141281 -27.427523) (xy 78.945424 -27.385756)
			(xy 78.748054 -27.351859) (xy 78.549485 -27.325885) (xy 78.350036 -27.307877) (xy 78.150027 -27.297863)
			(xy 77.949776 -27.295859) (xy 77.749606 -27.301869) (xy 77.549837 -27.315883) (xy 77.350789 -27.337879)
			(xy 77.152779 -27.36782) (xy 76.956127 -27.40566) (xy 76.761145 -27.451338) (xy 76.568148 -27.50478)
			(xy 76.377443 -27.565901) (xy 76.189336 -27.634603) (xy 76.004129 -27.710776) (xy 75.822117 -27.794299)
			(xy 75.643593 -27.885036) (xy 75.468842 -27.982844) (xy 75.298145 -28.087565) (xy 75.131774 -28.199032)
			(xy 74.969996 -28.317066) (xy 74.81307 -28.441478) (xy 74.661247 -28.572069) (xy 74.514771 -28.70863)
			(xy 74.373876 -28.850942) (xy 74.238787 -28.998777) (xy 74.109722 -29.151899) (xy 73.986886 -29.310061)
			(xy 73.870476 -29.473012) (xy 73.76068 -29.64049) (xy 73.657672 -29.812227) (xy 73.561617 -29.987947)
			(xy 73.47267 -30.16737) (xy 73.390973 -30.350208) (xy 73.316657 -30.536169) (xy 73.24984 -30.724953)
			(xy 73.19063 -30.91626) (xy 73.139121 -31.109783) (xy 73.095397 -31.305211) (xy 73.059526 -31.502233)
			(xy 73.031567 -31.700532) (xy 73.011564 -31.89979) (xy 72.99955 -32.09969) (xy 72.995543 -32.29991)
			(xy 75.484741 -32.29991) (xy 75.488769 -32.157618) (xy 75.500841 -32.015782) (xy 75.520918 -31.874855)
			(xy 75.548936 -31.735291) (xy 75.584805 -31.597535) (xy 75.62841 -31.462029) (xy 75.679611 -31.329207)
			(xy 75.738245 -31.199494) (xy 75.804123 -31.073307) (xy 75.877035 -30.951048) (xy 75.956747 -30.833111)
			(xy 76.043004 -30.719872) (xy 76.135528 -30.611694) (xy 76.234025 -30.508924) (xy 76.338179 -30.411891)
			(xy 76.447655 -30.320907) (xy 76.562103 -30.236261) (xy 76.681157 -30.158226) (xy 76.804435 -30.087052)
			(xy 76.931542 -30.022965) (xy 77.062071 -29.966173) (xy 77.195605 -29.916856) (xy 77.331714 -29.875173)
			(xy 77.469964 -29.841257) (xy 77.609911 -29.815217) (xy 77.751107 -29.797136) (xy 77.8931 -29.787073)
			(xy 78.035435 -29.785058) (xy 78.177656 -29.7911) (xy 78.319307 -29.805178) (xy 78.459935 -29.827247)
			(xy 78.599089 -29.857237) (xy 78.736324 -29.895052) (xy 78.871199 -29.94057) (xy 79.003283 -29.993646)
			(xy 79.132153 -30.054109) (xy 79.257396 -30.121766) (xy 79.37861 -30.196401) (xy 79.495408 -30.277774)
			(xy 79.607415 -30.365624) (xy 79.714273 -30.459671) (xy 79.815638 -30.559612) (xy 79.911187 -30.665128)
			(xy 80.000614 -30.775881) (xy 80.083632 -30.891515) (xy 80.159974 -31.011662) (xy 80.229397 -31.135934)
			(xy 80.291678 -31.263936) (xy 80.346618 -31.395256) (xy 80.39404 -31.529473) (xy 80.433793 -31.666159)
			(xy 80.465749 -31.804875) (xy 80.489806 -31.945176) (xy 80.505887 -32.086614) (xy 80.51394 -32.228735)
			(xy 80.514444 -32.29991) (xy 80.51394 -32.371085) (xy 80.505887 -32.513206) (xy 80.489806 -32.654644)
			(xy 80.465749 -32.794945) (xy 80.433793 -32.933661) (xy 80.39404 -33.070347) (xy 80.346618 -33.204564)
			(xy 80.291678 -33.335884) (xy 80.229397 -33.463886) (xy 80.159974 -33.588158) (xy 80.083632 -33.708305)
			(xy 80.000614 -33.823939) (xy 79.911187 -33.934692) (xy 79.815638 -34.040208) (xy 79.714273 -34.140149)
			(xy 79.607415 -34.234196) (xy 79.495408 -34.322046) (xy 79.37861 -34.403419) (xy 79.257396 -34.478054)
			(xy 79.132153 -34.545711) (xy 79.003283 -34.606174) (xy 78.871199 -34.65925) (xy 78.736324 -34.704768)
			(xy 78.599089 -34.742583) (xy 78.459935 -34.772573) (xy 78.319307 -34.794642) (xy 78.177656 -34.80872)
			(xy 78.035435 -34.814762) (xy 77.8931 -34.812747) (xy 77.751107 -34.802684) (xy 77.609911 -34.784603)
			(xy 77.469964 -34.758563) (xy 77.331714 -34.724647) (xy 77.195605 -34.682964) (xy 77.062071 -34.633647)
			(xy 76.931542 -34.576855) (xy 76.804435 -34.512768) (xy 76.681157 -34.441594) (xy 76.562103 -34.363559)
			(xy 76.447655 -34.278913) (xy 76.338179 -34.187929) (xy 76.234025 -34.090896) (xy 76.135528 -33.988126)
			(xy 76.043004 -33.879948) (xy 75.956747 -33.766709) (xy 75.877035 -33.648772) (xy 75.804123 -33.526513)
			(xy 75.738245 -33.400326) (xy 75.679611 -33.270613) (xy 75.62841 -33.137791) (xy 75.584805 -33.002285)
			(xy 75.548936 -32.864529) (xy 75.520918 -32.724965) (xy 75.500841 -32.584038) (xy 75.488769 -32.442202)
			(xy 75.484741 -32.29991) (xy 72.995543 -32.29991) (xy 72.99955 -32.50013) (xy 73.011564 -32.70003)
			(xy 73.031567 -32.899288) (xy 73.059526 -33.097587) (xy 73.095397 -33.294609) (xy 73.139121 -33.490037)
			(xy 73.19063 -33.68356) (xy 73.24984 -33.874867) (xy 73.316657 -34.063651) (xy 73.390973 -34.249612)
			(xy 73.47267 -34.43245) (xy 73.561617 -34.611873) (xy 73.657672 -34.787593) (xy 73.76068 -34.95933)
			(xy 73.870476 -35.126808) (xy 73.986886 -35.289759) (xy 74.109722 -35.447921) (xy 74.238787 -35.601043)
			(xy 74.373876 -35.748878) (xy 74.514771 -35.89119) (xy 74.661247 -36.027751) (xy 74.81307 -36.158342)
			(xy 74.969996 -36.282754) (xy 75.131774 -36.400788) (xy 75.298145 -36.512255) (xy 75.468842 -36.616976)
			(xy 75.643593 -36.714784) (xy 75.822117 -36.805521) (xy 76.004129 -36.889044) (xy 76.189336 -36.965217)
			(xy 76.377443 -37.033919) (xy 76.568148 -37.09504) (xy 76.761145 -37.148482) (xy 76.956127 -37.19416)
			(xy 77.152779 -37.232) (xy 77.350789 -37.261941) (xy 77.549837 -37.283937) (xy 77.749606 -37.297951)
			(xy 77.949776 -37.303961) (xy 78.150027 -37.301957) (xy 78.350036 -37.291943) (xy 78.549485 -37.273935)
			(xy 78.748054 -37.247961) (xy 78.945424 -37.214064) (xy 79.141281 -37.172297) (xy 79.335309 -37.122727)
			(xy 79.527199 -37.065434) (xy 79.716642 -37.000509) (xy 79.903337 -36.928057) (xy 80.086983 -36.848193)
			(xy 80.267287 -36.761046) (xy 80.44396 -36.666754) (xy 80.616718 -36.565469) (xy 80.785286 -36.457354)
			(xy 80.949394 -36.342581) (xy 81.108778 -36.221333) (xy 81.263183 -36.093806) (xy 81.412362 -35.960203)
			(xy 81.556077 -35.820739) (xy 81.694096 -35.675637) (xy 81.8262 -35.525128) (xy 81.952176 -35.369455)
			(xy 82.071822 -35.208866) (xy 82.184948 -35.043618) (xy 82.291372 -34.873977) (xy 82.390923 -34.700213)
			(xy 82.483442 -34.522606) (xy 82.568781 -34.341439) (xy 82.646804 -34.157003) (xy 82.717384 -33.969593)
			(xy 82.78041 -33.77951) (xy 82.835781 -33.587056) (xy 82.883407 -33.392542) (xy 82.923212 -33.196277)
			(xy 82.955133 -32.998578) (xy 82.979119 -32.799759) (xy 82.995131 -32.60014) (xy 83.003143 -32.40004)
		)
		(stroke
			(width 0)
			(type solid)
		)
		(fill yes)
		(layer "F.Cu")
		(net "GND")
	)
	(gr_poly
		(pts
			(xy 83.003898 -519.049762) (xy 83.003397 -518.949632) (xy 82.995385 -518.749532) (xy 82.979373 -518.549913)
			(xy 82.955387 -518.351094) (xy 82.923466 -518.153395) (xy 82.883661 -517.95713) (xy 82.836035 -517.762616)
			(xy 82.780664 -517.570162) (xy 82.717638 -517.380079) (xy 82.647058 -517.192669) (xy 82.569035 -517.008233)
			(xy 82.483696 -516.827066) (xy 82.391177 -516.649459) (xy 82.291626 -516.475695) (xy 82.185202 -516.306054)
			(xy 82.072076 -516.140806) (xy 81.95243 -515.980217) (xy 81.826454 -515.824544) (xy 81.69435 -515.674035)
			(xy 81.556331 -515.528933) (xy 81.412616 -515.389469) (xy 81.263437 -515.255866) (xy 81.109032 -515.128339)
			(xy 80.949648 -515.007091) (xy 80.78554 -514.892318) (xy 80.616972 -514.784203) (xy 80.444214 -514.682918)
			(xy 80.267541 -514.588626) (xy 80.087237 -514.501479) (xy 79.903591 -514.421615) (xy 79.716896 -514.349163)
			(xy 79.527453 -514.284238) (xy 79.335563 -514.226945) (xy 79.141535 -514.177375) (xy 78.945678 -514.135608)
			(xy 78.748308 -514.101711) (xy 78.549739 -514.075737) (xy 78.35029 -514.057729) (xy 78.150281 -514.047715)
			(xy 77.95003 -514.045711) (xy 77.74986 -514.051721) (xy 77.550091 -514.065735) (xy 77.351043 -514.087731)
			(xy 77.153033 -514.117672) (xy 76.956381 -514.155512) (xy 76.761399 -514.20119) (xy 76.568402 -514.254632)
			(xy 76.377697 -514.315753) (xy 76.18959 -514.384455) (xy 76.004383 -514.460628) (xy 75.822371 -514.544151)
			(xy 75.643847 -514.634888) (xy 75.469096 -514.732696) (xy 75.298399 -514.837417) (xy 75.132028 -514.948884)
			(xy 74.97025 -515.066918) (xy 74.813324 -515.19133) (xy 74.661501 -515.321921) (xy 74.515025 -515.458482)
			(xy 74.37413 -515.600794) (xy 74.239041 -515.748629) (xy 74.109976 -515.901751) (xy 73.98714 -516.059913)
			(xy 73.87073 -516.222864) (xy 73.760934 -516.390342) (xy 73.657926 -516.562079) (xy 73.561871 -516.737799)
			(xy 73.472924 -516.917222) (xy 73.391227 -517.10006) (xy 73.316911 -517.286021) (xy 73.250094 -517.474805)
			(xy 73.190884 -517.666112) (xy 73.139375 -517.859635) (xy 73.095651 -518.055063) (xy 73.05978 -518.252085)
			(xy 73.031821 -518.450384) (xy 73.011818 -518.649642) (xy 72.999804 -518.849542) (xy 72.995797 -519.049762)
			(xy 75.484995 -519.049762) (xy 75.489023 -518.90747) (xy 75.501095 -518.765634) (xy 75.521172 -518.624707)
			(xy 75.54919 -518.485143) (xy 75.585059 -518.347387) (xy 75.628664 -518.211881) (xy 75.679865 -518.079059)
			(xy 75.738499 -517.949346) (xy 75.804377 -517.823159) (xy 75.877289 -517.7009) (xy 75.957001 -517.582963)
			(xy 76.043258 -517.469724) (xy 76.135782 -517.361546) (xy 76.234279 -517.258776) (xy 76.338433 -517.161743)
			(xy 76.447909 -517.070759) (xy 76.562357 -516.986113) (xy 76.681411 -516.908078) (xy 76.804689 -516.836904)
			(xy 76.931796 -516.772817) (xy 77.062325 -516.716025) (xy 77.195859 -516.666708) (xy 77.331968 -516.625025)
			(xy 77.470218 -516.591109) (xy 77.610165 -516.565069) (xy 77.751361 -516.546988) (xy 77.893354 -516.536925)
			(xy 78.035689 -516.53491) (xy 78.17791 -516.540952) (xy 78.319561 -516.55503) (xy 78.460189 -516.577099)
			(xy 78.599343 -516.607089) (xy 78.736578 -516.644904) (xy 78.871453 -516.690422) (xy 79.003537 -516.743498)
			(xy 79.132407 -516.803961) (xy 79.25765 -516.871618) (xy 79.378864 -516.946253) (xy 79.495662 -517.027626)
			(xy 79.607669 -517.115476) (xy 79.714527 -517.209523) (xy 79.815892 -517.309464) (xy 79.911441 -517.41498)
			(xy 80.000868 -517.525733) (xy 80.083886 -517.641367) (xy 80.160228 -517.761514) (xy 80.229651 -517.885786)
			(xy 80.291932 -518.013788) (xy 80.346872 -518.145108) (xy 80.394294 -518.279325) (xy 80.434047 -518.416011)
			(xy 80.466003 -518.554727) (xy 80.49006 -518.695028) (xy 80.506141 -518.836466) (xy 80.514194 -518.978587)
			(xy 80.514698 -519.049762) (xy 80.514194 -519.120937) (xy 80.506141 -519.263058) (xy 80.49006 -519.404496)
			(xy 80.466003 -519.544797) (xy 80.434047 -519.683513) (xy 80.394294 -519.820199) (xy 80.346872 -519.954416)
			(xy 80.291932 -520.085736) (xy 80.229651 -520.213738) (xy 80.160228 -520.33801) (xy 80.083886 -520.458157)
			(xy 80.000868 -520.573791) (xy 79.911441 -520.684544) (xy 79.815892 -520.79006) (xy 79.714527 -520.890001)
			(xy 79.607669 -520.984048) (xy 79.495662 -521.071898) (xy 79.378864 -521.153271) (xy 79.25765 -521.227906)
			(xy 79.132407 -521.295563) (xy 79.003537 -521.356026) (xy 78.871453 -521.409102) (xy 78.736578 -521.45462)
			(xy 78.599343 -521.492435) (xy 78.460189 -521.522425) (xy 78.319561 -521.544494) (xy 78.17791 -521.558572)
			(xy 78.035689 -521.564614) (xy 77.893354 -521.562599) (xy 77.751361 -521.552536) (xy 77.610165 -521.534455)
			(xy 77.470218 -521.508415) (xy 77.331968 -521.474499) (xy 77.195859 -521.432816) (xy 77.062325 -521.383499)
			(xy 76.931796 -521.326707) (xy 76.804689 -521.26262) (xy 76.681411 -521.191446) (xy 76.562357 -521.113411)
			(xy 76.447909 -521.028765) (xy 76.338433 -520.937781) (xy 76.234279 -520.840748) (xy 76.135782 -520.737978)
			(xy 76.043258 -520.6298) (xy 75.957001 -520.516561) (xy 75.877289 -520.398624) (xy 75.804377 -520.276365)
			(xy 75.738499 -520.150178) (xy 75.679865 -520.020465) (xy 75.628664 -519.887643) (xy 75.585059 -519.752137)
			(xy 75.54919 -519.614381) (xy 75.521172 -519.474817) (xy 75.501095 -519.33389) (xy 75.489023 -519.192054)
			(xy 75.484995 -519.049762) (xy 72.995797 -519.049762) (xy 72.999804 -519.249982) (xy 73.011818 -519.449882)
			(xy 73.031821 -519.64914) (xy 73.05978 -519.847439) (xy 73.095651 -520.044461) (xy 73.139375 -520.239889)
			(xy 73.190884 -520.433412) (xy 73.250094 -520.624719) (xy 73.316911 -520.813503) (xy 73.391227 -520.999464)
			(xy 73.472924 -521.182302) (xy 73.561871 -521.361725) (xy 73.657926 -521.537445) (xy 73.760934 -521.709182)
			(xy 73.87073 -521.87666) (xy 73.98714 -522.039611) (xy 74.109976 -522.197773) (xy 74.239041 -522.350895)
			(xy 74.37413 -522.49873) (xy 74.515025 -522.641042) (xy 74.661501 -522.777603) (xy 74.813324 -522.908194)
			(xy 74.97025 -523.032606) (xy 75.132028 -523.15064) (xy 75.298399 -523.262107) (xy 75.469096 -523.366828)
			(xy 75.643847 -523.464636) (xy 75.822371 -523.555373) (xy 76.004383 -523.638896) (xy 76.18959 -523.715069)
			(xy 76.377697 -523.783771) (xy 76.568402 -523.844892) (xy 76.761399 -523.898334) (xy 76.956381 -523.944012)
			(xy 77.153033 -523.981852) (xy 77.351043 -524.011793) (xy 77.550091 -524.033789) (xy 77.74986 -524.047803)
			(xy 77.95003 -524.053813) (xy 78.150281 -524.051809) (xy 78.35029 -524.041795) (xy 78.549739 -524.023787)
			(xy 78.748308 -523.997813) (xy 78.945678 -523.963916) (xy 79.141535 -523.922149) (xy 79.335563 -523.872579)
			(xy 79.527453 -523.815286) (xy 79.716896 -523.750361) (xy 79.903591 -523.677909) (xy 80.087237 -523.598045)
			(xy 80.267541 -523.510898) (xy 80.444214 -523.416606) (xy 80.616972 -523.315321) (xy 80.78554 -523.207206)
			(xy 80.949648 -523.092433) (xy 81.109032 -522.971185) (xy 81.263437 -522.843658) (xy 81.412616 -522.710055)
			(xy 81.556331 -522.570591) (xy 81.69435 -522.425489) (xy 81.826454 -522.27498) (xy 81.95243 -522.119307)
			(xy 82.072076 -521.958718) (xy 82.185202 -521.79347) (xy 82.291626 -521.623829) (xy 82.391177 -521.450065)
			(xy 82.483696 -521.272458) (xy 82.569035 -521.091291) (xy 82.647058 -520.906855) (xy 82.717638 -520.719445)
			(xy 82.780664 -520.529362) (xy 82.836035 -520.336908) (xy 82.883661 -520.142394) (xy 82.923466 -519.946129)
			(xy 82.955387 -519.74843) (xy 82.979373 -519.549611) (xy 82.995385 -519.349992) (xy 83.003397 -519.149892)
		)
		(stroke
			(width 0)
			(type solid)
		)
		(fill yes)
		(layer "F.Cu")
		(net "GND")
	)
	(gr_poly
		(pts
			(xy 16.599916 -468.69604) (xy 16.499786 -468.696541) (xy 16.299686 -468.704553) (xy 16.100067 -468.720565)
			(xy 15.901248 -468.744551) (xy 15.703549 -468.776472) (xy 15.507284 -468.816277) (xy 15.31277 -468.863903)
			(xy 15.120316 -468.919274) (xy 14.930233 -468.9823) (xy 14.742823 -469.05288) (xy 14.558387 -469.130903)
			(xy 14.37722 -469.216242) (xy 14.199613 -469.308761) (xy 14.025849 -469.408312) (xy 13.856208 -469.514736)
			(xy 13.69096 -469.627862) (xy 13.530371 -469.747508) (xy 13.374698 -469.873484) (xy 13.224189 -470.005588)
			(xy 13.079087 -470.143607) (xy 12.939623 -470.287322) (xy 12.80602 -470.436501) (xy 12.678493 -470.590906)
			(xy 12.557245 -470.75029) (xy 12.442472 -470.914398) (xy 12.334357 -471.082966) (xy 12.233072 -471.255724)
			(xy 12.13878 -471.432397) (xy 12.051633 -471.612701) (xy 11.971769 -471.796347) (xy 11.899317 -471.983042)
			(xy 11.834392 -472.172485) (xy 11.777099 -472.364375) (xy 11.727529 -472.558403) (xy 11.685762 -472.75426)
			(xy 11.651865 -472.95163) (xy 11.625891 -473.150199) (xy 11.607883 -473.349648) (xy 11.597869 -473.549657)
			(xy 11.596722 -473.664249) (xy 14.085064 -473.664249) (xy 14.091106 -473.522028) (xy 14.105184 -473.380377)
			(xy 14.127253 -473.239749) (xy 14.157243 -473.100595) (xy 14.195058 -472.96336) (xy 14.240576 -472.828485)
			(xy 14.293652 -472.696401) (xy 14.354115 -472.567531) (xy 14.421772 -472.442288) (xy 14.496407 -472.321074)
			(xy 14.57778 -472.204276) (xy 14.66563 -472.092269) (xy 14.759677 -471.985411) (xy 14.859618 -471.884046)
			(xy 14.965134 -471.788497) (xy 15.075887 -471.69907) (xy 15.191521 -471.616052) (xy 15.311668 -471.53971)
			(xy 15.43594 -471.470287) (xy 15.563942 -471.408006) (xy 15.695262 -471.353066) (xy 15.829479 -471.305644)
			(xy 15.966165 -471.265891) (xy 16.104881 -471.233935) (xy 16.245182 -471.209878) (xy 16.38662 -471.193797)
			(xy 16.528741 -471.185744) (xy 16.599916 -471.18524) (xy 16.671091 -471.185744) (xy 16.813212 -471.193797)
			(xy 16.95465 -471.209878) (xy 17.094951 -471.233935) (xy 17.233667 -471.265891) (xy 17.370353 -471.305644)
			(xy 17.50457 -471.353066) (xy 17.63589 -471.408006) (xy 17.763892 -471.470287) (xy 17.888164 -471.53971)
			(xy 18.008311 -471.616052) (xy 18.123945 -471.69907) (xy 18.234698 -471.788497) (xy 18.340214 -471.884046)
			(xy 18.440155 -471.985411) (xy 18.534202 -472.092269) (xy 18.622052 -472.204276) (xy 18.703425 -472.321074)
			(xy 18.77806 -472.442288) (xy 18.845717 -472.567531) (xy 18.90618 -472.696401) (xy 18.959256 -472.828485)
			(xy 19.004774 -472.96336) (xy 19.042589 -473.100595) (xy 19.072579 -473.239749) (xy 19.094648 -473.380377)
			(xy 19.108726 -473.522028) (xy 19.114768 -473.664249) (xy 19.112753 -473.806584) (xy 19.10269 -473.948577)
			(xy 19.084609 -474.089773) (xy 19.058569 -474.22972) (xy 19.024653 -474.36797) (xy 18.98297 -474.504079)
			(xy 18.933653 -474.637613) (xy 18.876861 -474.768142) (xy 18.812774 -474.895249) (xy 18.7416 -475.018527)
			(xy 18.663565 -475.137581) (xy 18.578919 -475.252029) (xy 18.487935 -475.361505) (xy 18.390902 -475.465659)
			(xy 18.288132 -475.564156) (xy 18.179954 -475.65668) (xy 18.066715 -475.742937) (xy 17.948778 -475.822649)
			(xy 17.826519 -475.895561) (xy 17.700332 -475.961439) (xy 17.570619 -476.020073) (xy 17.437797 -476.071274)
			(xy 17.302291 -476.114879) (xy 17.164535 -476.150748) (xy 17.024971 -476.178766) (xy 16.884044 -476.198843)
			(xy 16.742208 -476.210915) (xy 16.599916 -476.214944) (xy 16.457624 -476.210915) (xy 16.315788 -476.198843)
			(xy 16.174861 -476.178766) (xy 16.035297 -476.150748) (xy 15.897541 -476.114879) (xy 15.762035 -476.071274)
			(xy 15.629213 -476.020073) (xy 15.4995 -475.961439) (xy 15.373313 -475.895561) (xy 15.251054 -475.822649)
			(xy 15.133117 -475.742937) (xy 15.019878 -475.65668) (xy 14.9117 -475.564156) (xy 14.80893 -475.465659)
			(xy 14.711897 -475.361505) (xy 14.620913 -475.252029) (xy 14.536267 -475.137581) (xy 14.458232 -475.018527)
			(xy 14.387058 -474.895249) (xy 14.322971 -474.768142) (xy 14.266179 -474.637613) (xy 14.216862 -474.504079)
			(xy 14.175179 -474.36797) (xy 14.141263 -474.22972) (xy 14.115223 -474.089773) (xy 14.097142 -473.948577)
			(xy 14.087079 -473.806584) (xy 14.085064 -473.664249) (xy 11.596722 -473.664249) (xy 11.595865 -473.749908)
			(xy 11.601875 -473.950078) (xy 11.615889 -474.149847) (xy 11.637885 -474.348895) (xy 11.667826 -474.546905)
			(xy 11.705666 -474.743557) (xy 11.751344 -474.938539) (xy 11.804786 -475.131536) (xy 11.865907 -475.322241)
			(xy 11.934609 -475.510348) (xy 12.010782 -475.695555) (xy 12.094305 -475.877567) (xy 12.185042 -476.056091)
			(xy 12.28285 -476.230842) (xy 12.387571 -476.401539) (xy 12.499038 -476.56791) (xy 12.617072 -476.729688)
			(xy 12.741484 -476.886614) (xy 12.872075 -477.038437) (xy 13.008636 -477.184913) (xy 13.150948 -477.325808)
			(xy 13.298783 -477.460897) (xy 13.451905 -477.589962) (xy 13.610067 -477.712798) (xy 13.773018 -477.829208)
			(xy 13.940496 -477.939004) (xy 14.112233 -478.042012) (xy 14.287953 -478.138067) (xy 14.467376 -478.227014)
			(xy 14.650214 -478.308711) (xy 14.836175 -478.383027) (xy 15.024959 -478.449844) (xy 15.216266 -478.509054)
			(xy 15.409789 -478.560563) (xy 15.605217 -478.604287) (xy 15.802239 -478.640158) (xy 16.000538 -478.668117)
			(xy 16.199796 -478.68812) (xy 16.399696 -478.700134) (xy 16.599916 -478.704141) (xy 16.800136 -478.700134)
			(xy 17.000036 -478.68812) (xy 17.199294 -478.668117) (xy 17.397593 -478.640158) (xy 17.594615 -478.604287)
			(xy 17.790043 -478.560563) (xy 17.983566 -478.509054) (xy 18.174873 -478.449844) (xy 18.363657 -478.383027)
			(xy 18.549618 -478.308711) (xy 18.732456 -478.227014) (xy 18.911879 -478.138067) (xy 19.087599 -478.042012)
			(xy 19.259336 -477.939004) (xy 19.426814 -477.829208) (xy 19.589765 -477.712798) (xy 19.747927 -477.589962)
			(xy 19.901049 -477.460897) (xy 20.048884 -477.325808) (xy 20.191196 -477.184913) (xy 20.327757 -477.038437)
			(xy 20.458348 -476.886614) (xy 20.58276 -476.729688) (xy 20.700794 -476.56791) (xy 20.812261 -476.401539)
			(xy 20.916982 -476.230842) (xy 21.01479 -476.056091) (xy 21.105527 -475.877567) (xy 21.18905 -475.695555)
			(xy 21.265223 -475.510348) (xy 21.333925 -475.322241) (xy 21.395046 -475.131536) (xy 21.448488 -474.938539)
			(xy 21.494166 -474.743557) (xy 21.532006 -474.546905) (xy 21.561947 -474.348895) (xy 21.583943 -474.149847)
			(xy 21.597957 -473.950078) (xy 21.603967 -473.749908) (xy 21.601963 -473.549657) (xy 21.591949 -473.349648)
			(xy 21.573941 -473.150199) (xy 21.547967 -472.95163) (xy 21.51407 -472.75426) (xy 21.472303 -472.558403)
			(xy 21.422733 -472.364375) (xy 21.36544 -472.172485) (xy 21.300515 -471.983042) (xy 21.228063 -471.796347)
			(xy 21.148199 -471.612701) (xy 21.061052 -471.432397) (xy 20.96676 -471.255724) (xy 20.865475 -471.082966)
			(xy 20.75736 -470.914398) (xy 20.642587 -470.75029) (xy 20.521339 -470.590906) (xy 20.393812 -470.436501)
			(xy 20.260209 -470.287322) (xy 20.120745 -470.143607) (xy 19.975643 -470.005588) (xy 19.825134 -469.873484)
			(xy 19.669461 -469.747508) (xy 19.508872 -469.627862) (xy 19.343624 -469.514736) (xy 19.173983 -469.408312)
			(xy 19.000219 -469.308761) (xy 18.822612 -469.216242) (xy 18.641445 -469.130903) (xy 18.457009 -469.05288)
			(xy 18.269599 -468.9823) (xy 18.079516 -468.919274) (xy 17.887062 -468.863903) (xy 17.692548 -468.816277)
			(xy 17.496283 -468.776472) (xy 17.298584 -468.744551) (xy 17.099765 -468.720565) (xy 16.900146 -468.704553)
			(xy 16.700046 -468.696541)
		)
		(stroke
			(width 0)
			(type solid)
		)
		(fill yes)
		(layer "F.Cu")
		(net "GND")
	)
	(gr_poly
		(pts
			(xy 16.599916 -379.79604) (xy 16.499786 -379.796541) (xy 16.299686 -379.804553) (xy 16.100067 -379.820565)
			(xy 15.901248 -379.844551) (xy 15.703549 -379.876472) (xy 15.507284 -379.916277) (xy 15.31277 -379.963903)
			(xy 15.120316 -380.019274) (xy 14.930233 -380.0823) (xy 14.742823 -380.15288) (xy 14.558387 -380.230903)
			(xy 14.37722 -380.316242) (xy 14.199613 -380.408761) (xy 14.025849 -380.508312) (xy 13.856208 -380.614736)
			(xy 13.69096 -380.727862) (xy 13.530371 -380.847508) (xy 13.374698 -380.973484) (xy 13.224189 -381.105588)
			(xy 13.079087 -381.243607) (xy 12.939623 -381.387322) (xy 12.80602 -381.536501) (xy 12.678493 -381.690906)
			(xy 12.557245 -381.85029) (xy 12.442472 -382.014398) (xy 12.334357 -382.182966) (xy 12.233072 -382.355724)
			(xy 12.13878 -382.532397) (xy 12.051633 -382.712701) (xy 11.971769 -382.896347) (xy 11.899317 -383.083042)
			(xy 11.834392 -383.272485) (xy 11.777099 -383.464375) (xy 11.727529 -383.658403) (xy 11.685762 -383.85426)
			(xy 11.651865 -384.05163) (xy 11.625891 -384.250199) (xy 11.607883 -384.449648) (xy 11.597869 -384.649657)
			(xy 11.596722 -384.764249) (xy 14.085064 -384.764249) (xy 14.091106 -384.622028) (xy 14.105184 -384.480377)
			(xy 14.127253 -384.339749) (xy 14.157243 -384.200595) (xy 14.195058 -384.06336) (xy 14.240576 -383.928485)
			(xy 14.293652 -383.796401) (xy 14.354115 -383.667531) (xy 14.421772 -383.542288) (xy 14.496407 -383.421074)
			(xy 14.57778 -383.304276) (xy 14.66563 -383.192269) (xy 14.759677 -383.085411) (xy 14.859618 -382.984046)
			(xy 14.965134 -382.888497) (xy 15.075887 -382.79907) (xy 15.191521 -382.716052) (xy 15.311668 -382.63971)
			(xy 15.43594 -382.570287) (xy 15.563942 -382.508006) (xy 15.695262 -382.453066) (xy 15.829479 -382.405644)
			(xy 15.966165 -382.365891) (xy 16.104881 -382.333935) (xy 16.245182 -382.309878) (xy 16.38662 -382.293797)
			(xy 16.528741 -382.285744) (xy 16.599916 -382.28524) (xy 16.671091 -382.285744) (xy 16.813212 -382.293797)
			(xy 16.95465 -382.309878) (xy 17.094951 -382.333935) (xy 17.233667 -382.365891) (xy 17.370353 -382.405644)
			(xy 17.50457 -382.453066) (xy 17.63589 -382.508006) (xy 17.763892 -382.570287) (xy 17.888164 -382.63971)
			(xy 18.008311 -382.716052) (xy 18.123945 -382.79907) (xy 18.234698 -382.888497) (xy 18.340214 -382.984046)
			(xy 18.440155 -383.085411) (xy 18.534202 -383.192269) (xy 18.622052 -383.304276) (xy 18.703425 -383.421074)
			(xy 18.77806 -383.542288) (xy 18.845717 -383.667531) (xy 18.90618 -383.796401) (xy 18.959256 -383.928485)
			(xy 19.004774 -384.06336) (xy 19.042589 -384.200595) (xy 19.072579 -384.339749) (xy 19.094648 -384.480377)
			(xy 19.108726 -384.622028) (xy 19.114768 -384.764249) (xy 19.112753 -384.906584) (xy 19.10269 -385.048577)
			(xy 19.084609 -385.189773) (xy 19.058569 -385.32972) (xy 19.024653 -385.46797) (xy 18.98297 -385.604079)
			(xy 18.933653 -385.737613) (xy 18.876861 -385.868142) (xy 18.812774 -385.995249) (xy 18.7416 -386.118527)
			(xy 18.663565 -386.237581) (xy 18.578919 -386.352029) (xy 18.487935 -386.461505) (xy 18.390902 -386.565659)
			(xy 18.288132 -386.664156) (xy 18.179954 -386.75668) (xy 18.066715 -386.842937) (xy 17.948778 -386.922649)
			(xy 17.826519 -386.995561) (xy 17.700332 -387.061439) (xy 17.570619 -387.120073) (xy 17.437797 -387.171274)
			(xy 17.302291 -387.214879) (xy 17.164535 -387.250748) (xy 17.024971 -387.278766) (xy 16.884044 -387.298843)
			(xy 16.742208 -387.310915) (xy 16.599916 -387.314944) (xy 16.457624 -387.310915) (xy 16.315788 -387.298843)
			(xy 16.174861 -387.278766) (xy 16.035297 -387.250748) (xy 15.897541 -387.214879) (xy 15.762035 -387.171274)
			(xy 15.629213 -387.120073) (xy 15.4995 -387.061439) (xy 15.373313 -386.995561) (xy 15.251054 -386.922649)
			(xy 15.133117 -386.842937) (xy 15.019878 -386.75668) (xy 14.9117 -386.664156) (xy 14.80893 -386.565659)
			(xy 14.711897 -386.461505) (xy 14.620913 -386.352029) (xy 14.536267 -386.237581) (xy 14.458232 -386.118527)
			(xy 14.387058 -385.995249) (xy 14.322971 -385.868142) (xy 14.266179 -385.737613) (xy 14.216862 -385.604079)
			(xy 14.175179 -385.46797) (xy 14.141263 -385.32972) (xy 14.115223 -385.189773) (xy 14.097142 -385.048577)
			(xy 14.087079 -384.906584) (xy 14.085064 -384.764249) (xy 11.596722 -384.764249) (xy 11.595865 -384.849908)
			(xy 11.601875 -385.050078) (xy 11.615889 -385.249847) (xy 11.637885 -385.448895) (xy 11.667826 -385.646905)
			(xy 11.705666 -385.843557) (xy 11.751344 -386.038539) (xy 11.804786 -386.231536) (xy 11.865907 -386.422241)
			(xy 11.934609 -386.610348) (xy 12.010782 -386.795555) (xy 12.094305 -386.977567) (xy 12.185042 -387.156091)
			(xy 12.28285 -387.330842) (xy 12.387571 -387.501539) (xy 12.499038 -387.66791) (xy 12.617072 -387.829688)
			(xy 12.741484 -387.986614) (xy 12.872075 -388.138437) (xy 13.008636 -388.284913) (xy 13.150948 -388.425808)
			(xy 13.298783 -388.560897) (xy 13.451905 -388.689962) (xy 13.610067 -388.812798) (xy 13.773018 -388.929208)
			(xy 13.940496 -389.039004) (xy 14.112233 -389.142012) (xy 14.287953 -389.238067) (xy 14.467376 -389.327014)
			(xy 14.650214 -389.408711) (xy 14.836175 -389.483027) (xy 15.024959 -389.549844) (xy 15.216266 -389.609054)
			(xy 15.409789 -389.660563) (xy 15.605217 -389.704287) (xy 15.802239 -389.740158) (xy 16.000538 -389.768117)
			(xy 16.199796 -389.78812) (xy 16.399696 -389.800134) (xy 16.599916 -389.804141) (xy 16.800136 -389.800134)
			(xy 17.000036 -389.78812) (xy 17.199294 -389.768117) (xy 17.397593 -389.740158) (xy 17.594615 -389.704287)
			(xy 17.790043 -389.660563) (xy 17.983566 -389.609054) (xy 18.174873 -389.549844) (xy 18.363657 -389.483027)
			(xy 18.549618 -389.408711) (xy 18.732456 -389.327014) (xy 18.911879 -389.238067) (xy 19.087599 -389.142012)
			(xy 19.259336 -389.039004) (xy 19.426814 -388.929208) (xy 19.589765 -388.812798) (xy 19.747927 -388.689962)
			(xy 19.901049 -388.560897) (xy 20.048884 -388.425808) (xy 20.191196 -388.284913) (xy 20.327757 -388.138437)
			(xy 20.458348 -387.986614) (xy 20.58276 -387.829688) (xy 20.700794 -387.66791) (xy 20.812261 -387.501539)
			(xy 20.916982 -387.330842) (xy 21.01479 -387.156091) (xy 21.105527 -386.977567) (xy 21.18905 -386.795555)
			(xy 21.265223 -386.610348) (xy 21.333925 -386.422241) (xy 21.395046 -386.231536) (xy 21.448488 -386.038539)
			(xy 21.494166 -385.843557) (xy 21.532006 -385.646905) (xy 21.561947 -385.448895) (xy 21.583943 -385.249847)
			(xy 21.597957 -385.050078) (xy 21.603967 -384.849908) (xy 21.601963 -384.649657) (xy 21.591949 -384.449648)
			(xy 21.573941 -384.250199) (xy 21.547967 -384.05163) (xy 21.51407 -383.85426) (xy 21.472303 -383.658403)
			(xy 21.422733 -383.464375) (xy 21.36544 -383.272485) (xy 21.300515 -383.083042) (xy 21.228063 -382.896347)
			(xy 21.148199 -382.712701) (xy 21.061052 -382.532397) (xy 20.96676 -382.355724) (xy 20.865475 -382.182966)
			(xy 20.75736 -382.014398) (xy 20.642587 -381.85029) (xy 20.521339 -381.690906) (xy 20.393812 -381.536501)
			(xy 20.260209 -381.387322) (xy 20.120745 -381.243607) (xy 19.975643 -381.105588) (xy 19.825134 -380.973484)
			(xy 19.669461 -380.847508) (xy 19.508872 -380.727862) (xy 19.343624 -380.614736) (xy 19.173983 -380.508312)
			(xy 19.000219 -380.408761) (xy 18.822612 -380.316242) (xy 18.641445 -380.230903) (xy 18.457009 -380.15288)
			(xy 18.269599 -380.0823) (xy 18.079516 -380.019274) (xy 17.887062 -379.963903) (xy 17.692548 -379.916277)
			(xy 17.496283 -379.876472) (xy 17.298584 -379.844551) (xy 17.099765 -379.820565) (xy 16.900146 -379.804553)
			(xy 16.700046 -379.796541)
		)
		(stroke
			(width 0)
			(type solid)
		)
		(fill yes)
		(layer "F.Cu")
		(net "GND")
	)
	(gr_poly
		(pts
			(xy 16.599916 -290.89604) (xy 16.499786 -290.896541) (xy 16.299686 -290.904553) (xy 16.100067 -290.920565)
			(xy 15.901248 -290.944551) (xy 15.703549 -290.976472) (xy 15.507284 -291.016277) (xy 15.31277 -291.063903)
			(xy 15.120316 -291.119274) (xy 14.930233 -291.1823) (xy 14.742823 -291.25288) (xy 14.558387 -291.330903)
			(xy 14.37722 -291.416242) (xy 14.199613 -291.508761) (xy 14.025849 -291.608312) (xy 13.856208 -291.714736)
			(xy 13.69096 -291.827862) (xy 13.530371 -291.947508) (xy 13.374698 -292.073484) (xy 13.224189 -292.205588)
			(xy 13.079087 -292.343607) (xy 12.939623 -292.487322) (xy 12.80602 -292.636501) (xy 12.678493 -292.790906)
			(xy 12.557245 -292.95029) (xy 12.442472 -293.114398) (xy 12.334357 -293.282966) (xy 12.233072 -293.455724)
			(xy 12.13878 -293.632397) (xy 12.051633 -293.812701) (xy 11.971769 -293.996347) (xy 11.899317 -294.183042)
			(xy 11.834392 -294.372485) (xy 11.777099 -294.564375) (xy 11.727529 -294.758403) (xy 11.685762 -294.95426)
			(xy 11.651865 -295.15163) (xy 11.625891 -295.350199) (xy 11.607883 -295.549648) (xy 11.597869 -295.749657)
			(xy 11.596722 -295.864249) (xy 14.085064 -295.864249) (xy 14.091106 -295.722028) (xy 14.105184 -295.580377)
			(xy 14.127253 -295.439749) (xy 14.157243 -295.300595) (xy 14.195058 -295.16336) (xy 14.240576 -295.028485)
			(xy 14.293652 -294.896401) (xy 14.354115 -294.767531) (xy 14.421772 -294.642288) (xy 14.496407 -294.521074)
			(xy 14.57778 -294.404276) (xy 14.66563 -294.292269) (xy 14.759677 -294.185411) (xy 14.859618 -294.084046)
			(xy 14.965134 -293.988497) (xy 15.075887 -293.89907) (xy 15.191521 -293.816052) (xy 15.311668 -293.73971)
			(xy 15.43594 -293.670287) (xy 15.563942 -293.608006) (xy 15.695262 -293.553066) (xy 15.829479 -293.505644)
			(xy 15.966165 -293.465891) (xy 16.104881 -293.433935) (xy 16.245182 -293.409878) (xy 16.38662 -293.393797)
			(xy 16.528741 -293.385744) (xy 16.599916 -293.38524) (xy 16.671091 -293.385744) (xy 16.813212 -293.393797)
			(xy 16.95465 -293.409878) (xy 17.094951 -293.433935) (xy 17.233667 -293.465891) (xy 17.370353 -293.505644)
			(xy 17.50457 -293.553066) (xy 17.63589 -293.608006) (xy 17.763892 -293.670287) (xy 17.888164 -293.73971)
			(xy 18.008311 -293.816052) (xy 18.123945 -293.89907) (xy 18.234698 -293.988497) (xy 18.340214 -294.084046)
			(xy 18.440155 -294.185411) (xy 18.534202 -294.292269) (xy 18.622052 -294.404276) (xy 18.703425 -294.521074)
			(xy 18.77806 -294.642288) (xy 18.845717 -294.767531) (xy 18.90618 -294.896401) (xy 18.959256 -295.028485)
			(xy 19.004774 -295.16336) (xy 19.042589 -295.300595) (xy 19.072579 -295.439749) (xy 19.094648 -295.580377)
			(xy 19.108726 -295.722028) (xy 19.114768 -295.864249) (xy 19.112753 -296.006584) (xy 19.10269 -296.148577)
			(xy 19.084609 -296.289773) (xy 19.058569 -296.42972) (xy 19.024653 -296.56797) (xy 18.98297 -296.704079)
			(xy 18.933653 -296.837613) (xy 18.876861 -296.968142) (xy 18.812774 -297.095249) (xy 18.7416 -297.218527)
			(xy 18.663565 -297.337581) (xy 18.578919 -297.452029) (xy 18.487935 -297.561505) (xy 18.390902 -297.665659)
			(xy 18.288132 -297.764156) (xy 18.179954 -297.85668) (xy 18.066715 -297.942937) (xy 17.948778 -298.022649)
			(xy 17.826519 -298.095561) (xy 17.700332 -298.161439) (xy 17.570619 -298.220073) (xy 17.437797 -298.271274)
			(xy 17.302291 -298.314879) (xy 17.164535 -298.350748) (xy 17.024971 -298.378766) (xy 16.884044 -298.398843)
			(xy 16.742208 -298.410915) (xy 16.599916 -298.414944) (xy 16.457624 -298.410915) (xy 16.315788 -298.398843)
			(xy 16.174861 -298.378766) (xy 16.035297 -298.350748) (xy 15.897541 -298.314879) (xy 15.762035 -298.271274)
			(xy 15.629213 -298.220073) (xy 15.4995 -298.161439) (xy 15.373313 -298.095561) (xy 15.251054 -298.022649)
			(xy 15.133117 -297.942937) (xy 15.019878 -297.85668) (xy 14.9117 -297.764156) (xy 14.80893 -297.665659)
			(xy 14.711897 -297.561505) (xy 14.620913 -297.452029) (xy 14.536267 -297.337581) (xy 14.458232 -297.218527)
			(xy 14.387058 -297.095249) (xy 14.322971 -296.968142) (xy 14.266179 -296.837613) (xy 14.216862 -296.704079)
			(xy 14.175179 -296.56797) (xy 14.141263 -296.42972) (xy 14.115223 -296.289773) (xy 14.097142 -296.148577)
			(xy 14.087079 -296.006584) (xy 14.085064 -295.864249) (xy 11.596722 -295.864249) (xy 11.595865 -295.949908)
			(xy 11.601875 -296.150078) (xy 11.615889 -296.349847) (xy 11.637885 -296.548895) (xy 11.667826 -296.746905)
			(xy 11.705666 -296.943557) (xy 11.751344 -297.138539) (xy 11.804786 -297.331536) (xy 11.865907 -297.522241)
			(xy 11.934609 -297.710348) (xy 12.010782 -297.895555) (xy 12.094305 -298.077567) (xy 12.185042 -298.256091)
			(xy 12.28285 -298.430842) (xy 12.387571 -298.601539) (xy 12.499038 -298.76791) (xy 12.617072 -298.929688)
			(xy 12.741484 -299.086614) (xy 12.872075 -299.238437) (xy 13.008636 -299.384913) (xy 13.150948 -299.525808)
			(xy 13.298783 -299.660897) (xy 13.451905 -299.789962) (xy 13.610067 -299.912798) (xy 13.773018 -300.029208)
			(xy 13.940496 -300.139004) (xy 14.112233 -300.242012) (xy 14.287953 -300.338067) (xy 14.467376 -300.427014)
			(xy 14.650214 -300.508711) (xy 14.836175 -300.583027) (xy 15.024959 -300.649844) (xy 15.216266 -300.709054)
			(xy 15.409789 -300.760563) (xy 15.605217 -300.804287) (xy 15.802239 -300.840158) (xy 16.000538 -300.868117)
			(xy 16.199796 -300.88812) (xy 16.399696 -300.900134) (xy 16.599916 -300.904141) (xy 16.800136 -300.900134)
			(xy 17.000036 -300.88812) (xy 17.199294 -300.868117) (xy 17.397593 -300.840158) (xy 17.594615 -300.804287)
			(xy 17.790043 -300.760563) (xy 17.983566 -300.709054) (xy 18.174873 -300.649844) (xy 18.363657 -300.583027)
			(xy 18.549618 -300.508711) (xy 18.732456 -300.427014) (xy 18.911879 -300.338067) (xy 19.087599 -300.242012)
			(xy 19.259336 -300.139004) (xy 19.426814 -300.029208) (xy 19.589765 -299.912798) (xy 19.747927 -299.789962)
			(xy 19.901049 -299.660897) (xy 20.048884 -299.525808) (xy 20.191196 -299.384913) (xy 20.327757 -299.238437)
			(xy 20.458348 -299.086614) (xy 20.58276 -298.929688) (xy 20.700794 -298.76791) (xy 20.812261 -298.601539)
			(xy 20.916982 -298.430842) (xy 21.01479 -298.256091) (xy 21.105527 -298.077567) (xy 21.18905 -297.895555)
			(xy 21.265223 -297.710348) (xy 21.333925 -297.522241) (xy 21.395046 -297.331536) (xy 21.448488 -297.138539)
			(xy 21.494166 -296.943557) (xy 21.532006 -296.746905) (xy 21.561947 -296.548895) (xy 21.583943 -296.349847)
			(xy 21.597957 -296.150078) (xy 21.603967 -295.949908) (xy 21.601963 -295.749657) (xy 21.591949 -295.549648)
			(xy 21.573941 -295.350199) (xy 21.547967 -295.15163) (xy 21.51407 -294.95426) (xy 21.472303 -294.758403)
			(xy 21.422733 -294.564375) (xy 21.36544 -294.372485) (xy 21.300515 -294.183042) (xy 21.228063 -293.996347)
			(xy 21.148199 -293.812701) (xy 21.061052 -293.632397) (xy 20.96676 -293.455724) (xy 20.865475 -293.282966)
			(xy 20.75736 -293.114398) (xy 20.642587 -292.95029) (xy 20.521339 -292.790906) (xy 20.393812 -292.636501)
			(xy 20.260209 -292.487322) (xy 20.120745 -292.343607) (xy 19.975643 -292.205588) (xy 19.825134 -292.073484)
			(xy 19.669461 -291.947508) (xy 19.508872 -291.827862) (xy 19.343624 -291.714736) (xy 19.173983 -291.608312)
			(xy 19.000219 -291.508761) (xy 18.822612 -291.416242) (xy 18.641445 -291.330903) (xy 18.457009 -291.25288)
			(xy 18.269599 -291.1823) (xy 18.079516 -291.119274) (xy 17.887062 -291.063903) (xy 17.692548 -291.016277)
			(xy 17.496283 -290.976472) (xy 17.298584 -290.944551) (xy 17.099765 -290.920565) (xy 16.900146 -290.904553)
			(xy 16.700046 -290.896541)
		)
		(stroke
			(width 0)
			(type solid)
		)
		(fill yes)
		(layer "F.Cu")
		(net "GND")
	)
	(gr_poly
		(pts
			(xy 16.599916 -201.99604) (xy 16.499786 -201.996541) (xy 16.299686 -202.004553) (xy 16.100067 -202.020565)
			(xy 15.901248 -202.044551) (xy 15.703549 -202.076472) (xy 15.507284 -202.116277) (xy 15.31277 -202.163903)
			(xy 15.120316 -202.219274) (xy 14.930233 -202.2823) (xy 14.742823 -202.35288) (xy 14.558387 -202.430903)
			(xy 14.37722 -202.516242) (xy 14.199613 -202.608761) (xy 14.025849 -202.708312) (xy 13.856208 -202.814736)
			(xy 13.69096 -202.927862) (xy 13.530371 -203.047508) (xy 13.374698 -203.173484) (xy 13.224189 -203.305588)
			(xy 13.079087 -203.443607) (xy 12.939623 -203.587322) (xy 12.80602 -203.736501) (xy 12.678493 -203.890906)
			(xy 12.557245 -204.05029) (xy 12.442472 -204.214398) (xy 12.334357 -204.382966) (xy 12.233072 -204.555724)
			(xy 12.13878 -204.732397) (xy 12.051633 -204.912701) (xy 11.971769 -205.096347) (xy 11.899317 -205.283042)
			(xy 11.834392 -205.472485) (xy 11.777099 -205.664375) (xy 11.727529 -205.858403) (xy 11.685762 -206.05426)
			(xy 11.651865 -206.25163) (xy 11.625891 -206.450199) (xy 11.607883 -206.649648) (xy 11.597869 -206.849657)
			(xy 11.596722 -206.964249) (xy 14.085064 -206.964249) (xy 14.091106 -206.822028) (xy 14.105184 -206.680377)
			(xy 14.127253 -206.539749) (xy 14.157243 -206.400595) (xy 14.195058 -206.26336) (xy 14.240576 -206.128485)
			(xy 14.293652 -205.996401) (xy 14.354115 -205.867531) (xy 14.421772 -205.742288) (xy 14.496407 -205.621074)
			(xy 14.57778 -205.504276) (xy 14.66563 -205.392269) (xy 14.759677 -205.285411) (xy 14.859618 -205.184046)
			(xy 14.965134 -205.088497) (xy 15.075887 -204.99907) (xy 15.191521 -204.916052) (xy 15.311668 -204.83971)
			(xy 15.43594 -204.770287) (xy 15.563942 -204.708006) (xy 15.695262 -204.653066) (xy 15.829479 -204.605644)
			(xy 15.966165 -204.565891) (xy 16.104881 -204.533935) (xy 16.245182 -204.509878) (xy 16.38662 -204.493797)
			(xy 16.528741 -204.485744) (xy 16.599916 -204.48524) (xy 16.671091 -204.485744) (xy 16.813212 -204.493797)
			(xy 16.95465 -204.509878) (xy 17.094951 -204.533935) (xy 17.233667 -204.565891) (xy 17.370353 -204.605644)
			(xy 17.50457 -204.653066) (xy 17.63589 -204.708006) (xy 17.763892 -204.770287) (xy 17.888164 -204.83971)
			(xy 18.008311 -204.916052) (xy 18.123945 -204.99907) (xy 18.234698 -205.088497) (xy 18.340214 -205.184046)
			(xy 18.440155 -205.285411) (xy 18.534202 -205.392269) (xy 18.622052 -205.504276) (xy 18.703425 -205.621074)
			(xy 18.77806 -205.742288) (xy 18.845717 -205.867531) (xy 18.90618 -205.996401) (xy 18.959256 -206.128485)
			(xy 19.004774 -206.26336) (xy 19.042589 -206.400595) (xy 19.072579 -206.539749) (xy 19.094648 -206.680377)
			(xy 19.108726 -206.822028) (xy 19.114768 -206.964249) (xy 19.112753 -207.106584) (xy 19.10269 -207.248577)
			(xy 19.084609 -207.389773) (xy 19.058569 -207.52972) (xy 19.024653 -207.66797) (xy 18.98297 -207.804079)
			(xy 18.933653 -207.937613) (xy 18.876861 -208.068142) (xy 18.812774 -208.195249) (xy 18.7416 -208.318527)
			(xy 18.663565 -208.437581) (xy 18.578919 -208.552029) (xy 18.487935 -208.661505) (xy 18.390902 -208.765659)
			(xy 18.288132 -208.864156) (xy 18.179954 -208.95668) (xy 18.066715 -209.042937) (xy 17.948778 -209.122649)
			(xy 17.826519 -209.195561) (xy 17.700332 -209.261439) (xy 17.570619 -209.320073) (xy 17.437797 -209.371274)
			(xy 17.302291 -209.414879) (xy 17.164535 -209.450748) (xy 17.024971 -209.478766) (xy 16.884044 -209.498843)
			(xy 16.742208 -209.510915) (xy 16.599916 -209.514944) (xy 16.457624 -209.510915) (xy 16.315788 -209.498843)
			(xy 16.174861 -209.478766) (xy 16.035297 -209.450748) (xy 15.897541 -209.414879) (xy 15.762035 -209.371274)
			(xy 15.629213 -209.320073) (xy 15.4995 -209.261439) (xy 15.373313 -209.195561) (xy 15.251054 -209.122649)
			(xy 15.133117 -209.042937) (xy 15.019878 -208.95668) (xy 14.9117 -208.864156) (xy 14.80893 -208.765659)
			(xy 14.711897 -208.661505) (xy 14.620913 -208.552029) (xy 14.536267 -208.437581) (xy 14.458232 -208.318527)
			(xy 14.387058 -208.195249) (xy 14.322971 -208.068142) (xy 14.266179 -207.937613) (xy 14.216862 -207.804079)
			(xy 14.175179 -207.66797) (xy 14.141263 -207.52972) (xy 14.115223 -207.389773) (xy 14.097142 -207.248577)
			(xy 14.087079 -207.106584) (xy 14.085064 -206.964249) (xy 11.596722 -206.964249) (xy 11.595865 -207.049908)
			(xy 11.601875 -207.250078) (xy 11.615889 -207.449847) (xy 11.637885 -207.648895) (xy 11.667826 -207.846905)
			(xy 11.705666 -208.043557) (xy 11.751344 -208.238539) (xy 11.804786 -208.431536) (xy 11.865907 -208.622241)
			(xy 11.934609 -208.810348) (xy 12.010782 -208.995555) (xy 12.094305 -209.177567) (xy 12.185042 -209.356091)
			(xy 12.28285 -209.530842) (xy 12.387571 -209.701539) (xy 12.499038 -209.86791) (xy 12.617072 -210.029688)
			(xy 12.741484 -210.186614) (xy 12.872075 -210.338437) (xy 13.008636 -210.484913) (xy 13.150948 -210.625808)
			(xy 13.298783 -210.760897) (xy 13.451905 -210.889962) (xy 13.610067 -211.012798) (xy 13.773018 -211.129208)
			(xy 13.940496 -211.239004) (xy 14.112233 -211.342012) (xy 14.287953 -211.438067) (xy 14.467376 -211.527014)
			(xy 14.650214 -211.608711) (xy 14.836175 -211.683027) (xy 15.024959 -211.749844) (xy 15.216266 -211.809054)
			(xy 15.409789 -211.860563) (xy 15.605217 -211.904287) (xy 15.802239 -211.940158) (xy 16.000538 -211.968117)
			(xy 16.199796 -211.98812) (xy 16.399696 -212.000134) (xy 16.599916 -212.004141) (xy 16.800136 -212.000134)
			(xy 17.000036 -211.98812) (xy 17.199294 -211.968117) (xy 17.397593 -211.940158) (xy 17.594615 -211.904287)
			(xy 17.790043 -211.860563) (xy 17.983566 -211.809054) (xy 18.174873 -211.749844) (xy 18.363657 -211.683027)
			(xy 18.549618 -211.608711) (xy 18.732456 -211.527014) (xy 18.911879 -211.438067) (xy 19.087599 -211.342012)
			(xy 19.259336 -211.239004) (xy 19.426814 -211.129208) (xy 19.589765 -211.012798) (xy 19.747927 -210.889962)
			(xy 19.901049 -210.760897) (xy 20.048884 -210.625808) (xy 20.191196 -210.484913) (xy 20.327757 -210.338437)
			(xy 20.458348 -210.186614) (xy 20.58276 -210.029688) (xy 20.700794 -209.86791) (xy 20.812261 -209.701539)
			(xy 20.916982 -209.530842) (xy 21.01479 -209.356091) (xy 21.105527 -209.177567) (xy 21.18905 -208.995555)
			(xy 21.265223 -208.810348) (xy 21.333925 -208.622241) (xy 21.395046 -208.431536) (xy 21.448488 -208.238539)
			(xy 21.494166 -208.043557) (xy 21.532006 -207.846905) (xy 21.561947 -207.648895) (xy 21.583943 -207.449847)
			(xy 21.597957 -207.250078) (xy 21.603967 -207.049908) (xy 21.601963 -206.849657) (xy 21.591949 -206.649648)
			(xy 21.573941 -206.450199) (xy 21.547967 -206.25163) (xy 21.51407 -206.05426) (xy 21.472303 -205.858403)
			(xy 21.422733 -205.664375) (xy 21.36544 -205.472485) (xy 21.300515 -205.283042) (xy 21.228063 -205.096347)
			(xy 21.148199 -204.912701) (xy 21.061052 -204.732397) (xy 20.96676 -204.555724) (xy 20.865475 -204.382966)
			(xy 20.75736 -204.214398) (xy 20.642587 -204.05029) (xy 20.521339 -203.890906) (xy 20.393812 -203.736501)
			(xy 20.260209 -203.587322) (xy 20.120745 -203.443607) (xy 19.975643 -203.305588) (xy 19.825134 -203.173484)
			(xy 19.669461 -203.047508) (xy 19.508872 -202.927862) (xy 19.343624 -202.814736) (xy 19.173983 -202.708312)
			(xy 19.000219 -202.608761) (xy 18.822612 -202.516242) (xy 18.641445 -202.430903) (xy 18.457009 -202.35288)
			(xy 18.269599 -202.2823) (xy 18.079516 -202.219274) (xy 17.887062 -202.163903) (xy 17.692548 -202.116277)
			(xy 17.496283 -202.076472) (xy 17.298584 -202.044551) (xy 17.099765 -202.020565) (xy 16.900146 -202.004553)
			(xy 16.700046 -201.996541)
		)
		(stroke
			(width 0)
			(type solid)
		)
		(fill yes)
		(layer "F.Cu")
		(net "GND")
	)
	(gr_poly
		(pts
			(xy 16.599916 -113.09604) (xy 16.499786 -113.096541) (xy 16.299686 -113.104553) (xy 16.100067 -113.120565)
			(xy 15.901248 -113.144551) (xy 15.703549 -113.176472) (xy 15.507284 -113.216277) (xy 15.31277 -113.263903)
			(xy 15.120316 -113.319274) (xy 14.930233 -113.3823) (xy 14.742823 -113.45288) (xy 14.558387 -113.530903)
			(xy 14.37722 -113.616242) (xy 14.199613 -113.708761) (xy 14.025849 -113.808312) (xy 13.856208 -113.914736)
			(xy 13.69096 -114.027862) (xy 13.530371 -114.147508) (xy 13.374698 -114.273484) (xy 13.224189 -114.405588)
			(xy 13.079087 -114.543607) (xy 12.939623 -114.687322) (xy 12.80602 -114.836501) (xy 12.678493 -114.990906)
			(xy 12.557245 -115.15029) (xy 12.442472 -115.314398) (xy 12.334357 -115.482966) (xy 12.233072 -115.655724)
			(xy 12.13878 -115.832397) (xy 12.051633 -116.012701) (xy 11.971769 -116.196347) (xy 11.899317 -116.383042)
			(xy 11.834392 -116.572485) (xy 11.777099 -116.764375) (xy 11.727529 -116.958403) (xy 11.685762 -117.15426)
			(xy 11.651865 -117.35163) (xy 11.625891 -117.550199) (xy 11.607883 -117.749648) (xy 11.597869 -117.949657)
			(xy 11.596722 -118.064249) (xy 14.085064 -118.064249) (xy 14.091106 -117.922028) (xy 14.105184 -117.780377)
			(xy 14.127253 -117.639749) (xy 14.157243 -117.500595) (xy 14.195058 -117.36336) (xy 14.240576 -117.228485)
			(xy 14.293652 -117.096401) (xy 14.354115 -116.967531) (xy 14.421772 -116.842288) (xy 14.496407 -116.721074)
			(xy 14.57778 -116.604276) (xy 14.66563 -116.492269) (xy 14.759677 -116.385411) (xy 14.859618 -116.284046)
			(xy 14.965134 -116.188497) (xy 15.075887 -116.09907) (xy 15.191521 -116.016052) (xy 15.311668 -115.93971)
			(xy 15.43594 -115.870287) (xy 15.563942 -115.808006) (xy 15.695262 -115.753066) (xy 15.829479 -115.705644)
			(xy 15.966165 -115.665891) (xy 16.104881 -115.633935) (xy 16.245182 -115.609878) (xy 16.38662 -115.593797)
			(xy 16.528741 -115.585744) (xy 16.599916 -115.58524) (xy 16.671091 -115.585744) (xy 16.813212 -115.593797)
			(xy 16.95465 -115.609878) (xy 17.094951 -115.633935) (xy 17.233667 -115.665891) (xy 17.370353 -115.705644)
			(xy 17.50457 -115.753066) (xy 17.63589 -115.808006) (xy 17.763892 -115.870287) (xy 17.888164 -115.93971)
			(xy 18.008311 -116.016052) (xy 18.123945 -116.09907) (xy 18.234698 -116.188497) (xy 18.340214 -116.284046)
			(xy 18.440155 -116.385411) (xy 18.534202 -116.492269) (xy 18.622052 -116.604276) (xy 18.703425 -116.721074)
			(xy 18.77806 -116.842288) (xy 18.845717 -116.967531) (xy 18.90618 -117.096401) (xy 18.959256 -117.228485)
			(xy 19.004774 -117.36336) (xy 19.042589 -117.500595) (xy 19.072579 -117.639749) (xy 19.094648 -117.780377)
			(xy 19.108726 -117.922028) (xy 19.114768 -118.064249) (xy 19.112753 -118.206584) (xy 19.10269 -118.348577)
			(xy 19.084609 -118.489773) (xy 19.058569 -118.62972) (xy 19.024653 -118.76797) (xy 18.98297 -118.904079)
			(xy 18.933653 -119.037613) (xy 18.876861 -119.168142) (xy 18.812774 -119.295249) (xy 18.7416 -119.418527)
			(xy 18.663565 -119.537581) (xy 18.578919 -119.652029) (xy 18.487935 -119.761505) (xy 18.390902 -119.865659)
			(xy 18.288132 -119.964156) (xy 18.179954 -120.05668) (xy 18.066715 -120.142937) (xy 17.948778 -120.222649)
			(xy 17.826519 -120.295561) (xy 17.700332 -120.361439) (xy 17.570619 -120.420073) (xy 17.437797 -120.471274)
			(xy 17.302291 -120.514879) (xy 17.164535 -120.550748) (xy 17.024971 -120.578766) (xy 16.884044 -120.598843)
			(xy 16.742208 -120.610915) (xy 16.599916 -120.614944) (xy 16.457624 -120.610915) (xy 16.315788 -120.598843)
			(xy 16.174861 -120.578766) (xy 16.035297 -120.550748) (xy 15.897541 -120.514879) (xy 15.762035 -120.471274)
			(xy 15.629213 -120.420073) (xy 15.4995 -120.361439) (xy 15.373313 -120.295561) (xy 15.251054 -120.222649)
			(xy 15.133117 -120.142937) (xy 15.019878 -120.05668) (xy 14.9117 -119.964156) (xy 14.80893 -119.865659)
			(xy 14.711897 -119.761505) (xy 14.620913 -119.652029) (xy 14.536267 -119.537581) (xy 14.458232 -119.418527)
			(xy 14.387058 -119.295249) (xy 14.322971 -119.168142) (xy 14.266179 -119.037613) (xy 14.216862 -118.904079)
			(xy 14.175179 -118.76797) (xy 14.141263 -118.62972) (xy 14.115223 -118.489773) (xy 14.097142 -118.348577)
			(xy 14.087079 -118.206584) (xy 14.085064 -118.064249) (xy 11.596722 -118.064249) (xy 11.595865 -118.149908)
			(xy 11.601875 -118.350078) (xy 11.615889 -118.549847) (xy 11.637885 -118.748895) (xy 11.667826 -118.946905)
			(xy 11.705666 -119.143557) (xy 11.751344 -119.338539) (xy 11.804786 -119.531536) (xy 11.865907 -119.722241)
			(xy 11.934609 -119.910348) (xy 12.010782 -120.095555) (xy 12.094305 -120.277567) (xy 12.185042 -120.456091)
			(xy 12.28285 -120.630842) (xy 12.387571 -120.801539) (xy 12.499038 -120.96791) (xy 12.617072 -121.129688)
			(xy 12.741484 -121.286614) (xy 12.872075 -121.438437) (xy 13.008636 -121.584913) (xy 13.150948 -121.725808)
			(xy 13.298783 -121.860897) (xy 13.451905 -121.989962) (xy 13.610067 -122.112798) (xy 13.773018 -122.229208)
			(xy 13.940496 -122.339004) (xy 14.112233 -122.442012) (xy 14.287953 -122.538067) (xy 14.467376 -122.627014)
			(xy 14.650214 -122.708711) (xy 14.836175 -122.783027) (xy 15.024959 -122.849844) (xy 15.216266 -122.909054)
			(xy 15.409789 -122.960563) (xy 15.605217 -123.004287) (xy 15.802239 -123.040158) (xy 16.000538 -123.068117)
			(xy 16.199796 -123.08812) (xy 16.399696 -123.100134) (xy 16.599916 -123.104141) (xy 16.800136 -123.100134)
			(xy 17.000036 -123.08812) (xy 17.199294 -123.068117) (xy 17.397593 -123.040158) (xy 17.594615 -123.004287)
			(xy 17.790043 -122.960563) (xy 17.983566 -122.909054) (xy 18.174873 -122.849844) (xy 18.363657 -122.783027)
			(xy 18.549618 -122.708711) (xy 18.732456 -122.627014) (xy 18.911879 -122.538067) (xy 19.087599 -122.442012)
			(xy 19.259336 -122.339004) (xy 19.426814 -122.229208) (xy 19.589765 -122.112798) (xy 19.747927 -121.989962)
			(xy 19.901049 -121.860897) (xy 20.048884 -121.725808) (xy 20.191196 -121.584913) (xy 20.327757 -121.438437)
			(xy 20.458348 -121.286614) (xy 20.58276 -121.129688) (xy 20.700794 -120.96791) (xy 20.812261 -120.801539)
			(xy 20.916982 -120.630842) (xy 21.01479 -120.456091) (xy 21.105527 -120.277567) (xy 21.18905 -120.095555)
			(xy 21.265223 -119.910348) (xy 21.333925 -119.722241) (xy 21.395046 -119.531536) (xy 21.448488 -119.338539)
			(xy 21.494166 -119.143557) (xy 21.532006 -118.946905) (xy 21.561947 -118.748895) (xy 21.583943 -118.549847)
			(xy 21.597957 -118.350078) (xy 21.603967 -118.149908) (xy 21.601963 -117.949657) (xy 21.591949 -117.749648)
			(xy 21.573941 -117.550199) (xy 21.547967 -117.35163) (xy 21.51407 -117.15426) (xy 21.472303 -116.958403)
			(xy 21.422733 -116.764375) (xy 21.36544 -116.572485) (xy 21.300515 -116.383042) (xy 21.228063 -116.196347)
			(xy 21.148199 -116.012701) (xy 21.061052 -115.832397) (xy 20.96676 -115.655724) (xy 20.865475 -115.482966)
			(xy 20.75736 -115.314398) (xy 20.642587 -115.15029) (xy 20.521339 -114.990906) (xy 20.393812 -114.836501)
			(xy 20.260209 -114.687322) (xy 20.120745 -114.543607) (xy 19.975643 -114.405588) (xy 19.825134 -114.273484)
			(xy 19.669461 -114.147508) (xy 19.508872 -114.027862) (xy 19.343624 -113.914736) (xy 19.173983 -113.808312)
			(xy 19.000219 -113.708761) (xy 18.822612 -113.616242) (xy 18.641445 -113.530903) (xy 18.457009 -113.45288)
			(xy 18.269599 -113.3823) (xy 18.079516 -113.319274) (xy 17.887062 -113.263903) (xy 17.692548 -113.216277)
			(xy 17.496283 -113.176472) (xy 17.298584 -113.144551) (xy 17.099765 -113.120565) (xy 16.900146 -113.104553)
			(xy 16.700046 -113.096541)
		)
		(stroke
			(width 0)
			(type solid)
		)
		(fill yes)
		(layer "F.Cu")
		(net "GND")
	)
	(gr_poly
		(pts
			(xy 16.599916 -24.19604) (xy 16.499786 -24.196541) (xy 16.299686 -24.204553) (xy 16.100067 -24.220565)
			(xy 15.901248 -24.244551) (xy 15.703549 -24.276472) (xy 15.507284 -24.316277) (xy 15.31277 -24.363903)
			(xy 15.120316 -24.419274) (xy 14.930233 -24.4823) (xy 14.742823 -24.55288) (xy 14.558387 -24.630903)
			(xy 14.37722 -24.716242) (xy 14.199613 -24.808761) (xy 14.025849 -24.908312) (xy 13.856208 -25.014736)
			(xy 13.69096 -25.127862) (xy 13.530371 -25.247508) (xy 13.374698 -25.373484) (xy 13.224189 -25.505588)
			(xy 13.079087 -25.643607) (xy 12.939623 -25.787322) (xy 12.80602 -25.936501) (xy 12.678493 -26.090906)
			(xy 12.557245 -26.25029) (xy 12.442472 -26.414398) (xy 12.334357 -26.582966) (xy 12.233072 -26.755724)
			(xy 12.13878 -26.932397) (xy 12.051633 -27.112701) (xy 11.971769 -27.296347) (xy 11.899317 -27.483042)
			(xy 11.834392 -27.672485) (xy 11.777099 -27.864375) (xy 11.727529 -28.058403) (xy 11.685762 -28.25426)
			(xy 11.651865 -28.45163) (xy 11.625891 -28.650199) (xy 11.607883 -28.849648) (xy 11.597869 -29.049657)
			(xy 11.596722 -29.164249) (xy 14.085064 -29.164249) (xy 14.091106 -29.022028) (xy 14.105184 -28.880377)
			(xy 14.127253 -28.739749) (xy 14.157243 -28.600595) (xy 14.195058 -28.46336) (xy 14.240576 -28.328485)
			(xy 14.293652 -28.196401) (xy 14.354115 -28.067531) (xy 14.421772 -27.942288) (xy 14.496407 -27.821074)
			(xy 14.57778 -27.704276) (xy 14.66563 -27.592269) (xy 14.759677 -27.485411) (xy 14.859618 -27.384046)
			(xy 14.965134 -27.288497) (xy 15.075887 -27.19907) (xy 15.191521 -27.116052) (xy 15.311668 -27.03971)
			(xy 15.43594 -26.970287) (xy 15.563942 -26.908006) (xy 15.695262 -26.853066) (xy 15.829479 -26.805644)
			(xy 15.966165 -26.765891) (xy 16.104881 -26.733935) (xy 16.245182 -26.709878) (xy 16.38662 -26.693797)
			(xy 16.528741 -26.685744) (xy 16.599916 -26.68524) (xy 16.671091 -26.685744) (xy 16.813212 -26.693797)
			(xy 16.95465 -26.709878) (xy 17.094951 -26.733935) (xy 17.233667 -26.765891) (xy 17.370353 -26.805644)
			(xy 17.50457 -26.853066) (xy 17.63589 -26.908006) (xy 17.763892 -26.970287) (xy 17.888164 -27.03971)
			(xy 18.008311 -27.116052) (xy 18.123945 -27.19907) (xy 18.234698 -27.288497) (xy 18.340214 -27.384046)
			(xy 18.440155 -27.485411) (xy 18.534202 -27.592269) (xy 18.622052 -27.704276) (xy 18.703425 -27.821074)
			(xy 18.77806 -27.942288) (xy 18.845717 -28.067531) (xy 18.90618 -28.196401) (xy 18.959256 -28.328485)
			(xy 19.004774 -28.46336) (xy 19.042589 -28.600595) (xy 19.072579 -28.739749) (xy 19.094648 -28.880377)
			(xy 19.108726 -29.022028) (xy 19.114768 -29.164249) (xy 19.112753 -29.306584) (xy 19.10269 -29.448577)
			(xy 19.084609 -29.589773) (xy 19.058569 -29.72972) (xy 19.024653 -29.86797) (xy 18.98297 -30.004079)
			(xy 18.933653 -30.137613) (xy 18.876861 -30.268142) (xy 18.812774 -30.395249) (xy 18.7416 -30.518527)
			(xy 18.663565 -30.637581) (xy 18.578919 -30.752029) (xy 18.487935 -30.861505) (xy 18.390902 -30.965659)
			(xy 18.288132 -31.064156) (xy 18.179954 -31.15668) (xy 18.066715 -31.242937) (xy 17.948778 -31.322649)
			(xy 17.826519 -31.395561) (xy 17.700332 -31.461439) (xy 17.570619 -31.520073) (xy 17.437797 -31.571274)
			(xy 17.302291 -31.614879) (xy 17.164535 -31.650748) (xy 17.024971 -31.678766) (xy 16.884044 -31.698843)
			(xy 16.742208 -31.710915) (xy 16.599916 -31.714944) (xy 16.457624 -31.710915) (xy 16.315788 -31.698843)
			(xy 16.174861 -31.678766) (xy 16.035297 -31.650748) (xy 15.897541 -31.614879) (xy 15.762035 -31.571274)
			(xy 15.629213 -31.520073) (xy 15.4995 -31.461439) (xy 15.373313 -31.395561) (xy 15.251054 -31.322649)
			(xy 15.133117 -31.242937) (xy 15.019878 -31.15668) (xy 14.9117 -31.064156) (xy 14.80893 -30.965659)
			(xy 14.711897 -30.861505) (xy 14.620913 -30.752029) (xy 14.536267 -30.637581) (xy 14.458232 -30.518527)
			(xy 14.387058 -30.395249) (xy 14.322971 -30.268142) (xy 14.266179 -30.137613) (xy 14.216862 -30.004079)
			(xy 14.175179 -29.86797) (xy 14.141263 -29.72972) (xy 14.115223 -29.589773) (xy 14.097142 -29.448577)
			(xy 14.087079 -29.306584) (xy 14.085064 -29.164249) (xy 11.596722 -29.164249) (xy 11.595865 -29.249908)
			(xy 11.601875 -29.450078) (xy 11.615889 -29.649847) (xy 11.637885 -29.848895) (xy 11.667826 -30.046905)
			(xy 11.705666 -30.243557) (xy 11.751344 -30.438539) (xy 11.804786 -30.631536) (xy 11.865907 -30.822241)
			(xy 11.934609 -31.010348) (xy 12.010782 -31.195555) (xy 12.094305 -31.377567) (xy 12.185042 -31.556091)
			(xy 12.28285 -31.730842) (xy 12.387571 -31.901539) (xy 12.499038 -32.06791) (xy 12.617072 -32.229688)
			(xy 12.741484 -32.386614) (xy 12.872075 -32.538437) (xy 13.008636 -32.684913) (xy 13.150948 -32.825808)
			(xy 13.298783 -32.960897) (xy 13.451905 -33.089962) (xy 13.610067 -33.212798) (xy 13.773018 -33.329208)
			(xy 13.940496 -33.439004) (xy 14.112233 -33.542012) (xy 14.287953 -33.638067) (xy 14.467376 -33.727014)
			(xy 14.650214 -33.808711) (xy 14.836175 -33.883027) (xy 15.024959 -33.949844) (xy 15.216266 -34.009054)
			(xy 15.409789 -34.060563) (xy 15.605217 -34.104287) (xy 15.802239 -34.140158) (xy 16.000538 -34.168117)
			(xy 16.199796 -34.18812) (xy 16.399696 -34.200134) (xy 16.599916 -34.204141) (xy 16.800136 -34.200134)
			(xy 17.000036 -34.18812) (xy 17.199294 -34.168117) (xy 17.397593 -34.140158) (xy 17.594615 -34.104287)
			(xy 17.790043 -34.060563) (xy 17.983566 -34.009054) (xy 18.174873 -33.949844) (xy 18.363657 -33.883027)
			(xy 18.549618 -33.808711) (xy 18.732456 -33.727014) (xy 18.911879 -33.638067) (xy 19.087599 -33.542012)
			(xy 19.259336 -33.439004) (xy 19.426814 -33.329208) (xy 19.589765 -33.212798) (xy 19.747927 -33.089962)
			(xy 19.901049 -32.960897) (xy 20.048884 -32.825808) (xy 20.191196 -32.684913) (xy 20.327757 -32.538437)
			(xy 20.458348 -32.386614) (xy 20.58276 -32.229688) (xy 20.700794 -32.06791) (xy 20.812261 -31.901539)
			(xy 20.916982 -31.730842) (xy 21.01479 -31.556091) (xy 21.105527 -31.377567) (xy 21.18905 -31.195555)
			(xy 21.265223 -31.010348) (xy 21.333925 -30.822241) (xy 21.395046 -30.631536) (xy 21.448488 -30.438539)
			(xy 21.494166 -30.243557) (xy 21.532006 -30.046905) (xy 21.561947 -29.848895) (xy 21.583943 -29.649847)
			(xy 21.597957 -29.450078) (xy 21.603967 -29.249908) (xy 21.601963 -29.049657) (xy 21.591949 -28.849648)
			(xy 21.573941 -28.650199) (xy 21.547967 -28.45163) (xy 21.51407 -28.25426) (xy 21.472303 -28.058403)
			(xy 21.422733 -27.864375) (xy 21.36544 -27.672485) (xy 21.300515 -27.483042) (xy 21.228063 -27.296347)
			(xy 21.148199 -27.112701) (xy 21.061052 -26.932397) (xy 20.96676 -26.755724) (xy 20.865475 -26.582966)
			(xy 20.75736 -26.414398) (xy 20.642587 -26.25029) (xy 20.521339 -26.090906) (xy 20.393812 -25.936501)
			(xy 20.260209 -25.787322) (xy 20.120745 -25.643607) (xy 19.975643 -25.505588) (xy 19.825134 -25.373484)
			(xy 19.669461 -25.247508) (xy 19.508872 -25.127862) (xy 19.343624 -25.014736) (xy 19.173983 -24.908312)
			(xy 19.000219 -24.808761) (xy 18.822612 -24.716242) (xy 18.641445 -24.630903) (xy 18.457009 -24.55288)
			(xy 18.269599 -24.4823) (xy 18.079516 -24.419274) (xy 17.887062 -24.363903) (xy 17.692548 -24.316277)
			(xy 17.496283 -24.276472) (xy 17.298584 -24.244551) (xy 17.099765 -24.220565) (xy 16.900146 -24.204553)
			(xy 16.700046 -24.196541)
		)
		(stroke
			(width 0)
			(type solid)
		)
		(fill yes)
		(layer "F.Cu")
		(net "GND")
	)
	(gr_poly
		(pts
			(xy 101.000052 -529.49094) (xy 101.055822 -529.490433) (xy 101.167051 -529.482101) (xy 101.277346 -529.46548)
			(xy 101.38609 -529.440662) (xy 101.492675 -529.407788) (xy 101.596506 -529.367039) (xy 101.697001 -529.318645)
			(xy 101.793598 -529.262876) (xy 101.885758 -529.200044) (xy 101.972964 -529.130501) (xy 102.054729 -529.054635)
			(xy 102.130596 -528.97287) (xy 102.20014 -528.885664) (xy 102.262972 -528.793505) (xy 102.318742 -528.696908)
			(xy 102.367136 -528.596413) (xy 102.407885 -528.492583) (xy 102.44076 -528.385998) (xy 102.465578 -528.277253)
			(xy 102.4822 -528.166959) (xy 102.490533 -528.05573) (xy 102.491032 -527.99996) (xy 102.491032 -1.999996)
			(xy 102.490523 -1.944227) (xy 102.482188 -1.833002) (xy 102.465563 -1.72271) (xy 102.440743 -1.613969)
			(xy 102.407866 -1.507387) (xy 102.367116 -1.40356) (xy 102.31872 -1.303069) (xy 102.26295 -1.206475)
			(xy 102.200118 -1.11432) (xy 102.130574 -1.027117) (xy 102.054708 -0.945356) (xy 101.972944 -0.869492)
			(xy 101.885739 -0.799951) (xy 101.793581 -0.737122) (xy 101.696985 -0.681355) (xy 101.596492 -0.632964)
			(xy 101.492664 -0.592217) (xy 101.386081 -0.559343) (xy 101.277339 -0.534527) (xy 101.167047 -0.517907)
			(xy 101.055821 -0.509575) (xy 101.000052 -0.509016) (xy 26.500074 -0.509016) (xy 26.454278 -0.509546)
			(xy 26.363077 -0.517999) (xy 26.273045 -0.534832) (xy 26.184949 -0.559899) (xy 26.099543 -0.592988)
			(xy 26.017554 -0.633817) (xy 25.939682 -0.682036) (xy 25.866592 -0.737234) (xy 25.798906 -0.798941)
			(xy 25.737202 -0.86663) (xy 25.682007 -0.939724) (xy 25.633792 -1.017598) (xy 25.592968 -1.099589)
			(xy 25.559883 -1.184997) (xy 25.53482 -1.273093) (xy 25.517992 -1.363126) (xy 25.509543 -1.454328)
			(xy 25.508966 -1.500124) (xy 25.508966 -2.500122) (xy 25.50847 -2.563238) (xy 25.500544 -2.689221)
			(xy 25.484723 -2.814458) (xy 25.461069 -2.938455) (xy 25.429676 -3.060721) (xy 25.390668 -3.180775)
			(xy 25.344199 -3.298143) (xy 25.290452 -3.412362) (xy 25.229639 -3.52298) (xy 25.162 -3.629561) (xy 25.087803 -3.731685)
			(xy 25.007339 -3.828949) (xy 24.920927 -3.920968) (xy 24.828907 -4.00738) (xy 24.731644 -4.087844)
			(xy 24.62952 -4.162041) (xy 24.522938 -4.22968) (xy 24.41232 -4.290493) (xy 24.298101 -4.34424) (xy 24.180733 -4.390709)
			(xy 24.060679 -4.429717) (xy 23.938413 -4.46111) (xy 23.814416 -4.484763) (xy 23.689179 -4.500584)
			(xy 23.563196 -4.50851) (xy 23.50008 -4.509008) (xy 1.500124 -4.509008) (xy 1.454327 -4.509537) (xy 1.363123 -4.517988)
			(xy 1.273088 -4.534819) (xy 1.18499 -4.559885) (xy 1.099581 -4.592972) (xy 1.017589 -4.6338) (xy 0.939714 -4.682018)
			(xy 0.86662 -4.737216) (xy 0.798931 -4.798923) (xy 0.737224 -4.866612) (xy 0.682026 -4.939706) (xy 0.633808 -5.017581)
			(xy 0.59298 -5.099573) (xy 0.559893 -5.184982) (xy 0.534827 -5.27308) (xy 0.517996 -5.363115) (xy 0.509545 -5.454319)
			(xy 0.509222 -5.482255) (xy 1.01507 -5.482255) (xy 1.021763 -5.417929) (xy 1.036946 -5.355063) (xy 1.06035 -5.294772)
			(xy 1.091558 -5.238126) (xy 1.130019 -5.186131) (xy 1.175048 -5.139708) (xy 1.225848 -5.099682) (xy 1.281516 -5.066762)
			(xy 1.341066 -5.041533) (xy 1.403441 -5.024442) (xy 1.467534 -5.015793) (xy 1.49987 -5.01523) (xy 1.500124 -5.01523)
			(xy 1.500124 -5.015484) (xy 23.266908 -5.015484) (xy 23.266908 -5.01523) (xy 23.50008 -5.01523) (xy 23.570631 -5.014727)
			(xy 23.711511 -5.006802) (xy 23.851725 -4.990991) (xy 23.990832 -4.967345) (xy 24.128395 -4.935937)
			(xy 24.26398 -4.896866) (xy 24.397162 -4.850255) (xy 24.527521 -4.796251) (xy 24.654648 -4.735024)
			(xy 24.778142 -4.666765) (xy 24.897614 -4.591691) (xy 25.01269 -4.510037) (xy 25.123008 -4.422059)
			(xy 25.228219 -4.328035) (xy 25.327994 -4.228261) (xy 25.422018 -4.123049) (xy 25.509995 -4.012732)
			(xy 25.59165 -3.897656) (xy 25.666724 -3.778183) (xy 25.734983 -3.654689) (xy 25.796211 -3.527563)
			(xy 25.850215 -3.397204) (xy 25.896826 -3.264022) (xy 25.935897 -3.128437) (xy 25.967305 -2.990874)
			(xy 25.990951 -2.851767) (xy 26.006762 -2.711553) (xy 26.014687 -2.570673) (xy 26.015188 -2.500122)
			(xy 26.015188 -1.500124) (xy 26.01562 -1.46838) (xy 26.023881 -1.405431) (xy 26.04029 -1.3441) (xy 26.064566 -1.285437)
			(xy 26.096294 -1.230445) (xy 26.13493 -1.180067) (xy 26.179813 -1.135165) (xy 26.230175 -1.096507)
			(xy 26.285154 -1.064756) (xy 26.343807 -1.040455) (xy 26.405131 -1.024021) (xy 26.468076 -1.015734)
			(xy 26.49982 -1.015238) (xy 26.500074 -1.015238) (xy 26.500074 -1.015492) (xy 101.000052 -1.015492)
			(xy 101.045544 -1.016051) (xy 101.13614 -1.024442) (xy 101.225575 -1.041156) (xy 101.313087 -1.066052)
			(xy 101.397928 -1.098916) (xy 101.479375 -1.139468) (xy 101.556732 -1.187362) (xy 101.629341 -1.24219)
			(xy 101.69658 -1.303483) (xy 101.757877 -1.370719) (xy 101.812709 -1.443325) (xy 101.860607 -1.52068)
			(xy 101.901163 -1.602124) (xy 101.934032 -1.686964) (xy 101.958932 -1.774474) (xy 101.975651 -1.863909)
			(xy 101.984046 -1.954504) (xy 101.984556 -1.999996) (xy 101.984556 -486.544366) (xy 101.98481 -486.544366)
			(xy 101.98481 -486.547414) (xy 101.984556 -486.549954) (xy 101.984556 -527.99996) (xy 101.984056 -528.045454)
			(xy 101.975664 -528.136053) (xy 101.958948 -528.225491) (xy 101.93405 -528.313006) (xy 101.901184 -528.397849)
			(xy 101.860628 -528.479298) (xy 101.812731 -528.556657) (xy 101.757899 -528.629267) (xy 101.696601 -528.696507)
			(xy 101.629361 -528.757804) (xy 101.556751 -528.812635) (xy 101.479391 -528.860532) (xy 101.397942 -528.901087)
			(xy 101.313098 -528.933953) (xy 101.225583 -528.95885) (xy 101.136145 -528.975565) (xy 101.045546 -528.983957)
			(xy 101.000052 -528.984464) (xy 26.500074 -528.984464) (xy 26.500074 -528.984718) (xy 26.49982 -528.984718)
			(xy 26.468088 -528.984217) (xy 26.405167 -528.975935) (xy 26.343864 -528.959512) (xy 26.285231 -528.935226)
			(xy 26.230269 -528.903495) (xy 26.179919 -528.864861) (xy 26.135043 -528.819986) (xy 26.096408 -528.769636)
			(xy 26.064676 -528.714675) (xy 26.04039 -528.656041) (xy 26.023966 -528.594739) (xy 26.015683 -528.531818)
			(xy 26.015188 -528.500086) (xy 26.015188 -527.500088) (xy 26.014716 -527.429524) (xy 26.006818 -527.288618)
			(xy 25.991032 -527.148377) (xy 25.967407 -527.009241) (xy 25.936016 -526.871649) (xy 25.89696 -526.736034)
			(xy 25.850361 -526.602822) (xy 25.796365 -526.472433) (xy 25.735143 -526.345277) (xy 25.666887 -526.221754)
			(xy 25.591812 -526.102252) (xy 25.510154 -525.987148) (xy 25.42217 -525.876805) (xy 25.328137 -525.771568)
			(xy 25.278588 -525.721326) (xy 25.228345 -525.671786) (xy 25.123129 -525.577747) (xy 25.012807 -525.489756)
			(xy 24.897725 -525.408088) (xy 24.778244 -525.333002) (xy 24.654742 -525.264732) (xy 24.527607 -525.203494)
			(xy 24.397238 -525.14948) (xy 24.264046 -525.102861) (xy 24.12845 -525.063783) (xy 23.990875 -525.032368)
			(xy 23.851756 -525.008716) (xy 23.71153 -524.992902) (xy 23.570638 -524.984974) (xy 23.50008 -524.984472)
			(xy 1.514856 -524.984472) (xy 1.481877 -524.984932) (xy 1.416287 -524.977997) (xy 1.352242 -524.962233)
			(xy 1.290926 -524.937933) (xy 1.233471 -524.905544) (xy 1.180938 -524.865664) (xy 1.157224 -524.84274)
			(xy 1.135152 -524.81995) (xy 1.096547 -524.769602) (xy 1.064848 -524.714643) (xy 1.040598 -524.656016)
			(xy 1.02421 -524.594724) (xy 1.015968 -524.531817) (xy 1.015492 -524.500094) (xy 1.015492 -5.514594)
			(xy 1.01507 -5.482255) (xy 0.509222 -5.482255) (xy 0.509016 -5.500116) (xy 0.509016 -524.500094)
			(xy 0.509529 -524.54588) (xy 0.517978 -524.637062) (xy 0.534804 -524.727075) (xy 0.559864 -524.815152)
			(xy 0.592944 -524.900541) (xy 0.633761 -524.982513) (xy 0.681968 -525.06037) (xy 0.737153 -525.133446)
			(xy 0.798845 -525.201119) (xy 0.866518 -525.262811) (xy 0.939594 -525.317996) (xy 1.017451 -525.366203)
			(xy 1.099423 -525.40702) (xy 1.184812 -525.4401) (xy 1.272889 -525.46516) (xy 1.362902 -525.481986)
			(xy 1.454084 -525.490435) (xy 1.49987 -525.490948) (xy 23.50008 -525.490948) (xy 23.563202 -525.491433)
			(xy 23.689196 -525.499359) (xy 23.814444 -525.515182) (xy 23.93845 -525.538839) (xy 24.060727 -525.570236)
			(xy 24.180791 -525.60925) (xy 24.298167 -525.655726) (xy 24.412394 -525.709482) (xy 24.523019 -525.770304)
			(xy 24.629607 -525.837954) (xy 24.731736 -525.912163) (xy 24.829004 -525.992639) (xy 24.921025 -526.079064)
			(xy 25.007438 -526.171097) (xy 25.087902 -526.268376) (xy 25.162097 -526.370515) (xy 25.229732 -526.477111)
			(xy 25.29054 -526.587745) (xy 25.34428 -526.701979) (xy 25.390741 -526.819362) (xy 25.429739 -526.93943)
			(xy 25.46112 -527.061711) (xy 25.48476 -527.185721) (xy 25.500566 -527.310971) (xy 25.508475 -527.436966)
			(xy 25.508966 -527.500088) (xy 25.508966 -528.500086) (xy 25.509507 -528.545875) (xy 25.517982 -528.637061)
			(xy 25.534832 -528.727076) (xy 25.559914 -528.815153) (xy 25.593014 -528.90054) (xy 25.633851 -528.98251)
			(xy 25.682074 -529.060363) (xy 25.737274 -529.133435) (xy 25.79898 -529.201104) (xy 25.866665 -529.262792)
			(xy 25.939752 -529.317973) (xy 26.017618 -529.366176) (xy 26.099598 -529.406991) (xy 26.184994 -529.440069)
			(xy 26.273077 -529.465128) (xy 26.363097 -529.481954) (xy 26.454285 -529.490405) (xy 26.500074 -529.49094)
		)
		(stroke
			(width 0)
			(type solid)
		)
		(fill yes)
		(layer "F.Cu")
		(net "GND")
	)
	(gr_poly
		(pts
			(xy 7.438644 -202.378564) (xy 8.008112 -201.809096) (xy 9.609328 -201.809096) (xy 13.27404 -198.144384)
			(xy 20.531582 -198.144384) (xy 21.171408 -197.504558) (xy 21.171408 -184.488582) (xy 16.955262 -180.272436)
			(xy 8.193024 -180.272436) (xy 7.281672 -181.183788) (xy 3.824732 -181.183788) (xy 3.425444 -180.7845)
			(xy 3.408804 -180.768537) (xy 3.370883 -180.742312) (xy 3.328853 -180.723356) (xy 3.284093 -180.712293)
			(xy 3.238072 -180.709485) (xy 3.192299 -180.715023) (xy 3.148276 -180.728727) (xy 3.107447 -180.750147)
			(xy 3.071151 -180.778579) (xy 3.040579 -180.813093) (xy 3.016734 -180.852554) (xy 3.000397 -180.89567)
			(xy 2.992105 -180.941024) (xy 2.991612 -180.964078) (xy 2.991612 -182.09514) (xy 2.592578 -182.494174)
			(xy 2.573782 -182.550816) (xy 2.5781 -182.580534) (xy 2.582604 -182.615389) (xy 2.584809 -182.685637)
			(xy 2.57925 -182.7557) (xy 2.565995 -182.824721) (xy 2.545206 -182.891859) (xy 2.517138 -182.956294)
			(xy 2.482132 -183.017239) (xy 2.440616 -183.07395) (xy 2.393097 -183.125734) (xy 2.340155 -183.17196)
			(xy 2.282436 -183.212063) (xy 2.220646 -183.245553) (xy 2.155538 -183.272022) (xy 2.087907 -183.291146)
			(xy 2.018579 -183.302693) (xy 1.9484 -183.30652) (xy 1.878228 -183.302582) (xy 1.808918 -183.290926)
			(xy 1.741318 -183.271695) (xy 1.676252 -183.245123) (xy 1.645158 -183.228742) (xy 1.625698 -183.218703)
			(xy 1.584205 -183.204724) (xy 1.540931 -183.198064) (xy 1.497155 -183.19892) (xy 1.454174 -183.207267)
			(xy 1.413259 -183.222857) (xy 1.375623 -183.245229) (xy 1.342377 -183.273721) (xy 1.314508 -183.30749)
			(xy 1.292839 -183.345536) (xy 1.278012 -183.386734) (xy 1.270465 -183.429862) (xy 1.27 -183.451754)
			(xy 1.27 -183.706109) (xy 3.31393 -183.706109) (xy 3.31393 -183.634787) (xy 3.321916 -183.563913)
			(xy 3.337786 -183.494378) (xy 3.361343 -183.427058) (xy 3.392288 -183.362799) (xy 3.430234 -183.302408)
			(xy 3.474703 -183.246646) (xy 3.525136 -183.196213) (xy 3.580898 -183.151744) (xy 3.641289 -183.113798)
			(xy 3.705548 -183.082853) (xy 3.772868 -183.059296) (xy 3.842403 -183.043426) (xy 3.913277 -183.03544)
			(xy 3.984599 -183.03544) (xy 4.055473 -183.043426) (xy 4.125008 -183.059296) (xy 4.192328 -183.082853)
			(xy 4.256587 -183.113798) (xy 4.316978 -183.151744) (xy 4.37274 -183.196213) (xy 4.423173 -183.246646)
			(xy 4.467642 -183.302408) (xy 4.505588 -183.362799) (xy 4.536533 -183.427058) (xy 4.56009 -183.494378)
			(xy 4.57596 -183.563913) (xy 4.583946 -183.634787) (xy 4.584446 -183.670448) (xy 4.583946 -183.706109)
			(xy 5.813798 -183.706109) (xy 5.813798 -183.634787) (xy 5.821784 -183.563913) (xy 5.837654 -183.494378)
			(xy 5.861211 -183.427058) (xy 5.892156 -183.362799) (xy 5.930102 -183.302408) (xy 5.974571 -183.246646)
			(xy 6.025004 -183.196213) (xy 6.080766 -183.151744) (xy 6.141157 -183.113798) (xy 6.205416 -183.082853)
			(xy 6.272736 -183.059296) (xy 6.342271 -183.043426) (xy 6.413145 -183.03544) (xy 6.484467 -183.03544)
			(xy 6.555341 -183.043426) (xy 6.624876 -183.059296) (xy 6.692196 -183.082853) (xy 6.756455 -183.113798)
			(xy 6.816846 -183.151744) (xy 6.872608 -183.196213) (xy 6.923041 -183.246646) (xy 6.96751 -183.302408)
			(xy 7.005456 -183.362799) (xy 7.036401 -183.427058) (xy 7.059958 -183.494378) (xy 7.075828 -183.563913)
			(xy 7.083814 -183.634787) (xy 7.084314 -183.670448) (xy 7.083814 -183.706109) (xy 7.075828 -183.776983)
			(xy 7.059958 -183.846518) (xy 7.036401 -183.913838) (xy 7.005456 -183.978097) (xy 6.96751 -184.038488)
			(xy 6.923041 -184.09425) (xy 6.872608 -184.144683) (xy 6.816846 -184.189152) (xy 6.756455 -184.227098)
			(xy 6.692196 -184.258043) (xy 6.624876 -184.2816) (xy 6.555341 -184.29747) (xy 6.484467 -184.305456)
			(xy 6.413145 -184.305456) (xy 6.342271 -184.29747) (xy 6.272736 -184.2816) (xy 6.205416 -184.258043)
			(xy 6.141157 -184.227098) (xy 6.080766 -184.189152) (xy 6.025004 -184.144683) (xy 5.974571 -184.09425)
			(xy 5.930102 -184.038488) (xy 5.892156 -183.978097) (xy 5.861211 -183.913838) (xy 5.837654 -183.846518)
			(xy 5.821784 -183.776983) (xy 5.813798 -183.706109) (xy 4.583946 -183.706109) (xy 4.57596 -183.776983)
			(xy 4.56009 -183.846518) (xy 4.536533 -183.913838) (xy 4.505588 -183.978097) (xy 4.467642 -184.038488)
			(xy 4.423173 -184.09425) (xy 4.37274 -184.144683) (xy 4.316978 -184.189152) (xy 4.256587 -184.227098)
			(xy 4.192328 -184.258043) (xy 4.125008 -184.2816) (xy 4.055473 -184.29747) (xy 3.984599 -184.305456)
			(xy 3.913277 -184.305456) (xy 3.842403 -184.29747) (xy 3.772868 -184.2816) (xy 3.705548 -184.258043)
			(xy 3.641289 -184.227098) (xy 3.580898 -184.189152) (xy 3.525136 -184.144683) (xy 3.474703 -184.09425)
			(xy 3.430234 -184.038488) (xy 3.392288 -183.978097) (xy 3.361343 -183.913838) (xy 3.337786 -183.846518)
			(xy 3.321916 -183.776983) (xy 3.31393 -183.706109) (xy 1.27 -183.706109) (xy 1.27 -183.889142) (xy 1.27045 -183.911045)
			(xy 1.277949 -183.954204) (xy 1.292744 -183.995435) (xy 1.314396 -184.033515) (xy 1.342263 -184.067314)
			(xy 1.375517 -184.095829) (xy 1.413172 -184.118212) (xy 1.45411 -184.133801) (xy 1.497116 -184.142132)
			(xy 1.540913 -184.142957) (xy 1.584203 -184.136254) (xy 1.625699 -184.122219) (xy 1.645158 -184.112154)
			(xy 1.676623 -184.095595) (xy 1.742485 -184.068793) (xy 1.810926 -184.049509) (xy 1.881092 -184.037985)
			(xy 1.952106 -184.034363) (xy 2.02308 -184.038691) (xy 2.093128 -184.050913) (xy 2.161374 -184.070876)
			(xy 2.226966 -184.098332) (xy 2.289083 -184.132938) (xy 2.34695 -184.17426) (xy 2.399843 -184.221782)
			(xy 2.447102 -184.274911) (xy 2.488136 -184.332983) (xy 2.522431 -184.395271) (xy 2.549561 -184.460999)
			(xy 2.569185 -184.529343) (xy 2.581058 -184.599451) (xy 2.585033 -184.670446) (xy 2.583036 -184.706107)
			(xy 7.813794 -184.706107) (xy 7.813794 -184.634785) (xy 7.82178 -184.563911) (xy 7.83765 -184.494376)
			(xy 7.861207 -184.427056) (xy 7.892152 -184.362797) (xy 7.930098 -184.302406) (xy 7.974567 -184.246644)
			(xy 8.025 -184.196211) (xy 8.080762 -184.151742) (xy 8.141153 -184.113796) (xy 8.205412 -184.082851)
			(xy 8.272732 -184.059294) (xy 8.342267 -184.043424) (xy 8.413141 -184.035438) (xy 8.484463 -184.035438)
			(xy 8.555337 -184.043424) (xy 8.624872 -184.059294) (xy 8.692192 -184.082851) (xy 8.756451 -184.113796)
			(xy 8.816842 -184.151742) (xy 8.872604 -184.196211) (xy 8.923037 -184.246644) (xy 8.967506 -184.302406)
			(xy 9.005452 -184.362797) (xy 9.036397 -184.427056) (xy 9.059954 -184.494376) (xy 9.075824 -184.563911)
			(xy 9.08381 -184.634785) (xy 9.08431 -184.670446) (xy 9.08381 -184.706107) (xy 9.075824 -184.776981)
			(xy 9.059954 -184.846516) (xy 9.036397 -184.913836) (xy 9.005452 -184.978095) (xy 8.967506 -185.038486)
			(xy 8.923037 -185.094248) (xy 8.872604 -185.144681) (xy 8.816842 -185.18915) (xy 8.756451 -185.227096)
			(xy 8.692192 -185.258041) (xy 8.624872 -185.281598) (xy 8.555337 -185.297468) (xy 8.484463 -185.305454)
			(xy 8.413141 -185.305454) (xy 8.342267 -185.297468) (xy 8.272732 -185.281598) (xy 8.205412 -185.258041)
			(xy 8.141153 -185.227096) (xy 8.080762 -185.18915) (xy 8.025 -185.144681) (xy 7.974567 -185.094248)
			(xy 7.930098 -185.038486) (xy 7.892152 -184.978095) (xy 7.861207 -184.913836) (xy 7.83765 -184.846516)
			(xy 7.82178 -184.776981) (xy 7.813794 -184.706107) (xy 2.583036 -184.706107) (xy 2.581058 -184.741441)
			(xy 2.569185 -184.811549) (xy 2.549561 -184.879893) (xy 2.522431 -184.945621) (xy 2.488136 -185.007909)
			(xy 2.447102 -185.065981) (xy 2.399843 -185.11911) (xy 2.34695 -185.166632) (xy 2.289083 -185.207954)
			(xy 2.226966 -185.24256) (xy 2.161374 -185.270016) (xy 2.093128 -185.289979) (xy 2.02308 -185.302201)
			(xy 1.952106 -185.306529) (xy 1.881092 -185.302907) (xy 1.810926 -185.291383) (xy 1.742485 -185.272099)
			(xy 1.676623 -185.245297) (xy 1.645158 -185.228738) (xy 1.625698 -185.218699) (xy 1.584205 -185.20472)
			(xy 1.54093 -185.198061) (xy 1.497154 -185.198917) (xy 1.454173 -185.207263) (xy 1.413259 -185.222853)
			(xy 1.375622 -185.245226) (xy 1.342376 -185.273718) (xy 1.314506 -185.307486) (xy 1.292837 -185.345532)
			(xy 1.278009 -185.386729) (xy 1.270462 -185.429858) (xy 1.27 -185.45175) (xy 1.27 -185.706105) (xy 3.31393 -185.706105)
			(xy 3.31393 -185.634783) (xy 3.321916 -185.563909) (xy 3.337786 -185.494374) (xy 3.361343 -185.427054)
			(xy 3.392288 -185.362795) (xy 3.430234 -185.302404) (xy 3.474703 -185.246642) (xy 3.525136 -185.196209)
			(xy 3.580898 -185.15174) (xy 3.641289 -185.113794) (xy 3.705548 -185.082849) (xy 3.772868 -185.059292)
			(xy 3.842403 -185.043422) (xy 3.913277 -185.035436) (xy 3.984599 -185.035436) (xy 4.055473 -185.043422)
			(xy 4.125008 -185.059292) (xy 4.192328 -185.082849) (xy 4.256587 -185.113794) (xy 4.316978 -185.15174)
			(xy 4.37274 -185.196209) (xy 4.423173 -185.246642) (xy 4.467642 -185.302404) (xy 4.505588 -185.362795)
			(xy 4.536533 -185.427054) (xy 4.56009 -185.494374) (xy 4.57596 -185.563909) (xy 4.583946 -185.634783)
			(xy 4.584446 -185.670444) (xy 4.583946 -185.706105) (xy 5.813798 -185.706105) (xy 5.813798 -185.634783)
			(xy 5.821784 -185.563909) (xy 5.837654 -185.494374) (xy 5.861211 -185.427054) (xy 5.892156 -185.362795)
			(xy 5.930102 -185.302404) (xy 5.974571 -185.246642) (xy 6.025004 -185.196209) (xy 6.080766 -185.15174)
			(xy 6.141157 -185.113794) (xy 6.205416 -185.082849) (xy 6.272736 -185.059292) (xy 6.342271 -185.043422)
			(xy 6.413145 -185.035436) (xy 6.484467 -185.035436) (xy 6.555341 -185.043422) (xy 6.624876 -185.059292)
			(xy 6.692196 -185.082849) (xy 6.756455 -185.113794) (xy 6.816846 -185.15174) (xy 6.872608 -185.196209)
			(xy 6.923041 -185.246642) (xy 6.96751 -185.302404) (xy 7.005456 -185.362795) (xy 7.036401 -185.427054)
			(xy 7.059958 -185.494374) (xy 7.075828 -185.563909) (xy 7.083814 -185.634783) (xy 7.084314 -185.670444)
			(xy 7.083814 -185.706105) (xy 7.075828 -185.776979) (xy 7.059958 -185.846514) (xy 7.036401 -185.913834)
			(xy 7.005456 -185.978093) (xy 6.96751 -186.038484) (xy 6.923041 -186.094246) (xy 6.872608 -186.144679)
			(xy 6.816846 -186.189148) (xy 6.756455 -186.227094) (xy 6.692196 -186.258039) (xy 6.624876 -186.281596)
			(xy 6.555341 -186.297466) (xy 6.484467 -186.305452) (xy 6.413145 -186.305452) (xy 6.342271 -186.297466)
			(xy 6.272736 -186.281596) (xy 6.205416 -186.258039) (xy 6.141157 -186.227094) (xy 6.080766 -186.189148)
			(xy 6.025004 -186.144679) (xy 5.974571 -186.094246) (xy 5.930102 -186.038484) (xy 5.892156 -185.978093)
			(xy 5.861211 -185.913834) (xy 5.837654 -185.846514) (xy 5.821784 -185.776979) (xy 5.813798 -185.706105)
			(xy 4.583946 -185.706105) (xy 4.57596 -185.776979) (xy 4.56009 -185.846514) (xy 4.536533 -185.913834)
			(xy 4.505588 -185.978093) (xy 4.467642 -186.038484) (xy 4.423173 -186.094246) (xy 4.37274 -186.144679)
			(xy 4.316978 -186.189148) (xy 4.256587 -186.227094) (xy 4.192328 -186.258039) (xy 4.125008 -186.281596)
			(xy 4.055473 -186.297466) (xy 3.984599 -186.305452) (xy 3.913277 -186.305452) (xy 3.842403 -186.297466)
			(xy 3.772868 -186.281596) (xy 3.705548 -186.258039) (xy 3.641289 -186.227094) (xy 3.580898 -186.189148)
			(xy 3.525136 -186.144679) (xy 3.474703 -186.094246) (xy 3.430234 -186.038484) (xy 3.392288 -185.978093)
			(xy 3.361343 -185.913834) (xy 3.337786 -185.846514) (xy 3.321916 -185.776979) (xy 3.31393 -185.706105)
			(xy 1.27 -185.706105) (xy 1.27 -185.889138) (xy 1.270451 -185.911041) (xy 1.27795 -185.954199) (xy 1.292746 -185.995429)
			(xy 1.314398 -186.033508) (xy 1.342265 -186.067306) (xy 1.375519 -186.09582) (xy 1.413173 -186.118203)
			(xy 1.45411 -186.133791) (xy 1.497116 -186.142122) (xy 1.540912 -186.142947) (xy 1.584201 -186.136244)
			(xy 1.625697 -186.12221) (xy 1.645158 -186.11215) (xy 1.676623 -186.095591) (xy 1.742484 -186.068789)
			(xy 1.810925 -186.049506) (xy 1.881091 -186.037981) (xy 1.952104 -186.03436) (xy 2.023078 -186.038687)
			(xy 2.093126 -186.050909) (xy 2.161371 -186.070873) (xy 2.226963 -186.098329) (xy 2.289079 -186.132934)
			(xy 2.346946 -186.174256) (xy 2.399839 -186.221778) (xy 2.447098 -186.274906) (xy 2.488131 -186.332978)
			(xy 2.522427 -186.395266) (xy 2.549556 -186.460993) (xy 2.56918 -186.529337) (xy 2.581053 -186.599444)
			(xy 2.585028 -186.670439) (xy 2.583032 -186.706103) (xy 7.813794 -186.706103) (xy 7.813794 -186.634781)
			(xy 7.82178 -186.563907) (xy 7.83765 -186.494372) (xy 7.861207 -186.427052) (xy 7.892152 -186.362793)
			(xy 7.930098 -186.302402) (xy 7.974567 -186.24664) (xy 8.025 -186.196207) (xy 8.080762 -186.151738)
			(xy 8.141153 -186.113792) (xy 8.205412 -186.082847) (xy 8.272732 -186.05929) (xy 8.342267 -186.04342)
			(xy 8.413141 -186.035434) (xy 8.484463 -186.035434) (xy 8.555337 -186.04342) (xy 8.624872 -186.05929)
			(xy 8.692192 -186.082847) (xy 8.756451 -186.113792) (xy 8.816842 -186.151738) (xy 8.872604 -186.196207)
			(xy 8.923037 -186.24664) (xy 8.967506 -186.302402) (xy 9.005452 -186.362793) (xy 9.036397 -186.427052)
			(xy 9.059954 -186.494372) (xy 9.075824 -186.563907) (xy 9.08381 -186.634781) (xy 9.08431 -186.670442)
			(xy 9.08381 -186.706103) (xy 9.075824 -186.776977) (xy 9.059954 -186.846512) (xy 9.036397 -186.913832)
			(xy 9.005452 -186.978091) (xy 8.967506 -187.038482) (xy 8.923037 -187.094244) (xy 8.872604 -187.144677)
			(xy 8.816842 -187.189146) (xy 8.756451 -187.227092) (xy 8.692192 -187.258037) (xy 8.624872 -187.281594)
			(xy 8.555337 -187.297464) (xy 8.484463 -187.30545) (xy 8.413141 -187.30545) (xy 8.342267 -187.297464)
			(xy 8.272732 -187.281594) (xy 8.205412 -187.258037) (xy 8.141153 -187.227092) (xy 8.080762 -187.189146)
			(xy 8.025 -187.144677) (xy 7.974567 -187.094244) (xy 7.930098 -187.038482) (xy 7.892152 -186.978091)
			(xy 7.861207 -186.913832) (xy 7.83765 -186.846512) (xy 7.82178 -186.776977) (xy 7.813794 -186.706103)
			(xy 2.583032 -186.706103) (xy 2.581054 -186.741434) (xy 2.56918 -186.811541) (xy 2.549557 -186.879885)
			(xy 2.522428 -186.945612) (xy 2.488132 -187.007901) (xy 2.447099 -187.065972) (xy 2.39984 -187.119101)
			(xy 2.346947 -187.166623) (xy 2.289081 -187.207945) (xy 2.226964 -187.24255) (xy 2.161373 -187.270006)
			(xy 2.093127 -187.28997) (xy 2.02308 -187.302192) (xy 1.952106 -187.30652) (xy 1.881093 -187.302899)
			(xy 1.810927 -187.291375) (xy 1.742486 -187.272091) (xy 1.676625 -187.24529) (xy 1.645158 -187.228734)
			(xy 1.625698 -187.218695) (xy 1.584205 -187.204717) (xy 1.54093 -187.198057) (xy 1.497154 -187.198913)
			(xy 1.454172 -187.20726) (xy 1.413258 -187.22285) (xy 1.375621 -187.245222) (xy 1.342375 -187.273714)
			(xy 1.314505 -187.307483) (xy 1.292835 -187.345528) (xy 1.278006 -187.386725) (xy 1.270459 -187.429854)
			(xy 1.27 -187.451746) (xy 1.27 -187.706101) (xy 3.31393 -187.706101) (xy 3.31393 -187.634779) (xy 3.321916 -187.563905)
			(xy 3.337786 -187.49437) (xy 3.361343 -187.42705) (xy 3.392288 -187.362791) (xy 3.430234 -187.3024)
			(xy 3.474703 -187.246638) (xy 3.525136 -187.196205) (xy 3.580898 -187.151736) (xy 3.641289 -187.11379)
			(xy 3.705548 -187.082845) (xy 3.772868 -187.059288) (xy 3.842403 -187.043418) (xy 3.913277 -187.035432)
			(xy 3.984599 -187.035432) (xy 4.055473 -187.043418) (xy 4.125008 -187.059288) (xy 4.192328 -187.082845)
			(xy 4.256587 -187.11379) (xy 4.316978 -187.151736) (xy 4.37274 -187.196205) (xy 4.423173 -187.246638)
			(xy 4.467642 -187.3024) (xy 4.505588 -187.362791) (xy 4.536533 -187.42705) (xy 4.56009 -187.49437)
			(xy 4.57596 -187.563905) (xy 4.583946 -187.634779) (xy 4.584446 -187.67044) (xy 4.583946 -187.706101)
			(xy 5.813798 -187.706101) (xy 5.813798 -187.634779) (xy 5.821784 -187.563905) (xy 5.837654 -187.49437)
			(xy 5.861211 -187.42705) (xy 5.892156 -187.362791) (xy 5.930102 -187.3024) (xy 5.974571 -187.246638)
			(xy 6.025004 -187.196205) (xy 6.080766 -187.151736) (xy 6.141157 -187.11379) (xy 6.205416 -187.082845)
			(xy 6.272736 -187.059288) (xy 6.342271 -187.043418) (xy 6.413145 -187.035432) (xy 6.484467 -187.035432)
			(xy 6.555341 -187.043418) (xy 6.624876 -187.059288) (xy 6.692196 -187.082845) (xy 6.756455 -187.11379)
			(xy 6.816846 -187.151736) (xy 6.872608 -187.196205) (xy 6.923041 -187.246638) (xy 6.96751 -187.3024)
			(xy 7.005456 -187.362791) (xy 7.036401 -187.42705) (xy 7.059958 -187.49437) (xy 7.075828 -187.563905)
			(xy 7.083814 -187.634779) (xy 7.084314 -187.67044) (xy 7.083814 -187.706101) (xy 7.075828 -187.776975)
			(xy 7.059958 -187.84651) (xy 7.036401 -187.91383) (xy 7.005456 -187.978089) (xy 6.96751 -188.03848)
			(xy 6.923041 -188.094242) (xy 6.872608 -188.144675) (xy 6.816846 -188.189144) (xy 6.756455 -188.22709)
			(xy 6.692196 -188.258035) (xy 6.624876 -188.281592) (xy 6.555341 -188.297462) (xy 6.484467 -188.305448)
			(xy 6.413145 -188.305448) (xy 6.342271 -188.297462) (xy 6.272736 -188.281592) (xy 6.205416 -188.258035)
			(xy 6.141157 -188.22709) (xy 6.080766 -188.189144) (xy 6.025004 -188.144675) (xy 5.974571 -188.094242)
			(xy 5.930102 -188.03848) (xy 5.892156 -187.978089) (xy 5.861211 -187.91383) (xy 5.837654 -187.84651)
			(xy 5.821784 -187.776975) (xy 5.813798 -187.706101) (xy 4.583946 -187.706101) (xy 4.57596 -187.776975)
			(xy 4.56009 -187.84651) (xy 4.536533 -187.91383) (xy 4.505588 -187.978089) (xy 4.467642 -188.03848)
			(xy 4.423173 -188.094242) (xy 4.37274 -188.144675) (xy 4.316978 -188.189144) (xy 4.256587 -188.22709)
			(xy 4.192328 -188.258035) (xy 4.125008 -188.281592) (xy 4.055473 -188.297462) (xy 3.984599 -188.305448)
			(xy 3.913277 -188.305448) (xy 3.842403 -188.297462) (xy 3.772868 -188.281592) (xy 3.705548 -188.258035)
			(xy 3.641289 -188.22709) (xy 3.580898 -188.189144) (xy 3.525136 -188.144675) (xy 3.474703 -188.094242)
			(xy 3.430234 -188.03848) (xy 3.392288 -187.978089) (xy 3.361343 -187.91383) (xy 3.337786 -187.84651)
			(xy 3.321916 -187.776975) (xy 3.31393 -187.706101) (xy 1.27 -187.706101) (xy 1.27 -187.889134) (xy 1.270451 -187.911037)
			(xy 1.277949 -187.954195) (xy 1.292744 -187.995427) (xy 1.314397 -188.033506) (xy 1.342263 -188.067305)
			(xy 1.375517 -188.095819) (xy 1.413172 -188.118202) (xy 1.45411 -188.133791) (xy 1.497116 -188.142122)
			(xy 1.540913 -188.142947) (xy 1.584202 -188.136244) (xy 1.625699 -188.12221) (xy 1.645158 -188.112146)
			(xy 1.676623 -188.095587) (xy 1.742485 -188.068785) (xy 1.810926 -188.049502) (xy 1.881092 -188.037977)
			(xy 1.952106 -188.034357) (xy 2.02308 -188.038684) (xy 2.093128 -188.050906) (xy 2.161374 -188.07087)
			(xy 2.226966 -188.098327) (xy 2.289083 -188.132932) (xy 2.34695 -188.174254) (xy 2.399843 -188.221777)
			(xy 2.447101 -188.274906) (xy 2.488135 -188.332978) (xy 2.522431 -188.395266) (xy 2.54956 -188.460994)
			(xy 2.569184 -188.529338) (xy 2.581057 -188.599446) (xy 2.585031 -188.670441) (xy 2.583035 -188.706099)
			(xy 7.813794 -188.706099) (xy 7.813794 -188.634777) (xy 7.82178 -188.563903) (xy 7.83765 -188.494368)
			(xy 7.861207 -188.427048) (xy 7.892152 -188.362789) (xy 7.930098 -188.302398) (xy 7.974567 -188.246636)
			(xy 8.025 -188.196203) (xy 8.080762 -188.151734) (xy 8.141153 -188.113788) (xy 8.205412 -188.082843)
			(xy 8.272732 -188.059286) (xy 8.342267 -188.043416) (xy 8.413141 -188.03543) (xy 8.484463 -188.03543)
			(xy 8.555337 -188.043416) (xy 8.624872 -188.059286) (xy 8.692192 -188.082843) (xy 8.756451 -188.113788)
			(xy 8.816842 -188.151734) (xy 8.872604 -188.196203) (xy 8.923037 -188.246636) (xy 8.967506 -188.302398)
			(xy 9.005452 -188.362789) (xy 9.036397 -188.427048) (xy 9.059954 -188.494368) (xy 9.075824 -188.563903)
			(xy 9.08381 -188.634777) (xy 9.08431 -188.670438) (xy 9.08381 -188.706099) (xy 9.075824 -188.776973)
			(xy 9.059954 -188.846508) (xy 9.036397 -188.913828) (xy 9.005452 -188.978087) (xy 8.967506 -189.038478)
			(xy 8.923037 -189.09424) (xy 8.872604 -189.144673) (xy 8.816842 -189.189142) (xy 8.756451 -189.227088)
			(xy 8.692192 -189.258033) (xy 8.624872 -189.28159) (xy 8.555337 -189.29746) (xy 8.484463 -189.305446)
			(xy 8.413141 -189.305446) (xy 8.342267 -189.29746) (xy 8.272732 -189.28159) (xy 8.205412 -189.258033)
			(xy 8.141153 -189.227088) (xy 8.080762 -189.189142) (xy 8.025 -189.144673) (xy 7.974567 -189.09424)
			(xy 7.930098 -189.038478) (xy 7.892152 -188.978087) (xy 7.861207 -188.913828) (xy 7.83765 -188.846508)
			(xy 7.82178 -188.776973) (xy 7.813794 -188.706099) (xy 2.583035 -188.706099) (xy 2.581057 -188.741436)
			(xy 2.569183 -188.811544) (xy 2.549559 -188.879888) (xy 2.52243 -188.945615) (xy 2.488134 -189.007904)
			(xy 2.4471 -189.065976) (xy 2.399841 -189.119105) (xy 2.346948 -189.166627) (xy 2.289081 -189.207949)
			(xy 2.226964 -189.242554) (xy 2.161373 -189.27001) (xy 2.093126 -189.289974) (xy 2.023079 -189.302196)
			(xy 1.952104 -189.306523) (xy 1.88109 -189.302902) (xy 1.810924 -189.291378) (xy 1.742483 -189.272094)
			(xy 1.676622 -189.245292) (xy 1.645158 -189.22873) (xy 1.625698 -189.218691) (xy 1.584204 -189.204713)
			(xy 1.540929 -189.198054) (xy 1.497153 -189.19891) (xy 1.454172 -189.207256) (xy 1.413257 -189.222846)
			(xy 1.37562 -189.245218) (xy 1.342374 -189.27371) (xy 1.314503 -189.307479) (xy 1.292833 -189.345524)
			(xy 1.278004 -189.386721) (xy 1.270456 -189.42985) (xy 1.27 -189.451742) (xy 1.27 -189.706097) (xy 3.31393 -189.706097)
			(xy 3.31393 -189.634775) (xy 3.321916 -189.563901) (xy 3.337786 -189.494366) (xy 3.361343 -189.427046)
			(xy 3.392288 -189.362787) (xy 3.430234 -189.302396) (xy 3.474703 -189.246634) (xy 3.525136 -189.196201)
			(xy 3.580898 -189.151732) (xy 3.641289 -189.113786) (xy 3.705548 -189.082841) (xy 3.772868 -189.059284)
			(xy 3.842403 -189.043414) (xy 3.913277 -189.035428) (xy 3.984599 -189.035428) (xy 4.055473 -189.043414)
			(xy 4.125008 -189.059284) (xy 4.192328 -189.082841) (xy 4.256587 -189.113786) (xy 4.316978 -189.151732)
			(xy 4.37274 -189.196201) (xy 4.423173 -189.246634) (xy 4.467642 -189.302396) (xy 4.505588 -189.362787)
			(xy 4.536533 -189.427046) (xy 4.56009 -189.494366) (xy 4.57596 -189.563901) (xy 4.583946 -189.634775)
			(xy 4.584446 -189.670436) (xy 4.583946 -189.706097) (xy 5.813798 -189.706097) (xy 5.813798 -189.634775)
			(xy 5.821784 -189.563901) (xy 5.837654 -189.494366) (xy 5.861211 -189.427046) (xy 5.892156 -189.362787)
			(xy 5.930102 -189.302396) (xy 5.974571 -189.246634) (xy 6.025004 -189.196201) (xy 6.080766 -189.151732)
			(xy 6.141157 -189.113786) (xy 6.205416 -189.082841) (xy 6.272736 -189.059284) (xy 6.342271 -189.043414)
			(xy 6.413145 -189.035428) (xy 6.484467 -189.035428) (xy 6.555341 -189.043414) (xy 6.624876 -189.059284)
			(xy 6.692196 -189.082841) (xy 6.756455 -189.113786) (xy 6.816846 -189.151732) (xy 6.872608 -189.196201)
			(xy 6.923041 -189.246634) (xy 6.96751 -189.302396) (xy 7.005456 -189.362787) (xy 7.036401 -189.427046)
			(xy 7.059958 -189.494366) (xy 7.075828 -189.563901) (xy 7.083814 -189.634775) (xy 7.084314 -189.670436)
			(xy 7.083814 -189.706097) (xy 7.075828 -189.776971) (xy 7.059958 -189.846506) (xy 7.036401 -189.913826)
			(xy 7.005456 -189.978085) (xy 6.96751 -190.038476) (xy 6.923041 -190.094238) (xy 6.872608 -190.144671)
			(xy 6.816846 -190.18914) (xy 6.756455 -190.227086) (xy 6.692196 -190.258031) (xy 6.624876 -190.281588)
			(xy 6.555341 -190.297458) (xy 6.484467 -190.305444) (xy 6.413145 -190.305444) (xy 6.342271 -190.297458)
			(xy 6.272736 -190.281588) (xy 6.205416 -190.258031) (xy 6.141157 -190.227086) (xy 6.080766 -190.18914)
			(xy 6.025004 -190.144671) (xy 5.974571 -190.094238) (xy 5.930102 -190.038476) (xy 5.892156 -189.978085)
			(xy 5.861211 -189.913826) (xy 5.837654 -189.846506) (xy 5.821784 -189.776971) (xy 5.813798 -189.706097)
			(xy 4.583946 -189.706097) (xy 4.57596 -189.776971) (xy 4.56009 -189.846506) (xy 4.536533 -189.913826)
			(xy 4.505588 -189.978085) (xy 4.467642 -190.038476) (xy 4.423173 -190.094238) (xy 4.37274 -190.144671)
			(xy 4.316978 -190.18914) (xy 4.256587 -190.227086) (xy 4.192328 -190.258031) (xy 4.125008 -190.281588)
			(xy 4.055473 -190.297458) (xy 3.984599 -190.305444) (xy 3.913277 -190.305444) (xy 3.842403 -190.297458)
			(xy 3.772868 -190.281588) (xy 3.705548 -190.258031) (xy 3.641289 -190.227086) (xy 3.580898 -190.18914)
			(xy 3.525136 -190.144671) (xy 3.474703 -190.094238) (xy 3.430234 -190.038476) (xy 3.392288 -189.978085)
			(xy 3.361343 -189.913826) (xy 3.337786 -189.846506) (xy 3.321916 -189.776971) (xy 3.31393 -189.706097)
			(xy 1.27 -189.706097) (xy 1.27 -189.88913) (xy 1.27045 -189.911033) (xy 1.277949 -189.954192) (xy 1.292743 -189.995424)
			(xy 1.314395 -190.033505) (xy 1.342262 -190.067304) (xy 1.375516 -190.095818) (xy 1.413171 -190.118202)
			(xy 1.45411 -190.133791) (xy 1.497116 -190.142122) (xy 1.540914 -190.142947) (xy 1.584204 -190.136243)
			(xy 1.6257 -190.122209) (xy 1.645158 -190.112142) (xy 1.676623 -190.095583) (xy 1.742485 -190.068781)
			(xy 1.810926 -190.049497) (xy 1.881092 -190.037973) (xy 1.952106 -190.034351) (xy 2.02308 -190.038679)
			(xy 2.093128 -190.050901) (xy 2.161374 -190.070864) (xy 2.226966 -190.09832) (xy 2.289083 -190.132926)
			(xy 2.34695 -190.174248) (xy 2.399843 -190.22177) (xy 2.447102 -190.274899) (xy 2.488136 -190.332971)
			(xy 2.522431 -190.395259) (xy 2.549561 -190.460987) (xy 2.569185 -190.529331) (xy 2.581058 -190.599439)
			(xy 2.585033 -190.670434) (xy 2.583036 -190.706095) (xy 7.813794 -190.706095) (xy 7.813794 -190.634773)
			(xy 7.82178 -190.563899) (xy 7.83765 -190.494364) (xy 7.861207 -190.427044) (xy 7.892152 -190.362785)
			(xy 7.930098 -190.302394) (xy 7.974567 -190.246632) (xy 8.025 -190.196199) (xy 8.080762 -190.15173)
			(xy 8.141153 -190.113784) (xy 8.205412 -190.082839) (xy 8.272732 -190.059282) (xy 8.342267 -190.043412)
			(xy 8.413141 -190.035426) (xy 8.484463 -190.035426) (xy 8.555337 -190.043412) (xy 8.624872 -190.059282)
			(xy 8.692192 -190.082839) (xy 8.756451 -190.113784) (xy 8.816842 -190.15173) (xy 8.872604 -190.196199)
			(xy 8.923037 -190.246632) (xy 8.967506 -190.302394) (xy 9.005452 -190.362785) (xy 9.036397 -190.427044)
			(xy 9.059954 -190.494364) (xy 9.075824 -190.563899) (xy 9.08381 -190.634773) (xy 9.08431 -190.670434)
			(xy 9.08381 -190.706095) (xy 9.075824 -190.776969) (xy 9.059954 -190.846504) (xy 9.036397 -190.913824)
			(xy 9.005452 -190.978083) (xy 8.967506 -191.038474) (xy 8.923037 -191.094236) (xy 8.872604 -191.144669)
			(xy 8.816842 -191.189138) (xy 8.756451 -191.227084) (xy 8.692192 -191.258029) (xy 8.624872 -191.281586)
			(xy 8.555337 -191.297456) (xy 8.484463 -191.305442) (xy 8.413141 -191.305442) (xy 8.342267 -191.297456)
			(xy 8.272732 -191.281586) (xy 8.205412 -191.258029) (xy 8.141153 -191.227084) (xy 8.080762 -191.189138)
			(xy 8.025 -191.144669) (xy 7.974567 -191.094236) (xy 7.930098 -191.038474) (xy 7.892152 -190.978083)
			(xy 7.861207 -190.913824) (xy 7.83765 -190.846504) (xy 7.82178 -190.776969) (xy 7.813794 -190.706095)
			(xy 2.583036 -190.706095) (xy 2.581058 -190.741429) (xy 2.569185 -190.811537) (xy 2.549561 -190.879881)
			(xy 2.522431 -190.945609) (xy 2.488136 -191.007897) (xy 2.447102 -191.065969) (xy 2.399843 -191.119098)
			(xy 2.34695 -191.16662) (xy 2.289083 -191.207942) (xy 2.226966 -191.242548) (xy 2.161374 -191.270004)
			(xy 2.093128 -191.289967) (xy 2.02308 -191.302189) (xy 1.952106 -191.306517) (xy 1.881092 -191.302895)
			(xy 1.810926 -191.291371) (xy 1.742485 -191.272087) (xy 1.676623 -191.245285) (xy 1.645158 -191.228726)
			(xy 1.625698 -191.218687) (xy 1.584204 -191.204709) (xy 1.540929 -191.19805) (xy 1.497153 -191.198906)
			(xy 1.454171 -191.207253) (xy 1.413256 -191.222843) (xy 1.375619 -191.245215) (xy 1.342372 -191.273707)
			(xy 1.314501 -191.307475) (xy 1.292831 -191.34552) (xy 1.278001 -191.386717) (xy 1.270452 -191.429846)
			(xy 1.27 -191.451738) (xy 1.27 -191.706093) (xy 3.31393 -191.706093) (xy 3.31393 -191.634771) (xy 3.321916 -191.563897)
			(xy 3.337786 -191.494362) (xy 3.361343 -191.427042) (xy 3.392288 -191.362783) (xy 3.430234 -191.302392)
			(xy 3.474703 -191.24663) (xy 3.525136 -191.196197) (xy 3.580898 -191.151728) (xy 3.641289 -191.113782)
			(xy 3.705548 -191.082837) (xy 3.772868 -191.05928) (xy 3.842403 -191.04341) (xy 3.913277 -191.035424)
			(xy 3.984599 -191.035424) (xy 4.055473 -191.04341) (xy 4.125008 -191.05928) (xy 4.192328 -191.082837)
			(xy 4.256587 -191.113782) (xy 4.316978 -191.151728) (xy 4.37274 -191.196197) (xy 4.423173 -191.24663)
			(xy 4.467642 -191.302392) (xy 4.505588 -191.362783) (xy 4.536533 -191.427042) (xy 4.56009 -191.494362)
			(xy 4.57596 -191.563897) (xy 4.583946 -191.634771) (xy 4.584446 -191.670432) (xy 4.583946 -191.706093)
			(xy 5.813798 -191.706093) (xy 5.813798 -191.634771) (xy 5.821784 -191.563897) (xy 5.837654 -191.494362)
			(xy 5.861211 -191.427042) (xy 5.892156 -191.362783) (xy 5.930102 -191.302392) (xy 5.974571 -191.24663)
			(xy 6.025004 -191.196197) (xy 6.080766 -191.151728) (xy 6.141157 -191.113782) (xy 6.205416 -191.082837)
			(xy 6.272736 -191.05928) (xy 6.342271 -191.04341) (xy 6.413145 -191.035424) (xy 6.484467 -191.035424)
			(xy 6.555341 -191.04341) (xy 6.624876 -191.05928) (xy 6.692196 -191.082837) (xy 6.756455 -191.113782)
			(xy 6.816846 -191.151728) (xy 6.872608 -191.196197) (xy 6.923041 -191.24663) (xy 6.96751 -191.302392)
			(xy 7.005456 -191.362783) (xy 7.036401 -191.427042) (xy 7.059958 -191.494362) (xy 7.075828 -191.563897)
			(xy 7.083814 -191.634771) (xy 7.084314 -191.670432) (xy 7.083814 -191.706093) (xy 7.075828 -191.776967)
			(xy 7.059958 -191.846502) (xy 7.036401 -191.913822) (xy 7.005456 -191.978081) (xy 6.96751 -192.038472)
			(xy 6.923041 -192.094234) (xy 6.872608 -192.144667) (xy 6.816846 -192.189136) (xy 6.756455 -192.227082)
			(xy 6.692196 -192.258027) (xy 6.624876 -192.281584) (xy 6.555341 -192.297454) (xy 6.484467 -192.30544)
			(xy 6.413145 -192.30544) (xy 6.342271 -192.297454) (xy 6.272736 -192.281584) (xy 6.205416 -192.258027)
			(xy 6.141157 -192.227082) (xy 6.080766 -192.189136) (xy 6.025004 -192.144667) (xy 5.974571 -192.094234)
			(xy 5.930102 -192.038472) (xy 5.892156 -191.978081) (xy 5.861211 -191.913822) (xy 5.837654 -191.846502)
			(xy 5.821784 -191.776967) (xy 5.813798 -191.706093) (xy 4.583946 -191.706093) (xy 4.57596 -191.776967)
			(xy 4.56009 -191.846502) (xy 4.536533 -191.913822) (xy 4.505588 -191.978081) (xy 4.467642 -192.038472)
			(xy 4.423173 -192.094234) (xy 4.37274 -192.144667) (xy 4.316978 -192.189136) (xy 4.256587 -192.227082)
			(xy 4.192328 -192.258027) (xy 4.125008 -192.281584) (xy 4.055473 -192.297454) (xy 3.984599 -192.30544)
			(xy 3.913277 -192.30544) (xy 3.842403 -192.297454) (xy 3.772868 -192.281584) (xy 3.705548 -192.258027)
			(xy 3.641289 -192.227082) (xy 3.580898 -192.189136) (xy 3.525136 -192.144667) (xy 3.474703 -192.094234)
			(xy 3.430234 -192.038472) (xy 3.392288 -191.978081) (xy 3.361343 -191.913822) (xy 3.337786 -191.846502)
			(xy 3.321916 -191.776967) (xy 3.31393 -191.706093) (xy 1.27 -191.706093) (xy 1.27 -191.889126) (xy 1.270451 -191.911029)
			(xy 1.27795 -191.954187) (xy 1.292745 -191.995418) (xy 1.314397 -192.033497) (xy 1.342264 -192.067296)
			(xy 1.375518 -192.095809) (xy 1.413173 -192.118193) (xy 1.45411 -192.133781) (xy 1.497116 -192.142112)
			(xy 1.540913 -192.142937) (xy 1.584202 -192.136234) (xy 1.625698 -192.1222) (xy 1.645158 -192.112138)
			(xy 1.676623 -192.095579) (xy 1.742485 -192.068777) (xy 1.810926 -192.049494) (xy 1.881092 -192.037969)
			(xy 1.952105 -192.034348) (xy 2.023079 -192.038676) (xy 2.093127 -192.050898) (xy 2.161373 -192.070862)
			(xy 2.226964 -192.098318) (xy 2.289081 -192.132923) (xy 2.346948 -192.174245) (xy 2.399841 -192.221767)
			(xy 2.447099 -192.274896) (xy 2.488133 -192.332968) (xy 2.522429 -192.395256) (xy 2.549558 -192.460983)
			(xy 2.569182 -192.529328) (xy 2.581055 -192.599435) (xy 2.58503 -192.67043) (xy 2.583033 -192.706091)
			(xy 7.813794 -192.706091) (xy 7.813794 -192.634769) (xy 7.82178 -192.563895) (xy 7.83765 -192.49436)
			(xy 7.861207 -192.42704) (xy 7.892152 -192.362781) (xy 7.930098 -192.30239) (xy 7.974567 -192.246628)
			(xy 8.025 -192.196195) (xy 8.080762 -192.151726) (xy 8.141153 -192.11378) (xy 8.205412 -192.082835)
			(xy 8.272732 -192.059278) (xy 8.342267 -192.043408) (xy 8.413141 -192.035422) (xy 8.484463 -192.035422)
			(xy 8.555337 -192.043408) (xy 8.624872 -192.059278) (xy 8.692192 -192.082835) (xy 8.756451 -192.11378)
			(xy 8.816842 -192.151726) (xy 8.872604 -192.196195) (xy 8.923037 -192.246628) (xy 8.967506 -192.30239)
			(xy 9.005452 -192.362781) (xy 9.036397 -192.42704) (xy 9.059954 -192.49436) (xy 9.075824 -192.563895)
			(xy 9.08381 -192.634769) (xy 9.08431 -192.67043) (xy 9.08381 -192.706091) (xy 9.075824 -192.776965)
			(xy 9.059954 -192.8465) (xy 9.036397 -192.91382) (xy 9.005452 -192.978079) (xy 8.967506 -193.03847)
			(xy 8.923037 -193.094232) (xy 8.872604 -193.144665) (xy 8.816842 -193.189134) (xy 8.756451 -193.22708)
			(xy 8.692192 -193.258025) (xy 8.624872 -193.281582) (xy 8.555337 -193.297452) (xy 8.484463 -193.305438)
			(xy 8.413141 -193.305438) (xy 8.342267 -193.297452) (xy 8.272732 -193.281582) (xy 8.205412 -193.258025)
			(xy 8.141153 -193.22708) (xy 8.080762 -193.189134) (xy 8.025 -193.144665) (xy 7.974567 -193.094232)
			(xy 7.930098 -193.03847) (xy 7.892152 -192.978079) (xy 7.861207 -192.91382) (xy 7.83765 -192.8465)
			(xy 7.82178 -192.776965) (xy 7.813794 -192.706091) (xy 2.583033 -192.706091) (xy 2.581055 -192.741425)
			(xy 2.569182 -192.811532) (xy 2.549558 -192.879877) (xy 2.522429 -192.945604) (xy 2.488133 -193.007892)
			(xy 2.447099 -193.065964) (xy 2.399841 -193.119093) (xy 2.346948 -193.166615) (xy 2.289081 -193.207937)
			(xy 2.226964 -193.242542) (xy 2.161373 -193.269998) (xy 2.093127 -193.289962) (xy 2.023079 -193.302184)
			(xy 1.952105 -193.306512) (xy 1.881092 -193.302891) (xy 1.810926 -193.291366) (xy 1.742485 -193.272083)
			(xy 1.676623 -193.245281) (xy 1.645158 -193.228722) (xy 1.625697 -193.218683) (xy 1.584204 -193.204706)
			(xy 1.540929 -193.198046) (xy 1.497152 -193.198903) (xy 1.45417 -193.207249) (xy 1.413255 -193.222839)
			(xy 1.375618 -193.245211) (xy 1.342371 -193.273703) (xy 1.3145 -193.307471) (xy 1.292829 -193.345516)
			(xy 1.277999 -193.386713) (xy 1.270449 -193.429842) (xy 1.27 -193.451734) (xy 1.27 -193.706343) (xy 3.31393 -193.706343)
			(xy 3.31393 -193.635021) (xy 3.321916 -193.564147) (xy 3.337786 -193.494612) (xy 3.361343 -193.427292)
			(xy 3.392288 -193.363033) (xy 3.430234 -193.302642) (xy 3.474703 -193.24688) (xy 3.525136 -193.196447)
			(xy 3.580898 -193.151978) (xy 3.641289 -193.114032) (xy 3.705548 -193.083087) (xy 3.772868 -193.05953)
			(xy 3.842403 -193.04366) (xy 3.913277 -193.035674) (xy 3.984599 -193.035674) (xy 4.055473 -193.04366)
			(xy 4.125008 -193.05953) (xy 4.192328 -193.083087) (xy 4.256587 -193.114032) (xy 4.316978 -193.151978)
			(xy 4.37274 -193.196447) (xy 4.423173 -193.24688) (xy 4.467642 -193.302642) (xy 4.505588 -193.363033)
			(xy 4.536533 -193.427292) (xy 4.56009 -193.494612) (xy 4.57596 -193.564147) (xy 4.583946 -193.635021)
			(xy 4.584446 -193.670682) (xy 4.583946 -193.706343) (xy 5.813798 -193.706343) (xy 5.813798 -193.635021)
			(xy 5.821784 -193.564147) (xy 5.837654 -193.494612) (xy 5.861211 -193.427292) (xy 5.892156 -193.363033)
			(xy 5.930102 -193.302642) (xy 5.974571 -193.24688) (xy 6.025004 -193.196447) (xy 6.080766 -193.151978)
			(xy 6.141157 -193.114032) (xy 6.205416 -193.083087) (xy 6.272736 -193.05953) (xy 6.342271 -193.04366)
			(xy 6.413145 -193.035674) (xy 6.484467 -193.035674) (xy 6.555341 -193.04366) (xy 6.624876 -193.05953)
			(xy 6.692196 -193.083087) (xy 6.756455 -193.114032) (xy 6.816846 -193.151978) (xy 6.872608 -193.196447)
			(xy 6.923041 -193.24688) (xy 6.96751 -193.302642) (xy 7.005456 -193.363033) (xy 7.036401 -193.427292)
			(xy 7.059958 -193.494612) (xy 7.075828 -193.564147) (xy 7.083814 -193.635021) (xy 7.084314 -193.670682)
			(xy 7.083814 -193.706343) (xy 7.075828 -193.777217) (xy 7.059958 -193.846752) (xy 7.036401 -193.914072)
			(xy 7.005456 -193.978331) (xy 6.96751 -194.038722) (xy 6.923041 -194.094484) (xy 6.872608 -194.144917)
			(xy 6.816846 -194.189386) (xy 6.756455 -194.227332) (xy 6.692196 -194.258277) (xy 6.624876 -194.281834)
			(xy 6.555341 -194.297704) (xy 6.484467 -194.30569) (xy 6.413145 -194.30569) (xy 6.342271 -194.297704)
			(xy 6.272736 -194.281834) (xy 6.205416 -194.258277) (xy 6.141157 -194.227332) (xy 6.080766 -194.189386)
			(xy 6.025004 -194.144917) (xy 5.974571 -194.094484) (xy 5.930102 -194.038722) (xy 5.892156 -193.978331)
			(xy 5.861211 -193.914072) (xy 5.837654 -193.846752) (xy 5.821784 -193.777217) (xy 5.813798 -193.706343)
			(xy 4.583946 -193.706343) (xy 4.57596 -193.777217) (xy 4.56009 -193.846752) (xy 4.536533 -193.914072)
			(xy 4.505588 -193.978331) (xy 4.467642 -194.038722) (xy 4.423173 -194.094484) (xy 4.37274 -194.144917)
			(xy 4.316978 -194.189386) (xy 4.256587 -194.227332) (xy 4.192328 -194.258277) (xy 4.125008 -194.281834)
			(xy 4.055473 -194.297704) (xy 3.984599 -194.30569) (xy 3.913277 -194.30569) (xy 3.842403 -194.297704)
			(xy 3.772868 -194.281834) (xy 3.705548 -194.258277) (xy 3.641289 -194.227332) (xy 3.580898 -194.189386)
			(xy 3.525136 -194.144917) (xy 3.474703 -194.094484) (xy 3.430234 -194.038722) (xy 3.392288 -193.978331)
			(xy 3.361343 -193.914072) (xy 3.337786 -193.846752) (xy 3.321916 -193.777217) (xy 3.31393 -193.706343)
			(xy 1.27 -193.706343) (xy 1.27 -193.889122) (xy 1.27045 -193.911025) (xy 1.277949 -193.954184) (xy 1.292744 -193.995415)
			(xy 1.314396 -194.033495) (xy 1.342263 -194.067294) (xy 1.375517 -194.095809) (xy 1.413172 -194.118192)
			(xy 1.45411 -194.133781) (xy 1.497116 -194.142112) (xy 1.540913 -194.142937) (xy 1.584203 -194.136234)
			(xy 1.625699 -194.122199) (xy 1.645158 -194.112134) (xy 1.676623 -194.095575) (xy 1.742485 -194.068773)
			(xy 1.810926 -194.049489) (xy 1.881092 -194.037965) (xy 1.952106 -194.034343) (xy 2.02308 -194.038671)
			(xy 2.093128 -194.050893) (xy 2.161374 -194.070856) (xy 2.226966 -194.098312) (xy 2.289083 -194.132918)
			(xy 2.34695 -194.17424) (xy 2.399843 -194.221762) (xy 2.447102 -194.274891) (xy 2.488136 -194.332963)
			(xy 2.522431 -194.395251) (xy 2.549561 -194.460979) (xy 2.569185 -194.529323) (xy 2.581058 -194.599431)
			(xy 2.585033 -194.670426) (xy 2.583036 -194.706087) (xy 7.813794 -194.706087) (xy 7.813794 -194.634765)
			(xy 7.82178 -194.563891) (xy 7.83765 -194.494356) (xy 7.861207 -194.427036) (xy 7.892152 -194.362777)
			(xy 7.930098 -194.302386) (xy 7.974567 -194.246624) (xy 8.025 -194.196191) (xy 8.080762 -194.151722)
			(xy 8.141153 -194.113776) (xy 8.205412 -194.082831) (xy 8.272732 -194.059274) (xy 8.342267 -194.043404)
			(xy 8.413141 -194.035418) (xy 8.484463 -194.035418) (xy 8.555337 -194.043404) (xy 8.624872 -194.059274)
			(xy 8.692192 -194.082831) (xy 8.756451 -194.113776) (xy 8.816842 -194.151722) (xy 8.872604 -194.196191)
			(xy 8.923037 -194.246624) (xy 8.967506 -194.302386) (xy 9.005452 -194.362777) (xy 9.036397 -194.427036)
			(xy 9.059954 -194.494356) (xy 9.075824 -194.563891) (xy 9.08381 -194.634765) (xy 9.08431 -194.670426)
			(xy 9.08381 -194.706087) (xy 9.075824 -194.776961) (xy 9.059954 -194.846496) (xy 9.036397 -194.913816)
			(xy 9.005452 -194.978075) (xy 8.967506 -195.038466) (xy 8.923037 -195.094228) (xy 8.872604 -195.144661)
			(xy 8.816842 -195.18913) (xy 8.756451 -195.227076) (xy 8.692192 -195.258021) (xy 8.624872 -195.281578)
			(xy 8.555337 -195.297448) (xy 8.484463 -195.305434) (xy 8.413141 -195.305434) (xy 8.342267 -195.297448)
			(xy 8.272732 -195.281578) (xy 8.205412 -195.258021) (xy 8.141153 -195.227076) (xy 8.080762 -195.18913)
			(xy 8.025 -195.144661) (xy 7.974567 -195.094228) (xy 7.930098 -195.038466) (xy 7.892152 -194.978075)
			(xy 7.861207 -194.913816) (xy 7.83765 -194.846496) (xy 7.82178 -194.776961) (xy 7.813794 -194.706087)
			(xy 2.583036 -194.706087) (xy 2.581058 -194.741421) (xy 2.569185 -194.811529) (xy 2.549561 -194.879873)
			(xy 2.522431 -194.945601) (xy 2.488136 -195.007889) (xy 2.447102 -195.065961) (xy 2.399843 -195.11909)
			(xy 2.34695 -195.166612) (xy 2.289083 -195.207934) (xy 2.226966 -195.24254) (xy 2.161374 -195.269996)
			(xy 2.093128 -195.289959) (xy 2.02308 -195.302181) (xy 1.952106 -195.306509) (xy 1.881092 -195.302887)
			(xy 1.810926 -195.291363) (xy 1.742485 -195.272079) (xy 1.676623 -195.245277) (xy 1.645158 -195.228718)
			(xy 1.625697 -195.21868) (xy 1.584204 -195.204702) (xy 1.540928 -195.198043) (xy 1.497152 -195.198899)
			(xy 1.45417 -195.207246) (xy 1.413254 -195.222836) (xy 1.375617 -195.245208) (xy 1.34237 -195.273699)
			(xy 1.314498 -195.307467) (xy 1.292827 -195.345512) (xy 1.277996 -195.386709) (xy 1.270446 -195.429838)
			(xy 1.27 -195.45173) (xy 1.27 -195.706339) (xy 3.31393 -195.706339) (xy 3.31393 -195.635017) (xy 3.321916 -195.564143)
			(xy 3.337786 -195.494608) (xy 3.361343 -195.427288) (xy 3.392288 -195.363029) (xy 3.430234 -195.302638)
			(xy 3.474703 -195.246876) (xy 3.525136 -195.196443) (xy 3.580898 -195.151974) (xy 3.641289 -195.114028)
			(xy 3.705548 -195.083083) (xy 3.772868 -195.059526) (xy 3.842403 -195.043656) (xy 3.913277 -195.03567)
			(xy 3.984599 -195.03567) (xy 4.055473 -195.043656) (xy 4.125008 -195.059526) (xy 4.192328 -195.083083)
			(xy 4.256587 -195.114028) (xy 4.316978 -195.151974) (xy 4.37274 -195.196443) (xy 4.423173 -195.246876)
			(xy 4.467642 -195.302638) (xy 4.505588 -195.363029) (xy 4.536533 -195.427288) (xy 4.56009 -195.494608)
			(xy 4.57596 -195.564143) (xy 4.583946 -195.635017) (xy 4.584446 -195.670678) (xy 4.583946 -195.706339)
			(xy 5.813798 -195.706339) (xy 5.813798 -195.635017) (xy 5.821784 -195.564143) (xy 5.837654 -195.494608)
			(xy 5.861211 -195.427288) (xy 5.892156 -195.363029) (xy 5.930102 -195.302638) (xy 5.974571 -195.246876)
			(xy 6.025004 -195.196443) (xy 6.080766 -195.151974) (xy 6.141157 -195.114028) (xy 6.205416 -195.083083)
			(xy 6.272736 -195.059526) (xy 6.342271 -195.043656) (xy 6.413145 -195.03567) (xy 6.484467 -195.03567)
			(xy 6.555341 -195.043656) (xy 6.624876 -195.059526) (xy 6.692196 -195.083083) (xy 6.756455 -195.114028)
			(xy 6.816846 -195.151974) (xy 6.872608 -195.196443) (xy 6.923041 -195.246876) (xy 6.96751 -195.302638)
			(xy 7.005456 -195.363029) (xy 7.036401 -195.427288) (xy 7.059958 -195.494608) (xy 7.075828 -195.564143)
			(xy 7.083814 -195.635017) (xy 7.084314 -195.670678) (xy 7.083814 -195.706339) (xy 7.075828 -195.777213)
			(xy 7.059958 -195.846748) (xy 7.036401 -195.914068) (xy 7.005456 -195.978327) (xy 6.96751 -196.038718)
			(xy 6.923041 -196.09448) (xy 6.872608 -196.144913) (xy 6.816846 -196.189382) (xy 6.756455 -196.227328)
			(xy 6.692196 -196.258273) (xy 6.624876 -196.28183) (xy 6.555341 -196.2977) (xy 6.484467 -196.305686)
			(xy 6.413145 -196.305686) (xy 6.342271 -196.2977) (xy 6.272736 -196.28183) (xy 6.205416 -196.258273)
			(xy 6.141157 -196.227328) (xy 6.080766 -196.189382) (xy 6.025004 -196.144913) (xy 5.974571 -196.09448)
			(xy 5.930102 -196.038718) (xy 5.892156 -195.978327) (xy 5.861211 -195.914068) (xy 5.837654 -195.846748)
			(xy 5.821784 -195.777213) (xy 5.813798 -195.706339) (xy 4.583946 -195.706339) (xy 4.57596 -195.777213)
			(xy 4.56009 -195.846748) (xy 4.536533 -195.914068) (xy 4.505588 -195.978327) (xy 4.467642 -196.038718)
			(xy 4.423173 -196.09448) (xy 4.37274 -196.144913) (xy 4.316978 -196.189382) (xy 4.256587 -196.227328)
			(xy 4.192328 -196.258273) (xy 4.125008 -196.28183) (xy 4.055473 -196.2977) (xy 3.984599 -196.305686)
			(xy 3.913277 -196.305686) (xy 3.842403 -196.2977) (xy 3.772868 -196.28183) (xy 3.705548 -196.258273)
			(xy 3.641289 -196.227328) (xy 3.580898 -196.189382) (xy 3.525136 -196.144913) (xy 3.474703 -196.09448)
			(xy 3.430234 -196.038718) (xy 3.392288 -195.978327) (xy 3.361343 -195.914068) (xy 3.337786 -195.846748)
			(xy 3.321916 -195.777213) (xy 3.31393 -195.706339) (xy 1.27 -195.706339) (xy 1.27 -195.889118) (xy 1.270451 -195.911021)
			(xy 1.27795 -195.954179) (xy 1.292746 -195.995409) (xy 1.314398 -196.033488) (xy 1.342265 -196.067286)
			(xy 1.375519 -196.0958) (xy 1.413173 -196.118183) (xy 1.45411 -196.133771) (xy 1.497116 -196.142102)
			(xy 1.540912 -196.142927) (xy 1.584201 -196.136224) (xy 1.625697 -196.12219) (xy 1.645158 -196.11213)
			(xy 1.676623 -196.095571) (xy 1.742484 -196.068769) (xy 1.810925 -196.049486) (xy 1.881091 -196.037961)
			(xy 1.952104 -196.03434) (xy 2.023078 -196.038667) (xy 2.093126 -196.050889) (xy 2.161371 -196.070853)
			(xy 2.226963 -196.098309) (xy 2.289079 -196.132914) (xy 2.346946 -196.174236) (xy 2.399839 -196.221758)
			(xy 2.447098 -196.274886) (xy 2.488131 -196.332958) (xy 2.522427 -196.395246) (xy 2.549556 -196.460973)
			(xy 2.56918 -196.529317) (xy 2.581053 -196.599424) (xy 2.585028 -196.670419) (xy 2.583032 -196.706083)
			(xy 7.813794 -196.706083) (xy 7.813794 -196.634761) (xy 7.82178 -196.563887) (xy 7.83765 -196.494352)
			(xy 7.861207 -196.427032) (xy 7.892152 -196.362773) (xy 7.930098 -196.302382) (xy 7.974567 -196.24662)
			(xy 8.025 -196.196187) (xy 8.080762 -196.151718) (xy 8.141153 -196.113772) (xy 8.205412 -196.082827)
			(xy 8.272732 -196.05927) (xy 8.342267 -196.0434) (xy 8.413141 -196.035414) (xy 8.484463 -196.035414)
			(xy 8.555337 -196.0434) (xy 8.624872 -196.05927) (xy 8.692192 -196.082827) (xy 8.756451 -196.113772)
			(xy 8.816842 -196.151718) (xy 8.872604 -196.196187) (xy 8.923037 -196.24662) (xy 8.967506 -196.302382)
			(xy 9.005452 -196.362773) (xy 9.036397 -196.427032) (xy 9.059954 -196.494352) (xy 9.075824 -196.563887)
			(xy 9.08381 -196.634761) (xy 9.08431 -196.670422) (xy 9.08381 -196.706083) (xy 9.075824 -196.776957)
			(xy 9.059954 -196.846492) (xy 9.036397 -196.913812) (xy 9.005452 -196.978071) (xy 8.967506 -197.038462)
			(xy 8.923037 -197.094224) (xy 8.872604 -197.144657) (xy 8.816842 -197.189126) (xy 8.756451 -197.227072)
			(xy 8.692192 -197.258017) (xy 8.624872 -197.281574) (xy 8.555337 -197.297444) (xy 8.484463 -197.30543)
			(xy 8.413141 -197.30543) (xy 8.342267 -197.297444) (xy 8.272732 -197.281574) (xy 8.205412 -197.258017)
			(xy 8.141153 -197.227072) (xy 8.080762 -197.189126) (xy 8.025 -197.144657) (xy 7.974567 -197.094224)
			(xy 7.930098 -197.038462) (xy 7.892152 -196.978071) (xy 7.861207 -196.913812) (xy 7.83765 -196.846492)
			(xy 7.82178 -196.776957) (xy 7.813794 -196.706083) (xy 2.583032 -196.706083) (xy 2.581054 -196.741414)
			(xy 2.56918 -196.811521) (xy 2.549557 -196.879865) (xy 2.522428 -196.945592) (xy 2.488132 -197.007881)
			(xy 2.447099 -197.065952) (xy 2.39984 -197.119081) (xy 2.346947 -197.166603) (xy 2.289081 -197.207925)
			(xy 2.226964 -197.24253) (xy 2.161373 -197.269986) (xy 2.093127 -197.28995) (xy 2.02308 -197.302172)
			(xy 1.952106 -197.3065) (xy 1.881093 -197.302879) (xy 1.810927 -197.291355) (xy 1.742486 -197.272071)
			(xy 1.676625 -197.24527) (xy 1.645158 -197.228714) (xy 1.625697 -197.218676) (xy 1.584203 -197.204698)
			(xy 1.540928 -197.198039) (xy 1.497151 -197.198896) (xy 1.454169 -197.207243) (xy 1.413254 -197.222832)
			(xy 1.375616 -197.245204) (xy 1.342369 -197.273695) (xy 1.314497 -197.307463) (xy 1.292825 -197.345508)
			(xy 1.277994 -197.386705) (xy 1.270443 -197.429834) (xy 1.27 -197.451726) (xy 1.27 -197.706335) (xy 3.31393 -197.706335)
			(xy 3.31393 -197.635013) (xy 3.321916 -197.564139) (xy 3.337786 -197.494604) (xy 3.361343 -197.427284)
			(xy 3.392288 -197.363025) (xy 3.430234 -197.302634) (xy 3.474703 -197.246872) (xy 3.525136 -197.196439)
			(xy 3.580898 -197.15197) (xy 3.641289 -197.114024) (xy 3.705548 -197.083079) (xy 3.772868 -197.059522)
			(xy 3.842403 -197.043652) (xy 3.913277 -197.035666) (xy 3.984599 -197.035666) (xy 4.055473 -197.043652)
			(xy 4.125008 -197.059522) (xy 4.192328 -197.083079) (xy 4.256587 -197.114024) (xy 4.316978 -197.15197)
			(xy 4.37274 -197.196439) (xy 4.423173 -197.246872) (xy 4.467642 -197.302634) (xy 4.505588 -197.363025)
			(xy 4.536533 -197.427284) (xy 4.56009 -197.494604) (xy 4.57596 -197.564139) (xy 4.583946 -197.635013)
			(xy 4.584446 -197.670674) (xy 4.583946 -197.706335) (xy 5.813798 -197.706335) (xy 5.813798 -197.635013)
			(xy 5.821784 -197.564139) (xy 5.837654 -197.494604) (xy 5.861211 -197.427284) (xy 5.892156 -197.363025)
			(xy 5.930102 -197.302634) (xy 5.974571 -197.246872) (xy 6.025004 -197.196439) (xy 6.080766 -197.15197)
			(xy 6.141157 -197.114024) (xy 6.205416 -197.083079) (xy 6.272736 -197.059522) (xy 6.342271 -197.043652)
			(xy 6.413145 -197.035666) (xy 6.484467 -197.035666) (xy 6.555341 -197.043652) (xy 6.624876 -197.059522)
			(xy 6.692196 -197.083079) (xy 6.756455 -197.114024) (xy 6.816846 -197.15197) (xy 6.872608 -197.196439)
			(xy 6.923041 -197.246872) (xy 6.96751 -197.302634) (xy 7.005456 -197.363025) (xy 7.036401 -197.427284)
			(xy 7.059958 -197.494604) (xy 7.075828 -197.564139) (xy 7.083814 -197.635013) (xy 7.084314 -197.670674)
			(xy 7.083814 -197.706335) (xy 7.075828 -197.777209) (xy 7.059958 -197.846744) (xy 7.036401 -197.914064)
			(xy 7.005456 -197.978323) (xy 6.96751 -198.038714) (xy 6.923041 -198.094476) (xy 6.872608 -198.144909)
			(xy 6.816846 -198.189378) (xy 6.756455 -198.227324) (xy 6.692196 -198.258269) (xy 6.624876 -198.281826)
			(xy 6.555341 -198.297696) (xy 6.484467 -198.305682) (xy 6.413145 -198.305682) (xy 6.342271 -198.297696)
			(xy 6.272736 -198.281826) (xy 6.205416 -198.258269) (xy 6.141157 -198.227324) (xy 6.080766 -198.189378)
			(xy 6.025004 -198.144909) (xy 5.974571 -198.094476) (xy 5.930102 -198.038714) (xy 5.892156 -197.978323)
			(xy 5.861211 -197.914064) (xy 5.837654 -197.846744) (xy 5.821784 -197.777209) (xy 5.813798 -197.706335)
			(xy 4.583946 -197.706335) (xy 4.57596 -197.777209) (xy 4.56009 -197.846744) (xy 4.536533 -197.914064)
			(xy 4.505588 -197.978323) (xy 4.467642 -198.038714) (xy 4.423173 -198.094476) (xy 4.37274 -198.144909)
			(xy 4.316978 -198.189378) (xy 4.256587 -198.227324) (xy 4.192328 -198.258269) (xy 4.125008 -198.281826)
			(xy 4.055473 -198.297696) (xy 3.984599 -198.305682) (xy 3.913277 -198.305682) (xy 3.842403 -198.297696)
			(xy 3.772868 -198.281826) (xy 3.705548 -198.258269) (xy 3.641289 -198.227324) (xy 3.580898 -198.189378)
			(xy 3.525136 -198.144909) (xy 3.474703 -198.094476) (xy 3.430234 -198.038714) (xy 3.392288 -197.978323)
			(xy 3.361343 -197.914064) (xy 3.337786 -197.846744) (xy 3.321916 -197.777209) (xy 3.31393 -197.706335)
			(xy 1.27 -197.706335) (xy 1.27 -197.889114) (xy 1.270451 -197.911017) (xy 1.277949 -197.954175) (xy 1.292744 -197.995407)
			(xy 1.314397 -198.033486) (xy 1.342263 -198.067285) (xy 1.375517 -198.095799) (xy 1.413172 -198.118182)
			(xy 1.45411 -198.133771) (xy 1.497116 -198.142102) (xy 1.540913 -198.142927) (xy 1.584202 -198.136224)
			(xy 1.625699 -198.12219) (xy 1.645158 -198.112126) (xy 1.676623 -198.095567) (xy 1.742485 -198.068765)
			(xy 1.810926 -198.049482) (xy 1.881092 -198.037957) (xy 1.952106 -198.034337) (xy 2.02308 -198.038664)
			(xy 2.093128 -198.050886) (xy 2.161374 -198.07085) (xy 2.226966 -198.098307) (xy 2.289083 -198.132912)
			(xy 2.34695 -198.174234) (xy 2.399843 -198.221757) (xy 2.447101 -198.274886) (xy 2.488135 -198.332958)
			(xy 2.522431 -198.395246) (xy 2.54956 -198.460974) (xy 2.569184 -198.529318) (xy 2.581057 -198.599426)
			(xy 2.585031 -198.670421) (xy 2.583035 -198.706079) (xy 7.813794 -198.706079) (xy 7.813794 -198.634757)
			(xy 7.82178 -198.563883) (xy 7.83765 -198.494348) (xy 7.861207 -198.427028) (xy 7.892152 -198.362769)
			(xy 7.930098 -198.302378) (xy 7.974567 -198.246616) (xy 8.025 -198.196183) (xy 8.080762 -198.151714)
			(xy 8.141153 -198.113768) (xy 8.205412 -198.082823) (xy 8.272732 -198.059266) (xy 8.342267 -198.043396)
			(xy 8.413141 -198.03541) (xy 8.484463 -198.03541) (xy 8.555337 -198.043396) (xy 8.624872 -198.059266)
			(xy 8.692192 -198.082823) (xy 8.756451 -198.113768) (xy 8.816842 -198.151714) (xy 8.872604 -198.196183)
			(xy 8.923037 -198.246616) (xy 8.967506 -198.302378) (xy 9.005452 -198.362769) (xy 9.036397 -198.427028)
			(xy 9.059954 -198.494348) (xy 9.075824 -198.563883) (xy 9.08381 -198.634757) (xy 9.08431 -198.670418)
			(xy 9.08381 -198.706079) (xy 9.075824 -198.776953) (xy 9.059954 -198.846488) (xy 9.036397 -198.913808)
			(xy 9.005452 -198.978067) (xy 8.967506 -199.038458) (xy 8.923037 -199.09422) (xy 8.872604 -199.144653)
			(xy 8.816842 -199.189122) (xy 8.756451 -199.227068) (xy 8.692192 -199.258013) (xy 8.624872 -199.28157)
			(xy 8.555337 -199.29744) (xy 8.484463 -199.305426) (xy 8.413141 -199.305426) (xy 8.342267 -199.29744)
			(xy 8.272732 -199.28157) (xy 8.205412 -199.258013) (xy 8.141153 -199.227068) (xy 8.080762 -199.189122)
			(xy 8.025 -199.144653) (xy 7.974567 -199.09422) (xy 7.930098 -199.038458) (xy 7.892152 -198.978067)
			(xy 7.861207 -198.913808) (xy 7.83765 -198.846488) (xy 7.82178 -198.776953) (xy 7.813794 -198.706079)
			(xy 2.583035 -198.706079) (xy 2.581057 -198.741416) (xy 2.569183 -198.811524) (xy 2.549559 -198.879868)
			(xy 2.52243 -198.945595) (xy 2.488134 -199.007884) (xy 2.4471 -199.065956) (xy 2.399841 -199.119085)
			(xy 2.346948 -199.166607) (xy 2.289081 -199.207929) (xy 2.226964 -199.242534) (xy 2.161373 -199.26999)
			(xy 2.093126 -199.289954) (xy 2.023079 -199.302176) (xy 1.952104 -199.306503) (xy 1.88109 -199.302882)
			(xy 1.810924 -199.291358) (xy 1.742483 -199.272074) (xy 1.676622 -199.245272) (xy 1.645158 -199.22871)
			(xy 1.625697 -199.218672) (xy 1.584203 -199.204695) (xy 1.540927 -199.198036) (xy 1.497151 -199.198892)
			(xy 1.454168 -199.207239) (xy 1.413253 -199.222829) (xy 1.375615 -199.2452) (xy 1.342367 -199.273692)
			(xy 1.314495 -199.307459) (xy 1.292822 -199.345504) (xy 1.277991 -199.386701) (xy 1.27044 -199.42983)
			(xy 1.27 -199.451722) (xy 1.27 -199.706331) (xy 3.31393 -199.706331) (xy 3.31393 -199.635009) (xy 3.321916 -199.564135)
			(xy 3.337786 -199.4946) (xy 3.361343 -199.42728) (xy 3.392288 -199.363021) (xy 3.430234 -199.30263)
			(xy 3.474703 -199.246868) (xy 3.525136 -199.196435) (xy 3.580898 -199.151966) (xy 3.641289 -199.11402)
			(xy 3.705548 -199.083075) (xy 3.772868 -199.059518) (xy 3.842403 -199.043648) (xy 3.913277 -199.035662)
			(xy 3.984599 -199.035662) (xy 4.055473 -199.043648) (xy 4.125008 -199.059518) (xy 4.192328 -199.083075)
			(xy 4.256587 -199.11402) (xy 4.316978 -199.151966) (xy 4.37274 -199.196435) (xy 4.423173 -199.246868)
			(xy 4.467642 -199.30263) (xy 4.505588 -199.363021) (xy 4.536533 -199.42728) (xy 4.56009 -199.4946)
			(xy 4.57596 -199.564135) (xy 4.583946 -199.635009) (xy 4.584446 -199.67067) (xy 4.583946 -199.706331)
			(xy 5.813798 -199.706331) (xy 5.813798 -199.635009) (xy 5.821784 -199.564135) (xy 5.837654 -199.4946)
			(xy 5.861211 -199.42728) (xy 5.892156 -199.363021) (xy 5.930102 -199.30263) (xy 5.974571 -199.246868)
			(xy 6.025004 -199.196435) (xy 6.080766 -199.151966) (xy 6.141157 -199.11402) (xy 6.205416 -199.083075)
			(xy 6.272736 -199.059518) (xy 6.342271 -199.043648) (xy 6.413145 -199.035662) (xy 6.484467 -199.035662)
			(xy 6.555341 -199.043648) (xy 6.624876 -199.059518) (xy 6.692196 -199.083075) (xy 6.756455 -199.11402)
			(xy 6.816846 -199.151966) (xy 6.872608 -199.196435) (xy 6.923041 -199.246868) (xy 6.96751 -199.30263)
			(xy 7.005456 -199.363021) (xy 7.036401 -199.42728) (xy 7.059958 -199.4946) (xy 7.075828 -199.564135)
			(xy 7.083814 -199.635009) (xy 7.084314 -199.67067) (xy 7.083814 -199.706331) (xy 7.075828 -199.777205)
			(xy 7.059958 -199.84674) (xy 7.036401 -199.91406) (xy 7.005456 -199.978319) (xy 6.96751 -200.03871)
			(xy 6.923041 -200.094472) (xy 6.872608 -200.144905) (xy 6.816846 -200.189374) (xy 6.756455 -200.22732)
			(xy 6.692196 -200.258265) (xy 6.624876 -200.281822) (xy 6.555341 -200.297692) (xy 6.484467 -200.305678)
			(xy 6.413145 -200.305678) (xy 6.342271 -200.297692) (xy 6.272736 -200.281822) (xy 6.205416 -200.258265)
			(xy 6.141157 -200.22732) (xy 6.080766 -200.189374) (xy 6.025004 -200.144905) (xy 5.974571 -200.094472)
			(xy 5.930102 -200.03871) (xy 5.892156 -199.978319) (xy 5.861211 -199.91406) (xy 5.837654 -199.84674)
			(xy 5.821784 -199.777205) (xy 5.813798 -199.706331) (xy 4.583946 -199.706331) (xy 4.57596 -199.777205)
			(xy 4.56009 -199.84674) (xy 4.536533 -199.91406) (xy 4.505588 -199.978319) (xy 4.467642 -200.03871)
			(xy 4.423173 -200.094472) (xy 4.37274 -200.144905) (xy 4.316978 -200.189374) (xy 4.256587 -200.22732)
			(xy 4.192328 -200.258265) (xy 4.125008 -200.281822) (xy 4.055473 -200.297692) (xy 3.984599 -200.305678)
			(xy 3.913277 -200.305678) (xy 3.842403 -200.297692) (xy 3.772868 -200.281822) (xy 3.705548 -200.258265)
			(xy 3.641289 -200.22732) (xy 3.580898 -200.189374) (xy 3.525136 -200.144905) (xy 3.474703 -200.094472)
			(xy 3.430234 -200.03871) (xy 3.392288 -199.978319) (xy 3.361343 -199.91406) (xy 3.337786 -199.84674)
			(xy 3.321916 -199.777205) (xy 3.31393 -199.706331) (xy 1.27 -199.706331) (xy 1.27 -199.88911) (xy 1.27045 -199.911013)
			(xy 1.277949 -199.954172) (xy 1.292743 -199.995404) (xy 1.314395 -200.033485) (xy 1.342262 -200.067284)
			(xy 1.375516 -200.095798) (xy 1.413171 -200.118182) (xy 1.45411 -200.133771) (xy 1.497116 -200.142102)
			(xy 1.540914 -200.142927) (xy 1.584204 -200.136223) (xy 1.6257 -200.122189) (xy 1.645158 -200.112122)
			(xy 1.676279 -200.095729) (xy 1.741403 -200.069141) (xy 1.809065 -200.049905) (xy 1.878437 -200.038258)
			(xy 1.948671 -200.034342) (xy 2.018908 -200.038203) (xy 2.088289 -200.049796) (xy 2.155965 -200.068978)
			(xy 2.221111 -200.095515) (xy 2.282928 -200.129083) (xy 2.340661 -200.16927) (xy 2.393604 -200.215586)
			(xy 2.441109 -200.267464) (xy 2.482597 -200.32427) (xy 2.517558 -200.385309) (xy 2.545567 -200.449835)
			(xy 2.566281 -200.517059) (xy 2.579445 -200.586159) (xy 2.5849 -200.65629) (xy 2.583256 -200.706075)
			(xy 7.813794 -200.706075) (xy 7.813794 -200.634753) (xy 7.82178 -200.563879) (xy 7.83765 -200.494344)
			(xy 7.861207 -200.427024) (xy 7.892152 -200.362765) (xy 7.930098 -200.302374) (xy 7.974567 -200.246612)
			(xy 8.025 -200.196179) (xy 8.080762 -200.15171) (xy 8.141153 -200.113764) (xy 8.205412 -200.082819)
			(xy 8.272732 -200.059262) (xy 8.342267 -200.043392) (xy 8.413141 -200.035406) (xy 8.484463 -200.035406)
			(xy 8.555337 -200.043392) (xy 8.624872 -200.059262) (xy 8.692192 -200.082819) (xy 8.756451 -200.113764)
			(xy 8.816842 -200.15171) (xy 8.872604 -200.196179) (xy 8.923037 -200.246612) (xy 8.967506 -200.302374)
			(xy 9.005452 -200.362765) (xy 9.036397 -200.427024) (xy 9.059954 -200.494344) (xy 9.075824 -200.563879)
			(xy 9.08381 -200.634753) (xy 9.08431 -200.670414) (xy 9.08381 -200.706075) (xy 9.075824 -200.776949)
			(xy 9.059954 -200.846484) (xy 9.036397 -200.913804) (xy 9.005452 -200.978063) (xy 8.967506 -201.038454)
			(xy 8.923037 -201.094216) (xy 8.872604 -201.144649) (xy 8.816842 -201.189118) (xy 8.756451 -201.227064)
			(xy 8.692192 -201.258009) (xy 8.624872 -201.281566) (xy 8.555337 -201.297436) (xy 8.484463 -201.305422)
			(xy 8.413141 -201.305422) (xy 8.342267 -201.297436) (xy 8.272732 -201.281566) (xy 8.205412 -201.258009)
			(xy 8.141153 -201.227064) (xy 8.080762 -201.189118) (xy 8.025 -201.144649) (xy 7.974567 -201.094216)
			(xy 7.930098 -201.038454) (xy 7.892152 -200.978063) (xy 7.861207 -200.913804) (xy 7.83765 -200.846484)
			(xy 7.82178 -200.776949) (xy 7.813794 -200.706075) (xy 2.583256 -200.706075) (xy 2.582579 -200.726595)
			(xy 2.572509 -200.796213) (xy 2.554815 -200.864294) (xy 2.529712 -200.930005) (xy 2.497507 -200.992543)
			(xy 2.458594 -201.051143) (xy 2.41345 -201.105088) (xy 2.362625 -201.153719) (xy 2.306742 -201.196441)
			(xy 2.276856 -201.21499) (xy 2.286508 -201.224388) (xy 2.286508 -201.691494) (xy 2.301341 -201.706327)
			(xy 3.31393 -201.706327) (xy 3.31393 -201.635005) (xy 3.321916 -201.564131) (xy 3.337786 -201.494596)
			(xy 3.361343 -201.427276) (xy 3.392288 -201.363017) (xy 3.430234 -201.302626) (xy 3.474703 -201.246864)
			(xy 3.525136 -201.196431) (xy 3.580898 -201.151962) (xy 3.641289 -201.114016) (xy 3.705548 -201.083071)
			(xy 3.772868 -201.059514) (xy 3.842403 -201.043644) (xy 3.913277 -201.035658) (xy 3.984599 -201.035658)
			(xy 4.055473 -201.043644) (xy 4.125008 -201.059514) (xy 4.192328 -201.083071) (xy 4.256587 -201.114016)
			(xy 4.316978 -201.151962) (xy 4.37274 -201.196431) (xy 4.423173 -201.246864) (xy 4.467642 -201.302626)
			(xy 4.505588 -201.363017) (xy 4.536533 -201.427276) (xy 4.56009 -201.494596) (xy 4.57596 -201.564131)
			(xy 4.583946 -201.635005) (xy 4.584446 -201.670666) (xy 4.583946 -201.706327) (xy 5.813798 -201.706327)
			(xy 5.813798 -201.635005) (xy 5.821784 -201.564131) (xy 5.837654 -201.494596) (xy 5.861211 -201.427276)
			(xy 5.892156 -201.363017) (xy 5.930102 -201.302626) (xy 5.974571 -201.246864) (xy 6.025004 -201.196431)
			(xy 6.080766 -201.151962) (xy 6.141157 -201.114016) (xy 6.205416 -201.083071) (xy 6.272736 -201.059514)
			(xy 6.342271 -201.043644) (xy 6.413145 -201.035658) (xy 6.484467 -201.035658) (xy 6.555341 -201.043644)
			(xy 6.624876 -201.059514) (xy 6.692196 -201.083071) (xy 6.756455 -201.114016) (xy 6.816846 -201.151962)
			(xy 6.872608 -201.196431) (xy 6.923041 -201.246864) (xy 6.96751 -201.302626) (xy 7.005456 -201.363017)
			(xy 7.036401 -201.427276) (xy 7.059958 -201.494596) (xy 7.075828 -201.564131) (xy 7.083814 -201.635005)
			(xy 7.084314 -201.670666) (xy 7.083814 -201.706327) (xy 7.075828 -201.777201) (xy 7.059958 -201.846736)
			(xy 7.036401 -201.914056) (xy 7.005456 -201.978315) (xy 6.96751 -202.038706) (xy 6.923041 -202.094468)
			(xy 6.872608 -202.144901) (xy 6.816846 -202.18937) (xy 6.756455 -202.227316) (xy 6.692196 -202.258261)
			(xy 6.624876 -202.281818) (xy 6.555341 -202.297688) (xy 6.484467 -202.305674) (xy 6.413145 -202.305674)
			(xy 6.342271 -202.297688) (xy 6.272736 -202.281818) (xy 6.205416 -202.258261) (xy 6.141157 -202.227316)
			(xy 6.080766 -202.18937) (xy 6.025004 -202.144901) (xy 5.974571 -202.094468) (xy 5.930102 -202.038706)
			(xy 5.892156 -201.978315) (xy 5.861211 -201.914056) (xy 5.837654 -201.846736) (xy 5.821784 -201.777201)
			(xy 5.813798 -201.706327) (xy 4.583946 -201.706327) (xy 4.57596 -201.777201) (xy 4.56009 -201.846736)
			(xy 4.536533 -201.914056) (xy 4.505588 -201.978315) (xy 4.467642 -202.038706) (xy 4.423173 -202.094468)
			(xy 4.37274 -202.144901) (xy 4.316978 -202.18937) (xy 4.256587 -202.227316) (xy 4.192328 -202.258261)
			(xy 4.125008 -202.281818) (xy 4.055473 -202.297688) (xy 3.984599 -202.305674) (xy 3.913277 -202.305674)
			(xy 3.842403 -202.297688) (xy 3.772868 -202.281818) (xy 3.705548 -202.258261) (xy 3.641289 -202.227316)
			(xy 3.580898 -202.18937) (xy 3.525136 -202.144901) (xy 3.474703 -202.094468) (xy 3.430234 -202.038706)
			(xy 3.392288 -201.978315) (xy 3.361343 -201.914056) (xy 3.337786 -201.846736) (xy 3.321916 -201.777201)
			(xy 3.31393 -201.706327) (xy 2.301341 -201.706327) (xy 2.546604 -201.95159) (xy 3.436112 -202.841098)
			(xy 6.97611 -202.841098)
		)
		(stroke
			(width 0)
			(type solid)
		)
		(fill yes)
		(layer "F.Cu")
		(net "P12V")
	)
	(gr_poly
		(pts
			(xy 7.492492 -179.253388) (xy 19.860768 -179.253388) (xy 19.873214 -179.265834) (xy 20.13331 -179.265834)
			(xy 20.206462 -179.197508) (xy 20.209764 -179.147216) (xy 20.212865 -179.110474) (xy 20.228337 -179.038382)
			(xy 20.254068 -178.969284) (xy 20.271232 -178.93665) (xy 20.281381 -178.91718) (xy 20.295562 -178.875631)
			(xy 20.302392 -178.832263) (xy 20.301668 -178.788367) (xy 20.29341 -178.745248) (xy 20.277865 -178.70419)
			(xy 20.255496 -178.666414) (xy 20.226967 -178.633044) (xy 20.193128 -178.605074) (xy 20.154986 -178.583334)
			(xy 20.113675 -178.568474) (xy 20.070425 -178.560933) (xy 20.048474 -178.560476) (xy 20.007072 -178.560476)
			(xy 20.007072 -178.290728) (xy 19.437604 -177.721514) (xy 19.437604 -176.031144) (xy 19.253708 -175.847248)
			(xy 17.342612 -175.847248) (xy 17.342612 -175.033432) (xy 19.324828 -175.033432) (xy 19.324828 -175.035464)
			(xy 19.398996 -175.109632) (xy 19.45132 -175.109632) (xy 20.09902 -175.757332) (xy 20.09902 -177.447702)
			(xy 20.499832 -177.848768) (xy 20.76958 -177.848768) (xy 20.76958 -177.874168) (xy 20.962874 -177.874168)
			(xy 20.979529 -177.873676) (xy 21.011706 -177.865059) (xy 21.040555 -177.848405) (xy 21.064109 -177.82485)
			(xy 21.080761 -177.796001) (xy 21.089377 -177.763824) (xy 21.089874 -177.747168) (xy 21.089874 -177.048414)
			(xy 21.85289 -177.048414) (xy 21.85289 -177.074068) (xy 22.14372 -177.074068) (xy 22.14372 -177.048668)
			(xy 22.19452 -176.997868) (xy 22.19452 -176.830228) (xy 22.743922 -176.280826) (xy 22.759396 -176.264669)
			(xy 22.784985 -176.227978) (xy 22.803759 -176.187376) (xy 22.81514 -176.144115) (xy 22.818776 -176.099531)
			(xy 22.814556 -176.054997) (xy 22.802609 -176.01189) (xy 22.783304 -175.971537) (xy 22.757236 -175.935184)
			(xy 22.72521 -175.903953) (xy 22.688214 -175.878808) (xy 22.647389 -175.860523) (xy 22.625812 -175.854614)
			(xy 22.625812 -175.033432) (xy 24.608028 -175.033432) (xy 24.608028 -175.035464) (xy 24.682196 -175.109632)
			(xy 25.110186 -175.109632) (xy 25.126429 -175.109169) (xy 25.157873 -175.101019) (xy 25.18624 -175.085191)
			(xy 25.198324 -175.074326) (xy 25.22139 -175.052756) (xy 25.271937 -175.014898) (xy 25.326784 -174.983593)
			(xy 25.385087 -174.959323) (xy 25.445947 -174.942463) (xy 25.508427 -174.933271) (xy 25.571564 -174.931891)
			(xy 25.634386 -174.938341) (xy 25.695925 -174.952525) (xy 25.755234 -174.974222) (xy 25.811397 -175.003099)
			(xy 25.863551 -175.038711) (xy 25.910892 -175.08051) (xy 25.95269 -175.12785) (xy 25.988302 -175.180004)
			(xy 26.017178 -175.236168) (xy 26.038876 -175.295476) (xy 26.053059 -175.357015) (xy 26.05951 -175.419838)
			(xy 26.058128 -175.482975) (xy 26.048937 -175.545455) (xy 26.032076 -175.606315) (xy 26.007806 -175.664618)
			(xy 25.976501 -175.719465) (xy 25.938643 -175.770012) (xy 25.917144 -175.793146) (xy 25.906213 -175.805196)
			(xy 25.890297 -175.833558) (xy 25.88207 -175.865023) (xy 25.881584 -175.881284) (xy 25.881584 -176.177448)
			(xy 25.868376 -176.244504) (xy 25.88514 -176.28489) (xy 25.891258 -176.298576) (xy 25.908871 -176.322825)
			(xy 25.931658 -176.342293) (xy 25.958361 -176.355903) (xy 25.987503 -176.362902) (xy 26.002488 -176.363376)
			(xy 26.656538 -176.363376) (xy 26.882852 -176.137316) (xy 26.882852 -113.440464) (xy 21.830792 -108.388404)
			(xy 21.830792 -104.693974) (xy 22.259798 -104.264714) (xy 22.613112 -103.9114) (xy 22.613112 -98.858832)
			(xy 23.189438 -98.282506) (xy 23.889462 -97.582736) (xy 23.957534 -97.582736) (xy 23.979973 -97.58153)
			(xy 24.023927 -97.572209) (xy 24.065561 -97.555311) (xy 24.103578 -97.531363) (xy 24.136798 -97.501108)
			(xy 24.164186 -97.465489) (xy 24.184891 -97.425612) (xy 24.19827 -97.382718) (xy 24.203905 -97.33814)
			(xy 24.201621 -97.293267) (xy 24.191491 -97.249492) (xy 24.173828 -97.208177) (xy 24.149182 -97.170608)
			(xy 24.134064 -97.153984) (xy 23.154132 -96.174052) (xy 23.154132 -93.83141) (xy 23.843234 -93.142308)
			(xy 27.045158 -93.142308) (xy 28.976574 -91.210892) (xy 28.986976 -91.19893) (xy 29.002097 -91.171081)
			(xy 29.0099 -91.140368) (xy 29.009906 -91.108679) (xy 29.002114 -91.077963) (xy 28.987003 -91.050108)
			(xy 28.976574 -91.038172) (xy 28.223972 -90.28557) (xy 28.223972 -22.802596) (xy 28.222743 -22.786451)
			(xy 28.21317 -22.75553) (xy 28.196139 -22.728004) (xy 28.172741 -22.705637) (xy 28.144476 -22.689863)
			(xy 28.113156 -22.681692) (xy 28.096972 -22.681184) (xy 26.846022 -22.681184) (xy 25.19172 -21.026882)
			(xy 25.19172 -19.007328) (xy 22.866096 -16.681704) (xy 22.862032 -16.677894) (xy 22.862032 -6.147816)
			(xy 21.984208 -5.269992) (xy 12.575286 -5.269992) (xy 12.568682 -5.269992) (xy 1.49225 -5.269992)
			(xy 1.470926 -5.271163) (xy 1.429237 -5.280415) (xy 1.389967 -5.29719) (xy 1.354462 -5.320916) (xy 1.323937 -5.350778)
			(xy 1.299439 -5.385755) (xy 1.281806 -5.424647) (xy 1.271643 -5.466123) (xy 1.27 -5.487416) (xy 1.27 -7.747)
			(xy 5.5306 -7.747) (xy 5.534631 -7.617434) (xy 5.54671 -7.48837) (xy 5.566789 -7.360306) (xy 5.594791 -7.233739)
			(xy 5.630608 -7.109156) (xy 5.6741 -6.987042) (xy 5.7251 -6.867868) (xy 5.783411 -6.752095) (xy 5.848806 -6.640171)
			(xy 5.921033 -6.532529) (xy 5.999813 -6.429586) (xy 6.08484 -6.33174) (xy 6.175785 -6.239368) (xy 6.272297 -6.15283)
			(xy 6.374003 -6.072459) (xy 6.480509 -5.998567) (xy 6.591402 -5.931439) (xy 6.706254 -5.871335) (xy 6.824621 -5.818488)
			(xy 6.946044 -5.773101) (xy 7.070054 -5.735352) (xy 7.196171 -5.705385) (xy 7.323907 -5.683316) (xy 7.452768 -5.669232)
			(xy 7.582255 -5.663186) (xy 7.711868 -5.665202) (xy 7.841104 -5.675272) (xy 7.969465 -5.693357) (xy 8.096453 -5.719387)
			(xy 8.221577 -5.753262) (xy 8.344353 -5.79485) (xy 8.464306 -5.843991) (xy 8.580971 -5.900494) (xy 8.693899 -5.964141)
			(xy 8.802651 -6.034685) (xy 8.906807 -6.111854) (xy 9.005964 -6.195349) (xy 9.099738 -6.284847) (xy 9.187767 -6.380002)
			(xy 9.26971 -6.480445) (xy 9.345249 -6.585788) (xy 9.414094 -6.695624) (xy 9.475977 -6.809528) (xy 9.530658 -6.927058)
			(xy 9.577928 -7.047761) (xy 9.617601 -7.171169) (xy 9.649526 -7.296805) (xy 9.673578 -7.424182) (xy 9.689665 -7.552808)
			(xy 9.697724 -7.682186) (xy 9.698228 -7.747) (xy 9.697724 -7.811814) (xy 9.689665 -7.941192) (xy 9.673578 -8.069818)
			(xy 9.649526 -8.197195) (xy 9.617601 -8.322831) (xy 9.577928 -8.446239) (xy 9.530658 -8.566942) (xy 9.475977 -8.684472)
			(xy 9.414094 -8.798376) (xy 9.345249 -8.908212) (xy 9.26971 -9.013555) (xy 9.233814 -9.057555) (xy 15.679156 -9.057555)
			(xy 15.679156 -8.976445) (xy 15.687106 -8.895726) (xy 15.702929 -8.816175) (xy 15.726474 -8.738559)
			(xy 15.757513 -8.663623) (xy 15.795748 -8.592091) (xy 15.84081 -8.524651) (xy 15.892265 -8.461952)
			(xy 15.949618 -8.404599) (xy 16.012317 -8.353144) (xy 16.079757 -8.308082) (xy 16.151289 -8.269847)
			(xy 16.226225 -8.238808) (xy 16.303841 -8.215263) (xy 16.383392 -8.19944) (xy 16.464111 -8.19149)
			(xy 16.545221 -8.19149) (xy 16.62594 -8.19944) (xy 16.705491 -8.215263) (xy 16.783107 -8.238808)
			(xy 16.858043 -8.269847) (xy 16.929575 -8.308082) (xy 16.997015 -8.353144) (xy 17.059714 -8.404599)
			(xy 17.117067 -8.461952) (xy 17.168522 -8.524651) (xy 17.213584 -8.592091) (xy 17.251819 -8.663623)
			(xy 17.282858 -8.738559) (xy 17.306403 -8.816175) (xy 17.322226 -8.895726) (xy 17.330176 -8.976445)
			(xy 17.330674 -9.017) (xy 17.330176 -9.057555) (xy 17.322226 -9.138274) (xy 17.306403 -9.217825)
			(xy 17.282858 -9.295441) (xy 17.251819 -9.370377) (xy 17.213584 -9.441909) (xy 17.168522 -9.509349)
			(xy 17.117067 -9.572048) (xy 17.059714 -9.629401) (xy 16.997015 -9.680856) (xy 16.929575 -9.725918)
			(xy 16.858043 -9.764153) (xy 16.783107 -9.795192) (xy 16.705491 -9.818737) (xy 16.62594 -9.83456)
			(xy 16.545221 -9.84251) (xy 16.464111 -9.84251) (xy 16.383392 -9.83456) (xy 16.303841 -9.818737)
			(xy 16.226225 -9.795192) (xy 16.151289 -9.764153) (xy 16.079757 -9.725918) (xy 16.012317 -9.680856)
			(xy 15.949618 -9.629401) (xy 15.892265 -9.572048) (xy 15.84081 -9.509349) (xy 15.795748 -9.441909)
			(xy 15.757513 -9.370377) (xy 15.726474 -9.295441) (xy 15.702929 -9.217825) (xy 15.687106 -9.138274)
			(xy 15.679156 -9.057555) (xy 9.233814 -9.057555) (xy 9.187767 -9.113998) (xy 9.099738 -9.209153)
			(xy 9.005964 -9.298651) (xy 8.906807 -9.382146) (xy 8.802651 -9.459315) (xy 8.693899 -9.529859) (xy 8.580971 -9.593506)
			(xy 8.464306 -9.650009) (xy 8.344353 -9.69915) (xy 8.221577 -9.740738) (xy 8.096453 -9.774613) (xy 7.969465 -9.800643)
			(xy 7.841104 -9.818728) (xy 7.711868 -9.828798) (xy 7.582255 -9.830814) (xy 7.452768 -9.824768) (xy 7.323907 -9.810684)
			(xy 7.196171 -9.788615) (xy 7.070054 -9.758648) (xy 6.946044 -9.720899) (xy 6.824621 -9.675512) (xy 6.706254 -9.622665)
			(xy 6.591402 -9.562561) (xy 6.480509 -9.495433) (xy 6.374003 -9.421541) (xy 6.272297 -9.34117) (xy 6.175785 -9.254632)
			(xy 6.08484 -9.16226) (xy 5.999813 -9.064414) (xy 5.921033 -8.961471) (xy 5.848806 -8.853829) (xy 5.783411 -8.741905)
			(xy 5.7251 -8.626132) (xy 5.6741 -8.506958) (xy 5.630608 -8.384844) (xy 5.594791 -8.260261) (xy 5.566789 -8.133694)
			(xy 5.54671 -8.00563) (xy 5.534631 -7.876566) (xy 5.5306 -7.747) (xy 1.27 -7.747) (xy 1.27 -10.327555)
			(xy 13.139156 -10.327555) (xy 13.139156 -10.246445) (xy 13.147106 -10.165726) (xy 13.162929 -10.086175)
			(xy 13.186474 -10.008559) (xy 13.217513 -9.933623) (xy 13.255748 -9.862091) (xy 13.30081 -9.794651)
			(xy 13.352265 -9.731952) (xy 13.409618 -9.674599) (xy 13.472317 -9.623144) (xy 13.539757 -9.578082)
			(xy 13.611289 -9.539847) (xy 13.686225 -9.508808) (xy 13.763841 -9.485263) (xy 13.843392 -9.46944)
			(xy 13.924111 -9.46149) (xy 14.005221 -9.46149) (xy 14.08594 -9.46944) (xy 14.165491 -9.485263) (xy 14.243107 -9.508808)
			(xy 14.318043 -9.539847) (xy 14.389575 -9.578082) (xy 14.457015 -9.623144) (xy 14.519714 -9.674599)
			(xy 14.577067 -9.731952) (xy 14.628522 -9.794651) (xy 14.673584 -9.862091) (xy 14.711819 -9.933623)
			(xy 14.742858 -10.008559) (xy 14.766403 -10.086175) (xy 14.782226 -10.165726) (xy 14.790176 -10.246445)
			(xy 14.790674 -10.287) (xy 14.790176 -10.327555) (xy 14.782226 -10.408274) (xy 14.766403 -10.487825)
			(xy 14.742858 -10.565441) (xy 14.711819 -10.640377) (xy 14.673584 -10.711909) (xy 14.628522 -10.779349)
			(xy 14.577067 -10.842048) (xy 14.519714 -10.899401) (xy 14.457015 -10.950856) (xy 14.389575 -10.995918)
			(xy 14.318043 -11.034153) (xy 14.243107 -11.065192) (xy 14.165491 -11.088737) (xy 14.08594 -11.10456)
			(xy 14.005221 -11.11251) (xy 13.924111 -11.11251) (xy 13.843392 -11.10456) (xy 13.763841 -11.088737)
			(xy 13.686225 -11.065192) (xy 13.611289 -11.034153) (xy 13.539757 -10.995918) (xy 13.472317 -10.950856)
			(xy 13.409618 -10.899401) (xy 13.352265 -10.842048) (xy 13.30081 -10.779349) (xy 13.255748 -10.711909)
			(xy 13.217513 -10.640377) (xy 13.186474 -10.565441) (xy 13.162929 -10.487825) (xy 13.147106 -10.408274)
			(xy 13.139156 -10.327555) (xy 1.27 -10.327555) (xy 1.27 -11.597555) (xy 15.679156 -11.597555) (xy 15.679156 -11.516445)
			(xy 15.687106 -11.435726) (xy 15.702929 -11.356175) (xy 15.726474 -11.278559) (xy 15.757513 -11.203623)
			(xy 15.795748 -11.132091) (xy 15.84081 -11.064651) (xy 15.892265 -11.001952) (xy 15.949618 -10.944599)
			(xy 16.012317 -10.893144) (xy 16.079757 -10.848082) (xy 16.151289 -10.809847) (xy 16.226225 -10.778808)
			(xy 16.303841 -10.755263) (xy 16.383392 -10.73944) (xy 16.464111 -10.73149) (xy 16.545221 -10.73149)
			(xy 16.62594 -10.73944) (xy 16.705491 -10.755263) (xy 16.783107 -10.778808) (xy 16.858043 -10.809847)
			(xy 16.929575 -10.848082) (xy 16.997015 -10.893144) (xy 17.059714 -10.944599) (xy 17.117067 -11.001952)
			(xy 17.168522 -11.064651) (xy 17.213584 -11.132091) (xy 17.251819 -11.203623) (xy 17.282858 -11.278559)
			(xy 17.306403 -11.356175) (xy 17.322226 -11.435726) (xy 17.330176 -11.516445) (xy 17.330674 -11.557)
			(xy 17.330176 -11.597555) (xy 17.322226 -11.678274) (xy 17.306403 -11.757825) (xy 17.282858 -11.835441)
			(xy 17.251819 -11.910377) (xy 17.213584 -11.981909) (xy 17.168522 -12.049349) (xy 17.117067 -12.112048)
			(xy 17.059714 -12.169401) (xy 16.997015 -12.220856) (xy 16.929575 -12.265918) (xy 16.858043 -12.304153)
			(xy 16.783107 -12.335192) (xy 16.705491 -12.358737) (xy 16.62594 -12.37456) (xy 16.545221 -12.38251)
			(xy 16.464111 -12.38251) (xy 16.383392 -12.37456) (xy 16.303841 -12.358737) (xy 16.226225 -12.335192)
			(xy 16.151289 -12.304153) (xy 16.079757 -12.265918) (xy 16.012317 -12.220856) (xy 15.949618 -12.169401)
			(xy 15.892265 -12.112048) (xy 15.84081 -12.049349) (xy 15.795748 -11.981909) (xy 15.757513 -11.910377)
			(xy 15.726474 -11.835441) (xy 15.702929 -11.757825) (xy 15.687106 -11.678274) (xy 15.679156 -11.597555)
			(xy 1.27 -11.597555) (xy 1.27 -12.867555) (xy 13.139156 -12.867555) (xy 13.139156 -12.786445) (xy 13.147106 -12.705726)
			(xy 13.162929 -12.626175) (xy 13.186474 -12.548559) (xy 13.217513 -12.473623) (xy 13.255748 -12.402091)
			(xy 13.30081 -12.334651) (xy 13.352265 -12.271952) (xy 13.409618 -12.214599) (xy 13.472317 -12.163144)
			(xy 13.539757 -12.118082) (xy 13.611289 -12.079847) (xy 13.686225 -12.048808) (xy 13.763841 -12.025263)
			(xy 13.843392 -12.00944) (xy 13.924111 -12.00149) (xy 14.005221 -12.00149) (xy 14.08594 -12.00944)
			(xy 14.165491 -12.025263) (xy 14.243107 -12.048808) (xy 14.318043 -12.079847) (xy 14.389575 -12.118082)
			(xy 14.457015 -12.163144) (xy 14.519714 -12.214599) (xy 14.577067 -12.271952) (xy 14.628522 -12.334651)
			(xy 14.673584 -12.402091) (xy 14.711819 -12.473623) (xy 14.742858 -12.548559) (xy 14.766403 -12.626175)
			(xy 14.782226 -12.705726) (xy 14.790176 -12.786445) (xy 14.790674 -12.827) (xy 14.790176 -12.867555)
			(xy 14.782226 -12.948274) (xy 14.766403 -13.027825) (xy 14.742858 -13.105441) (xy 14.711819 -13.180377)
			(xy 14.673584 -13.251909) (xy 14.628522 -13.319349) (xy 14.577067 -13.382048) (xy 14.519714 -13.439401)
			(xy 14.457015 -13.490856) (xy 14.389575 -13.535918) (xy 14.318043 -13.574153) (xy 14.243107 -13.605192)
			(xy 14.165491 -13.628737) (xy 14.08594 -13.64456) (xy 14.005221 -13.65251) (xy 13.924111 -13.65251)
			(xy 13.843392 -13.64456) (xy 13.763841 -13.628737) (xy 13.686225 -13.605192) (xy 13.611289 -13.574153)
			(xy 13.539757 -13.535918) (xy 13.472317 -13.490856) (xy 13.409618 -13.439401) (xy 13.352265 -13.382048)
			(xy 13.30081 -13.319349) (xy 13.255748 -13.251909) (xy 13.217513 -13.180377) (xy 13.186474 -13.105441)
			(xy 13.162929 -13.027825) (xy 13.147106 -12.948274) (xy 13.139156 -12.867555) (xy 1.27 -12.867555)
			(xy 1.27 -14.137555) (xy 15.679156 -14.137555) (xy 15.679156 -14.056445) (xy 15.687106 -13.975726)
			(xy 15.702929 -13.896175) (xy 15.726474 -13.818559) (xy 15.757513 -13.743623) (xy 15.795748 -13.672091)
			(xy 15.84081 -13.604651) (xy 15.892265 -13.541952) (xy 15.949618 -13.484599) (xy 16.012317 -13.433144)
			(xy 16.079757 -13.388082) (xy 16.151289 -13.349847) (xy 16.226225 -13.318808) (xy 16.303841 -13.295263)
			(xy 16.383392 -13.27944) (xy 16.464111 -13.27149) (xy 16.545221 -13.27149) (xy 16.62594 -13.27944)
			(xy 16.705491 -13.295263) (xy 16.783107 -13.318808) (xy 16.858043 -13.349847) (xy 16.929575 -13.388082)
			(xy 16.997015 -13.433144) (xy 17.059714 -13.484599) (xy 17.117067 -13.541952) (xy 17.168522 -13.604651)
			(xy 17.213584 -13.672091) (xy 17.251819 -13.743623) (xy 17.282858 -13.818559) (xy 17.306403 -13.896175)
			(xy 17.322226 -13.975726) (xy 17.330176 -14.056445) (xy 17.330674 -14.097) (xy 17.330176 -14.137555)
			(xy 17.322226 -14.218274) (xy 17.306403 -14.297825) (xy 17.282858 -14.375441) (xy 17.251819 -14.450377)
			(xy 17.213584 -14.521909) (xy 17.168522 -14.589349) (xy 17.117067 -14.652048) (xy 17.059714 -14.709401)
			(xy 16.997015 -14.760856) (xy 16.929575 -14.805918) (xy 16.858043 -14.844153) (xy 16.783107 -14.875192)
			(xy 16.705491 -14.898737) (xy 16.62594 -14.91456) (xy 16.545221 -14.92251) (xy 16.464111 -14.92251)
			(xy 16.383392 -14.91456) (xy 16.303841 -14.898737) (xy 16.226225 -14.875192) (xy 16.151289 -14.844153)
			(xy 16.079757 -14.805918) (xy 16.012317 -14.760856) (xy 15.949618 -14.709401) (xy 15.892265 -14.652048)
			(xy 15.84081 -14.589349) (xy 15.795748 -14.521909) (xy 15.757513 -14.450377) (xy 15.726474 -14.375441)
			(xy 15.702929 -14.297825) (xy 15.687106 -14.218274) (xy 15.679156 -14.137555) (xy 1.27 -14.137555)
			(xy 1.27 -15.407555) (xy 13.139156 -15.407555) (xy 13.139156 -15.326445) (xy 13.147106 -15.245726)
			(xy 13.162929 -15.166175) (xy 13.186474 -15.088559) (xy 13.217513 -15.013623) (xy 13.255748 -14.942091)
			(xy 13.30081 -14.874651) (xy 13.352265 -14.811952) (xy 13.409618 -14.754599) (xy 13.472317 -14.703144)
			(xy 13.539757 -14.658082) (xy 13.611289 -14.619847) (xy 13.686225 -14.588808) (xy 13.763841 -14.565263)
			(xy 13.843392 -14.54944) (xy 13.924111 -14.54149) (xy 14.005221 -14.54149) (xy 14.08594 -14.54944)
			(xy 14.165491 -14.565263) (xy 14.243107 -14.588808) (xy 14.318043 -14.619847) (xy 14.389575 -14.658082)
			(xy 14.457015 -14.703144) (xy 14.519714 -14.754599) (xy 14.577067 -14.811952) (xy 14.628522 -14.874651)
			(xy 14.673584 -14.942091) (xy 14.711819 -15.013623) (xy 14.742858 -15.088559) (xy 14.766403 -15.166175)
			(xy 14.782226 -15.245726) (xy 14.790176 -15.326445) (xy 14.790674 -15.367) (xy 14.790176 -15.407555)
			(xy 14.782226 -15.488274) (xy 14.766403 -15.567825) (xy 14.742858 -15.645441) (xy 14.711819 -15.720377)
			(xy 14.673584 -15.791909) (xy 14.628522 -15.859349) (xy 14.577067 -15.922048) (xy 14.519714 -15.979401)
			(xy 14.457015 -16.030856) (xy 14.389575 -16.075918) (xy 14.318043 -16.114153) (xy 14.243107 -16.145192)
			(xy 14.165491 -16.168737) (xy 14.08594 -16.18456) (xy 14.005221 -16.19251) (xy 13.924111 -16.19251)
			(xy 13.843392 -16.18456) (xy 13.763841 -16.168737) (xy 13.686225 -16.145192) (xy 13.611289 -16.114153)
			(xy 13.539757 -16.075918) (xy 13.472317 -16.030856) (xy 13.409618 -15.979401) (xy 13.352265 -15.922048)
			(xy 13.30081 -15.859349) (xy 13.255748 -15.791909) (xy 13.217513 -15.720377) (xy 13.186474 -15.645441)
			(xy 13.162929 -15.567825) (xy 13.147106 -15.488274) (xy 13.139156 -15.407555) (xy 1.27 -15.407555)
			(xy 1.27 -16.677555) (xy 15.679156 -16.677555) (xy 15.679156 -16.596445) (xy 15.687106 -16.515726)
			(xy 15.702929 -16.436175) (xy 15.726474 -16.358559) (xy 15.757513 -16.283623) (xy 15.795748 -16.212091)
			(xy 15.84081 -16.144651) (xy 15.892265 -16.081952) (xy 15.949618 -16.024599) (xy 16.012317 -15.973144)
			(xy 16.079757 -15.928082) (xy 16.151289 -15.889847) (xy 16.226225 -15.858808) (xy 16.303841 -15.835263)
			(xy 16.383392 -15.81944) (xy 16.464111 -15.81149) (xy 16.545221 -15.81149) (xy 16.62594 -15.81944)
			(xy 16.705491 -15.835263) (xy 16.783107 -15.858808) (xy 16.858043 -15.889847) (xy 16.929575 -15.928082)
			(xy 16.997015 -15.973144) (xy 17.059714 -16.024599) (xy 17.117067 -16.081952) (xy 17.168522 -16.144651)
			(xy 17.213584 -16.212091) (xy 17.251819 -16.283623) (xy 17.282858 -16.358559) (xy 17.306403 -16.436175)
			(xy 17.322226 -16.515726) (xy 17.330176 -16.596445) (xy 17.330674 -16.637) (xy 17.330176 -16.677555)
			(xy 17.322226 -16.758274) (xy 17.306403 -16.837825) (xy 17.282858 -16.915441) (xy 17.251819 -16.990377)
			(xy 17.213584 -17.061909) (xy 17.168522 -17.129349) (xy 17.117067 -17.192048) (xy 17.059714 -17.249401)
			(xy 16.997015 -17.300856) (xy 16.929575 -17.345918) (xy 16.858043 -17.384153) (xy 16.783107 -17.415192)
			(xy 16.705491 -17.438737) (xy 16.62594 -17.45456) (xy 16.545221 -17.46251) (xy 16.464111 -17.46251)
			(xy 16.383392 -17.45456) (xy 16.303841 -17.438737) (xy 16.226225 -17.415192) (xy 16.151289 -17.384153)
			(xy 16.079757 -17.345918) (xy 16.012317 -17.300856) (xy 15.949618 -17.249401) (xy 15.892265 -17.192048)
			(xy 15.84081 -17.129349) (xy 15.795748 -17.061909) (xy 15.757513 -16.990377) (xy 15.726474 -16.915441)
			(xy 15.702929 -16.837825) (xy 15.687106 -16.758274) (xy 15.679156 -16.677555) (xy 1.27 -16.677555)
			(xy 1.27 -17.080992) (xy 13.138912 -17.080992) (xy 14.79042 -17.080992) (xy 14.79042 -18.733008)
			(xy 13.138912 -18.733008) (xy 13.138912 -17.080992) (xy 1.27 -17.080992) (xy 1.27 -19.177) (xy 5.5306 -19.177)
			(xy 5.534631 -19.047434) (xy 5.54671 -18.91837) (xy 5.566789 -18.790306) (xy 5.594791 -18.663739)
			(xy 5.630608 -18.539156) (xy 5.6741 -18.417042) (xy 5.7251 -18.297868) (xy 5.783411 -18.182095) (xy 5.848806 -18.070171)
			(xy 5.921033 -17.962529) (xy 5.999813 -17.859586) (xy 6.08484 -17.76174) (xy 6.175785 -17.669368)
			(xy 6.272297 -17.58283) (xy 6.374003 -17.502459) (xy 6.480509 -17.428567) (xy 6.591402 -17.361439)
			(xy 6.706254 -17.301335) (xy 6.824621 -17.248488) (xy 6.946044 -17.203101) (xy 7.070054 -17.165352)
			(xy 7.196171 -17.135385) (xy 7.323907 -17.113316) (xy 7.452768 -17.099232) (xy 7.582255 -17.093186)
			(xy 7.711868 -17.095202) (xy 7.841104 -17.105272) (xy 7.969465 -17.123357) (xy 8.096453 -17.149387)
			(xy 8.221577 -17.183262) (xy 8.344353 -17.22485) (xy 8.464306 -17.273991) (xy 8.580971 -17.330494)
			(xy 8.693899 -17.394141) (xy 8.802651 -17.464685) (xy 8.906807 -17.541854) (xy 9.005964 -17.625349)
			(xy 9.099738 -17.714847) (xy 9.187767 -17.810002) (xy 9.26971 -17.910445) (xy 9.345249 -18.015788)
			(xy 9.414094 -18.125624) (xy 9.475977 -18.239528) (xy 9.530658 -18.357058) (xy 9.577928 -18.477761)
			(xy 9.617601 -18.601169) (xy 9.649526 -18.726805) (xy 9.673578 -18.854182) (xy 9.689665 -18.982808)
			(xy 9.697724 -19.112186) (xy 9.698228 -19.177) (xy 9.697724 -19.241814) (xy 9.689665 -19.371192)
			(xy 9.673578 -19.499818) (xy 9.649526 -19.627195) (xy 9.617601 -19.752831) (xy 9.577928 -19.876239)
			(xy 9.530658 -19.996942) (xy 9.475977 -20.114472) (xy 9.414094 -20.228376) (xy 9.345249 -20.338212)
			(xy 9.26971 -20.443555) (xy 9.187767 -20.543998) (xy 9.099738 -20.639153) (xy 9.005964 -20.728651)
			(xy 8.906807 -20.812146) (xy 8.802651 -20.889315) (xy 8.693899 -20.959859) (xy 8.580971 -21.023506)
			(xy 8.464306 -21.080009) (xy 8.344353 -21.12915) (xy 8.221577 -21.170738) (xy 8.096453 -21.204613)
			(xy 7.969465 -21.230643) (xy 7.841104 -21.248728) (xy 7.711868 -21.258798) (xy 7.582255 -21.260814)
			(xy 7.452768 -21.254768) (xy 7.323907 -21.240684) (xy 7.196171 -21.218615) (xy 7.070054 -21.188648)
			(xy 6.946044 -21.150899) (xy 6.824621 -21.105512) (xy 6.706254 -21.052665) (xy 6.591402 -20.992561)
			(xy 6.480509 -20.925433) (xy 6.374003 -20.851541) (xy 6.272297 -20.77117) (xy 6.175785 -20.684632)
			(xy 6.08484 -20.59226) (xy 5.999813 -20.494414) (xy 5.921033 -20.391471) (xy 5.848806 -20.283829)
			(xy 5.783411 -20.171905) (xy 5.7251 -20.056132) (xy 5.6741 -19.936958) (xy 5.630608 -19.814844) (xy 5.594791 -19.690261)
			(xy 5.566789 -19.563694) (xy 5.54671 -19.43563) (xy 5.534631 -19.306566) (xy 5.5306 -19.177) (xy 1.27 -19.177)
			(xy 1.27 -25.909778) (xy 6.672086 -25.909778) (xy 6.676039 -25.817963) (xy 6.687871 -25.726827) (xy 6.707494 -25.637046)
			(xy 6.734762 -25.549284) (xy 6.769473 -25.464192) (xy 6.811371 -25.382398) (xy 6.860146 -25.304509)
			(xy 6.915435 -25.2311) (xy 6.97683 -25.162717) (xy 7.043877 -25.099865) (xy 7.116079 -25.043008)
			(xy 7.1929 -24.99257) (xy 7.273774 -24.948921) (xy 7.3581 -24.912387) (xy 7.445255 -24.883237) (xy 7.534593 -24.861687)
			(xy 7.625453 -24.847897) (xy 7.717162 -24.841969) (xy 7.809041 -24.843946) (xy 7.90041 -24.853814)
			(xy 7.990592 -24.871501) (xy 8.07892 -24.896874) (xy 8.16474 -24.929747) (xy 8.247417 -24.969875)
			(xy 8.326337 -25.016962) (xy 8.400918 -25.07066) (xy 8.470607 -25.130569) (xy 8.534887 -25.196248)
			(xy 8.593284 -25.26721) (xy 8.645364 -25.342928) (xy 8.690742 -25.422844) (xy 8.729082 -25.506365)
			(xy 8.7601 -25.592872) (xy 8.783568 -25.681726) (xy 8.799309 -25.772268) (xy 8.80721 -25.863828)
			(xy 8.807704 -25.909778) (xy 8.80721 -25.955728) (xy 8.799309 -26.047288) (xy 8.783568 -26.13783)
			(xy 8.7601 -26.226684) (xy 8.729082 -26.313191) (xy 8.690742 -26.396712) (xy 8.645364 -26.476628)
			(xy 8.593284 -26.552346) (xy 8.534887 -26.623308) (xy 8.470607 -26.688987) (xy 8.400918 -26.748896)
			(xy 8.326337 -26.802594) (xy 8.247417 -26.849681) (xy 8.16474 -26.889809) (xy 8.07892 -26.922682)
			(xy 7.990592 -26.948055) (xy 7.90041 -26.965742) (xy 7.809041 -26.97561) (xy 7.717162 -26.977587)
			(xy 7.625453 -26.971659) (xy 7.534593 -26.957869) (xy 7.445255 -26.936319) (xy 7.3581 -26.907169)
			(xy 7.273774 -26.870635) (xy 7.1929 -26.826986) (xy 7.116079 -26.776548) (xy 7.043877 -26.719691)
			(xy 6.97683 -26.656839) (xy 6.915435 -26.588456) (xy 6.860146 -26.515047) (xy 6.811371 -26.437158)
			(xy 6.769473 -26.355364) (xy 6.734762 -26.270272) (xy 6.707494 -26.18251) (xy 6.687871 -26.092729)
			(xy 6.676039 -26.001593) (xy 6.672086 -25.909778) (xy 1.27 -25.909778) (xy 1.27 -28.952635) (xy 4.852911 -28.952635)
			(xy 4.852911 -28.866909) (xy 4.860821 -28.781549) (xy 4.876573 -28.697282) (xy 4.900033 -28.614829)
			(xy 4.931001 -28.534892) (xy 4.969212 -28.458153) (xy 5.014341 -28.385267) (xy 5.066002 -28.316856)
			(xy 5.123756 -28.253504) (xy 5.187108 -28.19575) (xy 5.255519 -28.144089) (xy 5.328405 -28.09896)
			(xy 5.405144 -28.060749) (xy 5.485081 -28.029781) (xy 5.567534 -28.006321) (xy 5.651801 -27.990569)
			(xy 5.737161 -27.982659) (xy 5.822887 -27.982659) (xy 5.908247 -27.990569) (xy 5.992514 -28.006321)
			(xy 6.074967 -28.029781) (xy 6.154904 -28.060749) (xy 6.231643 -28.09896) (xy 6.304529 -28.144089)
			(xy 6.37294 -28.19575) (xy 6.436292 -28.253504) (xy 6.494046 -28.316856) (xy 6.545707 -28.385267)
			(xy 6.590836 -28.458153) (xy 6.629047 -28.534892) (xy 6.660015 -28.614829) (xy 6.683475 -28.697282)
			(xy 6.699227 -28.781549) (xy 6.707137 -28.866909) (xy 6.707632 -28.909772) (xy 6.707137 -28.952635)
			(xy 6.699227 -29.037995) (xy 6.683475 -29.122262) (xy 6.661402 -29.19984) (xy 8.597656 -29.19984)
			(xy 8.601644 -28.94722) (xy 8.613605 -28.694852) (xy 8.633527 -28.442988) (xy 8.661391 -28.191878)
			(xy 8.697167 -27.941772) (xy 8.740821 -27.692921) (xy 8.79231 -27.445572) (xy 8.851581 -27.199971)
			(xy 8.918576 -26.956364) (xy 8.993227 -26.714994) (xy 9.075462 -26.4761) (xy 9.165196 -26.239922)
			(xy 9.262342 -26.006694) (xy 9.366802 -25.776648) (xy 9.478473 -25.550016) (xy 9.597242 -25.327021)
			(xy 9.722991 -25.107887) (xy 9.855596 -24.892832) (xy 9.994923 -24.68207) (xy 10.140835 -24.475812)
			(xy 10.293185 -24.274263) (xy 10.451821 -24.077623) (xy 10.616586 -23.88609) (xy 10.787316 -23.699853)
			(xy 10.96384 -23.519099) (xy 11.145982 -23.344008) (xy 11.33356 -23.174754) (xy 11.526388 -23.011505)
			(xy 11.724273 -22.854426) (xy 11.927019 -22.703671) (xy 12.134423 -22.559393) (xy 12.346278 -22.421733)
			(xy 12.562373 -22.29083) (xy 12.782493 -22.166814) (xy 13.006418 -22.049809) (xy 13.233925 -21.939931)
			(xy 13.464787 -21.83729) (xy 13.698775 -21.741988) (xy 13.935654 -21.654121) (xy 14.17519 -21.573774)
			(xy 14.417142 -21.50103) (xy 14.66127 -21.43596) (xy 14.907331 -21.37863) (xy 15.155079 -21.329096)
			(xy 15.404267 -21.287407) (xy 15.654647 -21.253606) (xy 15.905969 -21.227725) (xy 16.157983 -21.209792)
			(xy 16.410437 -21.199823) (xy 16.663081 -21.197829) (xy 16.915661 -21.203811) (xy 17.167927 -21.217764)
			(xy 17.419626 -21.239674) (xy 17.670509 -21.269518) (xy 17.920324 -21.307268) (xy 18.168823 -21.352885)
			(xy 18.415758 -21.406324) (xy 18.660883 -21.467532) (xy 18.903953 -21.536447) (xy 19.144727 -21.613002)
			(xy 19.382964 -21.697119) (xy 19.618427 -21.788716) (xy 19.850881 -21.8877) (xy 20.080095 -21.993972)
			(xy 20.305839 -22.107428) (xy 20.527889 -22.227953) (xy 20.746023 -22.355429) (xy 20.960025 -22.489727)
			(xy 21.169681 -22.630713) (xy 21.374781 -22.778248) (xy 21.575121 -22.932184) (xy 21.770502 -23.092368)
			(xy 21.960729 -23.25864) (xy 22.145612 -23.430835) (xy 22.324968 -23.608779) (xy 22.498616 -23.792298)
			(xy 22.666384 -23.981206) (xy 22.828105 -24.175317) (xy 22.983618 -24.374436) (xy 23.132767 -24.578365)
			(xy 23.275404 -24.786901) (xy 23.411387 -24.999836) (xy 23.54058 -25.216958) (xy 23.662855 -25.43805)
			(xy 23.778089 -25.662891) (xy 23.886168 -25.891259) (xy 23.986983 -26.122924) (xy 24.080435 -26.357657)
			(xy 24.16643 -26.595222) (xy 24.244883 -26.835384) (xy 24.315715 -27.077903) (xy 24.378856 -27.322538)
			(xy 24.434243 -27.569043) (xy 24.48182 -27.817174) (xy 24.52154 -28.066684) (xy 24.553364 -28.317323)
			(xy 24.57726 -28.568841) (xy 24.593204 -28.820989) (xy 24.601179 -29.073514) (xy 24.601678 -29.19984)
			(xy 24.601179 -29.326166) (xy 24.593204 -29.578691) (xy 24.57726 -29.830839) (xy 24.553364 -30.082357)
			(xy 24.52154 -30.332996) (xy 24.48182 -30.582506) (xy 24.434243 -30.830637) (xy 24.378856 -31.077142)
			(xy 24.315715 -31.321777) (xy 24.244883 -31.564296) (xy 24.16643 -31.804458) (xy 24.080435 -32.042023)
			(xy 23.986983 -32.276756) (xy 23.886168 -32.508421) (xy 23.778089 -32.736789) (xy 23.662855 -32.96163)
			(xy 23.54058 -33.182722) (xy 23.411387 -33.399844) (xy 23.275404 -33.612779) (xy 23.132767 -33.821315)
			(xy 22.983618 -34.025244) (xy 22.828105 -34.224363) (xy 22.666384 -34.418474) (xy 22.498616 -34.607382)
			(xy 22.324968 -34.790901) (xy 22.145612 -34.968845) (xy 21.960729 -35.14104) (xy 21.770502 -35.307312)
			(xy 21.575121 -35.467496) (xy 21.374781 -35.621432) (xy 21.169681 -35.768967) (xy 20.960025 -35.909953)
			(xy 20.746023 -36.044251) (xy 20.527889 -36.171727) (xy 20.305839 -36.292252) (xy 20.080095 -36.405708)
			(xy 19.850881 -36.51198) (xy 19.618427 -36.610964) (xy 19.382964 -36.702561) (xy 19.144727 -36.786678)
			(xy 18.903953 -36.863233) (xy 18.660883 -36.932148) (xy 18.415758 -36.993356) (xy 18.168823 -37.046795)
			(xy 17.920324 -37.092412) (xy 17.670509 -37.130162) (xy 17.419626 -37.160006) (xy 17.167927 -37.181916)
			(xy 16.915661 -37.195869) (xy 16.663081 -37.201851) (xy 16.410437 -37.199857) (xy 16.157983 -37.189888)
			(xy 15.905969 -37.171955) (xy 15.654647 -37.146074) (xy 15.404267 -37.112273) (xy 15.155079 -37.070584)
			(xy 14.907331 -37.02105) (xy 14.66127 -36.96372) (xy 14.417142 -36.89865) (xy 14.17519 -36.825906)
			(xy 13.935654 -36.745559) (xy 13.698775 -36.657692) (xy 13.464787 -36.56239) (xy 13.233925 -36.459749)
			(xy 13.006418 -36.349871) (xy 12.782493 -36.232866) (xy 12.562373 -36.10885) (xy 12.346278 -35.977947)
			(xy 12.134423 -35.840287) (xy 11.927019 -35.696009) (xy 11.724273 -35.545254) (xy 11.526388 -35.388175)
			(xy 11.33356 -35.224926) (xy 11.145982 -35.055672) (xy 10.96384 -34.880581) (xy 10.787316 -34.699827)
			(xy 10.616586 -34.51359) (xy 10.451821 -34.322057) (xy 10.293185 -34.125417) (xy 10.140835 -33.923868)
			(xy 9.994923 -33.71761) (xy 9.855596 -33.506848) (xy 9.722991 -33.291793) (xy 9.597242 -33.072659)
			(xy 9.478473 -32.849664) (xy 9.366802 -32.623032) (xy 9.262342 -32.392986) (xy 9.165196 -32.159758)
			(xy 9.075462 -31.92358) (xy 8.993227 -31.684686) (xy 8.918576 -31.443316) (xy 8.851581 -31.199709)
			(xy 8.79231 -30.954108) (xy 8.740821 -30.706759) (xy 8.697167 -30.457908) (xy 8.661391 -30.207802)
			(xy 8.633527 -29.956692) (xy 8.613605 -29.704828) (xy 8.601644 -29.45246) (xy 8.597656 -29.19984)
			(xy 6.661402 -29.19984) (xy 6.660015 -29.204715) (xy 6.629047 -29.284652) (xy 6.590836 -29.361391)
			(xy 6.545707 -29.434277) (xy 6.494046 -29.502688) (xy 6.436292 -29.56604) (xy 6.37294 -29.623794)
			(xy 6.304529 -29.675455) (xy 6.231643 -29.720584) (xy 6.154904 -29.758795) (xy 6.074967 -29.789763)
			(xy 5.992514 -29.813223) (xy 5.908247 -29.828975) (xy 5.822887 -29.836885) (xy 5.737161 -29.836885)
			(xy 5.651801 -29.828975) (xy 5.567534 -29.813223) (xy 5.485081 -29.789763) (xy 5.405144 -29.758795)
			(xy 5.328405 -29.720584) (xy 5.255519 -29.675455) (xy 5.187108 -29.623794) (xy 5.123756 -29.56604)
			(xy 5.066002 -29.502688) (xy 5.014341 -29.434277) (xy 4.969212 -29.361391) (xy 4.931001 -29.284652)
			(xy 4.900033 -29.204715) (xy 4.876573 -29.122262) (xy 4.860821 -29.037995) (xy 4.852911 -28.952635)
			(xy 1.27 -28.952635) (xy 1.27 -35.33902) (xy 1.270499 -35.362055) (xy 1.2788 -35.407372) (xy 1.295135 -35.45045)
			(xy 1.318968 -35.489877) (xy 1.349519 -35.524361) (xy 1.385785 -35.552774) (xy 1.426579 -35.574183)
			(xy 1.470564 -35.587888) (xy 1.516299 -35.593438) (xy 1.562286 -35.590653) (xy 1.607017 -35.579624)
			(xy 1.649026 -35.560712) (xy 1.686939 -35.534536) (xy 1.703578 -35.518598) (xy 4.852416 -32.36976)
			(xy 4.852416 -30.982412) (xy 6.707632 -30.982412) (xy 6.707632 -32.83712) (xy 5.32003 -32.83712)
			(xy 3.247535 -34.90976) (xy 6.672086 -34.90976) (xy 6.676039 -34.817945) (xy 6.687871 -34.726809)
			(xy 6.707494 -34.637028) (xy 6.734762 -34.549266) (xy 6.769473 -34.464174) (xy 6.811371 -34.38238)
			(xy 6.860146 -34.304491) (xy 6.915435 -34.231082) (xy 6.97683 -34.162699) (xy 7.043877 -34.099847)
			(xy 7.116079 -34.04299) (xy 7.1929 -33.992552) (xy 7.273774 -33.948903) (xy 7.3581 -33.912369) (xy 7.445255 -33.883219)
			(xy 7.534593 -33.861669) (xy 7.625453 -33.847879) (xy 7.717162 -33.841951) (xy 7.809041 -33.843928)
			(xy 7.90041 -33.853796) (xy 7.990592 -33.871483) (xy 8.07892 -33.896856) (xy 8.16474 -33.929729)
			(xy 8.247417 -33.969857) (xy 8.326337 -34.016944) (xy 8.400918 -34.070642) (xy 8.470607 -34.130551)
			(xy 8.534887 -34.19623) (xy 8.593284 -34.267192) (xy 8.645364 -34.34291) (xy 8.690742 -34.422826)
			(xy 8.729082 -34.506347) (xy 8.7601 -34.592854) (xy 8.783568 -34.681708) (xy 8.799309 -34.77225)
			(xy 8.80721 -34.86381) (xy 8.807704 -34.90976) (xy 8.80721 -34.95571) (xy 8.799309 -35.04727) (xy 8.783568 -35.137812)
			(xy 8.7601 -35.226666) (xy 8.729082 -35.313173) (xy 8.690742 -35.396694) (xy 8.645364 -35.47661)
			(xy 8.593284 -35.552328) (xy 8.534887 -35.62329) (xy 8.470607 -35.688969) (xy 8.400918 -35.748878)
			(xy 8.326337 -35.802576) (xy 8.247417 -35.849663) (xy 8.16474 -35.889791) (xy 8.07892 -35.922664)
			(xy 7.990592 -35.948037) (xy 7.90041 -35.965724) (xy 7.809041 -35.975592) (xy 7.717162 -35.977569)
			(xy 7.625453 -35.971641) (xy 7.534593 -35.957851) (xy 7.445255 -35.936301) (xy 7.3581 -35.907151)
			(xy 7.273774 -35.870617) (xy 7.1929 -35.826968) (xy 7.116079 -35.77653) (xy 7.043877 -35.719673)
			(xy 6.97683 -35.656821) (xy 6.915435 -35.588438) (xy 6.860146 -35.515029) (xy 6.811371 -35.43714)
			(xy 6.769473 -35.355346) (xy 6.734762 -35.270254) (xy 6.707494 -35.182492) (xy 6.687871 -35.092711)
			(xy 6.676039 -35.001575) (xy 6.672086 -34.90976) (xy 3.247535 -34.90976) (xy 1.678432 -36.478972)
			(xy 1.678432 -42.291) (xy 5.5306 -42.291) (xy 5.534631 -42.161434) (xy 5.54671 -42.03237) (xy 5.566789 -41.904306)
			(xy 5.594791 -41.777739) (xy 5.630608 -41.653156) (xy 5.6741 -41.531042) (xy 5.7251 -41.411868) (xy 5.783411 -41.296095)
			(xy 5.848806 -41.184171) (xy 5.921033 -41.076529) (xy 5.999813 -40.973586) (xy 6.08484 -40.87574)
			(xy 6.175785 -40.783368) (xy 6.272297 -40.69683) (xy 6.374003 -40.616459) (xy 6.480509 -40.542567)
			(xy 6.591402 -40.475439) (xy 6.706254 -40.415335) (xy 6.824621 -40.362488) (xy 6.946044 -40.317101)
			(xy 7.070054 -40.279352) (xy 7.196171 -40.249385) (xy 7.323907 -40.227316) (xy 7.452768 -40.213232)
			(xy 7.582255 -40.207186) (xy 7.711868 -40.209202) (xy 7.841104 -40.219272) (xy 7.969465 -40.237357)
			(xy 8.096453 -40.263387) (xy 8.221577 -40.297262) (xy 8.344353 -40.33885) (xy 8.464306 -40.387991)
			(xy 8.580971 -40.444494) (xy 8.693899 -40.508141) (xy 8.802651 -40.578685) (xy 8.906807 -40.655854)
			(xy 9.005964 -40.739349) (xy 9.099738 -40.828847) (xy 9.187767 -40.924002) (xy 9.26971 -41.024445)
			(xy 9.345249 -41.129788) (xy 9.414094 -41.239624) (xy 9.475977 -41.353528) (xy 9.530658 -41.471058)
			(xy 9.577928 -41.591761) (xy 9.617601 -41.715169) (xy 9.649526 -41.840805) (xy 9.673578 -41.968182)
			(xy 9.689665 -42.096808) (xy 9.697724 -42.226186) (xy 9.698228 -42.291) (xy 9.697724 -42.355814)
			(xy 9.689665 -42.485192) (xy 9.673578 -42.613818) (xy 9.649526 -42.741195) (xy 9.617601 -42.866831)
			(xy 9.577928 -42.990239) (xy 9.530658 -43.110942) (xy 9.475977 -43.228472) (xy 9.414094 -43.342376)
			(xy 9.345249 -43.452212) (xy 9.26971 -43.557555) (xy 9.233814 -43.601555) (xy 15.679156 -43.601555)
			(xy 15.679156 -43.520445) (xy 15.687106 -43.439726) (xy 15.702929 -43.360175) (xy 15.726474 -43.282559)
			(xy 15.757513 -43.207623) (xy 15.795748 -43.136091) (xy 15.84081 -43.068651) (xy 15.892265 -43.005952)
			(xy 15.949618 -42.948599) (xy 16.012317 -42.897144) (xy 16.079757 -42.852082) (xy 16.151289 -42.813847)
			(xy 16.226225 -42.782808) (xy 16.303841 -42.759263) (xy 16.383392 -42.74344) (xy 16.464111 -42.73549)
			(xy 16.545221 -42.73549) (xy 16.62594 -42.74344) (xy 16.705491 -42.759263) (xy 16.783107 -42.782808)
			(xy 16.858043 -42.813847) (xy 16.929575 -42.852082) (xy 16.997015 -42.897144) (xy 17.059714 -42.948599)
			(xy 17.117067 -43.005952) (xy 17.168522 -43.068651) (xy 17.213584 -43.136091) (xy 17.251819 -43.207623)
			(xy 17.282858 -43.282559) (xy 17.306403 -43.360175) (xy 17.322226 -43.439726) (xy 17.330176 -43.520445)
			(xy 17.330674 -43.561) (xy 17.330176 -43.601555) (xy 17.322226 -43.682274) (xy 17.306403 -43.761825)
			(xy 17.282858 -43.839441) (xy 17.251819 -43.914377) (xy 17.213584 -43.985909) (xy 17.168522 -44.053349)
			(xy 17.117067 -44.116048) (xy 17.059714 -44.173401) (xy 16.997015 -44.224856) (xy 16.929575 -44.269918)
			(xy 16.858043 -44.308153) (xy 16.783107 -44.339192) (xy 16.705491 -44.362737) (xy 16.62594 -44.37856)
			(xy 16.545221 -44.38651) (xy 16.464111 -44.38651) (xy 16.383392 -44.37856) (xy 16.303841 -44.362737)
			(xy 16.226225 -44.339192) (xy 16.151289 -44.308153) (xy 16.079757 -44.269918) (xy 16.012317 -44.224856)
			(xy 15.949618 -44.173401) (xy 15.892265 -44.116048) (xy 15.84081 -44.053349) (xy 15.795748 -43.985909)
			(xy 15.757513 -43.914377) (xy 15.726474 -43.839441) (xy 15.702929 -43.761825) (xy 15.687106 -43.682274)
			(xy 15.679156 -43.601555) (xy 9.233814 -43.601555) (xy 9.187767 -43.657998) (xy 9.099738 -43.753153)
			(xy 9.005964 -43.842651) (xy 8.906807 -43.926146) (xy 8.802651 -44.003315) (xy 8.693899 -44.073859)
			(xy 8.580971 -44.137506) (xy 8.464306 -44.194009) (xy 8.344353 -44.24315) (xy 8.221577 -44.284738)
			(xy 8.096453 -44.318613) (xy 7.969465 -44.344643) (xy 7.841104 -44.362728) (xy 7.711868 -44.372798)
			(xy 7.582255 -44.374814) (xy 7.452768 -44.368768) (xy 7.323907 -44.354684) (xy 7.196171 -44.332615)
			(xy 7.070054 -44.302648) (xy 6.946044 -44.264899) (xy 6.824621 -44.219512) (xy 6.706254 -44.166665)
			(xy 6.591402 -44.106561) (xy 6.480509 -44.039433) (xy 6.374003 -43.965541) (xy 6.272297 -43.88517)
			(xy 6.175785 -43.798632) (xy 6.08484 -43.70626) (xy 5.999813 -43.608414) (xy 5.921033 -43.505471)
			(xy 5.848806 -43.397829) (xy 5.783411 -43.285905) (xy 5.7251 -43.170132) (xy 5.6741 -43.050958) (xy 5.630608 -42.928844)
			(xy 5.594791 -42.804261) (xy 5.566789 -42.677694) (xy 5.54671 -42.54963) (xy 5.534631 -42.420566)
			(xy 5.5306 -42.291) (xy 1.678432 -42.291) (xy 1.678432 -44.871555) (xy 13.139156 -44.871555) (xy 13.139156 -44.790445)
			(xy 13.147106 -44.709726) (xy 13.162929 -44.630175) (xy 13.186474 -44.552559) (xy 13.217513 -44.477623)
			(xy 13.255748 -44.406091) (xy 13.30081 -44.338651) (xy 13.352265 -44.275952) (xy 13.409618 -44.218599)
			(xy 13.472317 -44.167144) (xy 13.539757 -44.122082) (xy 13.611289 -44.083847) (xy 13.686225 -44.052808)
			(xy 13.763841 -44.029263) (xy 13.843392 -44.01344) (xy 13.924111 -44.00549) (xy 14.005221 -44.00549)
			(xy 14.08594 -44.01344) (xy 14.165491 -44.029263) (xy 14.243107 -44.052808) (xy 14.318043 -44.083847)
			(xy 14.389575 -44.122082) (xy 14.457015 -44.167144) (xy 14.519714 -44.218599) (xy 14.577067 -44.275952)
			(xy 14.628522 -44.338651) (xy 14.673584 -44.406091) (xy 14.711819 -44.477623) (xy 14.742858 -44.552559)
			(xy 14.766403 -44.630175) (xy 14.782226 -44.709726) (xy 14.790176 -44.790445) (xy 14.790674 -44.831)
			(xy 14.790176 -44.871555) (xy 14.782226 -44.952274) (xy 14.766403 -45.031825) (xy 14.742858 -45.109441)
			(xy 14.711819 -45.184377) (xy 14.673584 -45.255909) (xy 14.628522 -45.323349) (xy 14.577067 -45.386048)
			(xy 14.519714 -45.443401) (xy 14.457015 -45.494856) (xy 14.389575 -45.539918) (xy 14.318043 -45.578153)
			(xy 14.243107 -45.609192) (xy 14.165491 -45.632737) (xy 14.08594 -45.64856) (xy 14.005221 -45.65651)
			(xy 13.924111 -45.65651) (xy 13.843392 -45.64856) (xy 13.763841 -45.632737) (xy 13.686225 -45.609192)
			(xy 13.611289 -45.578153) (xy 13.539757 -45.539918) (xy 13.472317 -45.494856) (xy 13.409618 -45.443401)
			(xy 13.352265 -45.386048) (xy 13.30081 -45.323349) (xy 13.255748 -45.255909) (xy 13.217513 -45.184377)
			(xy 13.186474 -45.109441) (xy 13.162929 -45.031825) (xy 13.147106 -44.952274) (xy 13.139156 -44.871555)
			(xy 1.678432 -44.871555) (xy 1.678432 -46.141555) (xy 15.679156 -46.141555) (xy 15.679156 -46.060445)
			(xy 15.687106 -45.979726) (xy 15.702929 -45.900175) (xy 15.726474 -45.822559) (xy 15.757513 -45.747623)
			(xy 15.795748 -45.676091) (xy 15.84081 -45.608651) (xy 15.892265 -45.545952) (xy 15.949618 -45.488599)
			(xy 16.012317 -45.437144) (xy 16.079757 -45.392082) (xy 16.151289 -45.353847) (xy 16.226225 -45.322808)
			(xy 16.303841 -45.299263) (xy 16.383392 -45.28344) (xy 16.464111 -45.27549) (xy 16.545221 -45.27549)
			(xy 16.62594 -45.28344) (xy 16.705491 -45.299263) (xy 16.783107 -45.322808) (xy 16.858043 -45.353847)
			(xy 16.929575 -45.392082) (xy 16.997015 -45.437144) (xy 17.059714 -45.488599) (xy 17.117067 -45.545952)
			(xy 17.168522 -45.608651) (xy 17.213584 -45.676091) (xy 17.251819 -45.747623) (xy 17.282858 -45.822559)
			(xy 17.306403 -45.900175) (xy 17.322226 -45.979726) (xy 17.330176 -46.060445) (xy 17.330674 -46.101)
			(xy 17.330176 -46.141555) (xy 17.322226 -46.222274) (xy 17.306403 -46.301825) (xy 17.282858 -46.379441)
			(xy 17.251819 -46.454377) (xy 17.213584 -46.525909) (xy 17.168522 -46.593349) (xy 17.117067 -46.656048)
			(xy 17.059714 -46.713401) (xy 16.997015 -46.764856) (xy 16.929575 -46.809918) (xy 16.858043 -46.848153)
			(xy 16.783107 -46.879192) (xy 16.705491 -46.902737) (xy 16.62594 -46.91856) (xy 16.545221 -46.92651)
			(xy 16.464111 -46.92651) (xy 16.383392 -46.91856) (xy 16.303841 -46.902737) (xy 16.226225 -46.879192)
			(xy 16.151289 -46.848153) (xy 16.079757 -46.809918) (xy 16.012317 -46.764856) (xy 15.949618 -46.713401)
			(xy 15.892265 -46.656048) (xy 15.84081 -46.593349) (xy 15.795748 -46.525909) (xy 15.757513 -46.454377)
			(xy 15.726474 -46.379441) (xy 15.702929 -46.301825) (xy 15.687106 -46.222274) (xy 15.679156 -46.141555)
			(xy 1.678432 -46.141555) (xy 1.678432 -47.411555) (xy 13.139156 -47.411555) (xy 13.139156 -47.330445)
			(xy 13.147106 -47.249726) (xy 13.162929 -47.170175) (xy 13.186474 -47.092559) (xy 13.217513 -47.017623)
			(xy 13.255748 -46.946091) (xy 13.30081 -46.878651) (xy 13.352265 -46.815952) (xy 13.409618 -46.758599)
			(xy 13.472317 -46.707144) (xy 13.539757 -46.662082) (xy 13.611289 -46.623847) (xy 13.686225 -46.592808)
			(xy 13.763841 -46.569263) (xy 13.843392 -46.55344) (xy 13.924111 -46.54549) (xy 14.005221 -46.54549)
			(xy 14.08594 -46.55344) (xy 14.165491 -46.569263) (xy 14.243107 -46.592808) (xy 14.318043 -46.623847)
			(xy 14.389575 -46.662082) (xy 14.457015 -46.707144) (xy 14.519714 -46.758599) (xy 14.577067 -46.815952)
			(xy 14.628522 -46.878651) (xy 14.673584 -46.946091) (xy 14.711819 -47.017623) (xy 14.742858 -47.092559)
			(xy 14.766403 -47.170175) (xy 14.782226 -47.249726) (xy 14.790176 -47.330445) (xy 14.790674 -47.371)
			(xy 14.790176 -47.411555) (xy 14.782226 -47.492274) (xy 14.766403 -47.571825) (xy 14.742858 -47.649441)
			(xy 14.711819 -47.724377) (xy 14.673584 -47.795909) (xy 14.628522 -47.863349) (xy 14.577067 -47.926048)
			(xy 14.519714 -47.983401) (xy 14.457015 -48.034856) (xy 14.389575 -48.079918) (xy 14.318043 -48.118153)
			(xy 14.243107 -48.149192) (xy 14.165491 -48.172737) (xy 14.08594 -48.18856) (xy 14.005221 -48.19651)
			(xy 13.924111 -48.19651) (xy 13.843392 -48.18856) (xy 13.763841 -48.172737) (xy 13.686225 -48.149192)
			(xy 13.611289 -48.118153) (xy 13.539757 -48.079918) (xy 13.472317 -48.034856) (xy 13.409618 -47.983401)
			(xy 13.352265 -47.926048) (xy 13.30081 -47.863349) (xy 13.255748 -47.795909) (xy 13.217513 -47.724377)
			(xy 13.186474 -47.649441) (xy 13.162929 -47.571825) (xy 13.147106 -47.492274) (xy 13.139156 -47.411555)
			(xy 1.678432 -47.411555) (xy 1.678432 -48.681555) (xy 15.679156 -48.681555) (xy 15.679156 -48.600445)
			(xy 15.687106 -48.519726) (xy 15.702929 -48.440175) (xy 15.726474 -48.362559) (xy 15.757513 -48.287623)
			(xy 15.795748 -48.216091) (xy 15.84081 -48.148651) (xy 15.892265 -48.085952) (xy 15.949618 -48.028599)
			(xy 16.012317 -47.977144) (xy 16.079757 -47.932082) (xy 16.151289 -47.893847) (xy 16.226225 -47.862808)
			(xy 16.303841 -47.839263) (xy 16.383392 -47.82344) (xy 16.464111 -47.81549) (xy 16.545221 -47.81549)
			(xy 16.62594 -47.82344) (xy 16.705491 -47.839263) (xy 16.783107 -47.862808) (xy 16.858043 -47.893847)
			(xy 16.929575 -47.932082) (xy 16.997015 -47.977144) (xy 17.059714 -48.028599) (xy 17.117067 -48.085952)
			(xy 17.168522 -48.148651) (xy 17.213584 -48.216091) (xy 17.251819 -48.287623) (xy 17.282858 -48.362559)
			(xy 17.306403 -48.440175) (xy 17.322226 -48.519726) (xy 17.330176 -48.600445) (xy 17.330674 -48.641)
			(xy 17.330176 -48.681555) (xy 17.322226 -48.762274) (xy 17.306403 -48.841825) (xy 17.282858 -48.919441)
			(xy 17.251819 -48.994377) (xy 17.213584 -49.065909) (xy 17.168522 -49.133349) (xy 17.117067 -49.196048)
			(xy 17.059714 -49.253401) (xy 16.997015 -49.304856) (xy 16.929575 -49.349918) (xy 16.858043 -49.388153)
			(xy 16.783107 -49.419192) (xy 16.705491 -49.442737) (xy 16.62594 -49.45856) (xy 16.545221 -49.46651)
			(xy 16.464111 -49.46651) (xy 16.383392 -49.45856) (xy 16.303841 -49.442737) (xy 16.226225 -49.419192)
			(xy 16.151289 -49.388153) (xy 16.079757 -49.349918) (xy 16.012317 -49.304856) (xy 15.949618 -49.253401)
			(xy 15.892265 -49.196048) (xy 15.84081 -49.133349) (xy 15.795748 -49.065909) (xy 15.757513 -48.994377)
			(xy 15.726474 -48.919441) (xy 15.702929 -48.841825) (xy 15.687106 -48.762274) (xy 15.679156 -48.681555)
			(xy 1.678432 -48.681555) (xy 1.678432 -49.951555) (xy 13.139156 -49.951555) (xy 13.139156 -49.870445)
			(xy 13.147106 -49.789726) (xy 13.162929 -49.710175) (xy 13.186474 -49.632559) (xy 13.217513 -49.557623)
			(xy 13.255748 -49.486091) (xy 13.30081 -49.418651) (xy 13.352265 -49.355952) (xy 13.409618 -49.298599)
			(xy 13.472317 -49.247144) (xy 13.539757 -49.202082) (xy 13.611289 -49.163847) (xy 13.686225 -49.132808)
			(xy 13.763841 -49.109263) (xy 13.843392 -49.09344) (xy 13.924111 -49.08549) (xy 14.005221 -49.08549)
			(xy 14.08594 -49.09344) (xy 14.165491 -49.109263) (xy 14.243107 -49.132808) (xy 14.318043 -49.163847)
			(xy 14.389575 -49.202082) (xy 14.457015 -49.247144) (xy 14.519714 -49.298599) (xy 14.577067 -49.355952)
			(xy 14.628522 -49.418651) (xy 14.673584 -49.486091) (xy 14.711819 -49.557623) (xy 14.742858 -49.632559)
			(xy 14.766403 -49.710175) (xy 14.782226 -49.789726) (xy 14.790176 -49.870445) (xy 14.790674 -49.911)
			(xy 14.790176 -49.951555) (xy 14.782226 -50.032274) (xy 14.766403 -50.111825) (xy 14.742858 -50.189441)
			(xy 14.711819 -50.264377) (xy 14.673584 -50.335909) (xy 14.628522 -50.403349) (xy 14.577067 -50.466048)
			(xy 14.519714 -50.523401) (xy 14.457015 -50.574856) (xy 14.389575 -50.619918) (xy 14.318043 -50.658153)
			(xy 14.243107 -50.689192) (xy 14.165491 -50.712737) (xy 14.08594 -50.72856) (xy 14.005221 -50.73651)
			(xy 13.924111 -50.73651) (xy 13.843392 -50.72856) (xy 13.763841 -50.712737) (xy 13.686225 -50.689192)
			(xy 13.611289 -50.658153) (xy 13.539757 -50.619918) (xy 13.472317 -50.574856) (xy 13.409618 -50.523401)
			(xy 13.352265 -50.466048) (xy 13.30081 -50.403349) (xy 13.255748 -50.335909) (xy 13.217513 -50.264377)
			(xy 13.186474 -50.189441) (xy 13.162929 -50.111825) (xy 13.147106 -50.032274) (xy 13.139156 -49.951555)
			(xy 1.678432 -49.951555) (xy 1.678432 -51.221555) (xy 15.679156 -51.221555) (xy 15.679156 -51.140445)
			(xy 15.687106 -51.059726) (xy 15.702929 -50.980175) (xy 15.726474 -50.902559) (xy 15.757513 -50.827623)
			(xy 15.795748 -50.756091) (xy 15.84081 -50.688651) (xy 15.892265 -50.625952) (xy 15.949618 -50.568599)
			(xy 16.012317 -50.517144) (xy 16.079757 -50.472082) (xy 16.151289 -50.433847) (xy 16.226225 -50.402808)
			(xy 16.303841 -50.379263) (xy 16.383392 -50.36344) (xy 16.464111 -50.35549) (xy 16.545221 -50.35549)
			(xy 16.62594 -50.36344) (xy 16.705491 -50.379263) (xy 16.783107 -50.402808) (xy 16.858043 -50.433847)
			(xy 16.929575 -50.472082) (xy 16.997015 -50.517144) (xy 17.059714 -50.568599) (xy 17.117067 -50.625952)
			(xy 17.168522 -50.688651) (xy 17.213584 -50.756091) (xy 17.251819 -50.827623) (xy 17.282858 -50.902559)
			(xy 17.306403 -50.980175) (xy 17.322226 -51.059726) (xy 17.330176 -51.140445) (xy 17.330674 -51.181)
			(xy 17.330176 -51.221555) (xy 17.322226 -51.302274) (xy 17.306403 -51.381825) (xy 17.282858 -51.459441)
			(xy 17.251819 -51.534377) (xy 17.213584 -51.605909) (xy 17.168522 -51.673349) (xy 17.117067 -51.736048)
			(xy 17.059714 -51.793401) (xy 16.997015 -51.844856) (xy 16.929575 -51.889918) (xy 16.858043 -51.928153)
			(xy 16.783107 -51.959192) (xy 16.705491 -51.982737) (xy 16.62594 -51.99856) (xy 16.545221 -52.00651)
			(xy 16.464111 -52.00651) (xy 16.383392 -51.99856) (xy 16.303841 -51.982737) (xy 16.226225 -51.959192)
			(xy 16.151289 -51.928153) (xy 16.079757 -51.889918) (xy 16.012317 -51.844856) (xy 15.949618 -51.793401)
			(xy 15.892265 -51.736048) (xy 15.84081 -51.673349) (xy 15.795748 -51.605909) (xy 15.757513 -51.534377)
			(xy 15.726474 -51.459441) (xy 15.702929 -51.381825) (xy 15.687106 -51.302274) (xy 15.679156 -51.221555)
			(xy 1.678432 -51.221555) (xy 1.678432 -51.624992) (xy 13.138912 -51.624992) (xy 14.79042 -51.624992)
			(xy 14.79042 -53.277008) (xy 13.138912 -53.277008) (xy 13.138912 -51.624992) (xy 1.678432 -51.624992)
			(xy 1.678432 -53.721) (xy 5.5306 -53.721) (xy 5.534631 -53.591434) (xy 5.54671 -53.46237) (xy 5.566789 -53.334306)
			(xy 5.594791 -53.207739) (xy 5.630608 -53.083156) (xy 5.6741 -52.961042) (xy 5.7251 -52.841868) (xy 5.783411 -52.726095)
			(xy 5.848806 -52.614171) (xy 5.921033 -52.506529) (xy 5.999813 -52.403586) (xy 6.08484 -52.30574)
			(xy 6.175785 -52.213368) (xy 6.272297 -52.12683) (xy 6.374003 -52.046459) (xy 6.480509 -51.972567)
			(xy 6.591402 -51.905439) (xy 6.706254 -51.845335) (xy 6.824621 -51.792488) (xy 6.946044 -51.747101)
			(xy 7.070054 -51.709352) (xy 7.196171 -51.679385) (xy 7.323907 -51.657316) (xy 7.452768 -51.643232)
			(xy 7.582255 -51.637186) (xy 7.711868 -51.639202) (xy 7.841104 -51.649272) (xy 7.969465 -51.667357)
			(xy 8.096453 -51.693387) (xy 8.221577 -51.727262) (xy 8.344353 -51.76885) (xy 8.464306 -51.817991)
			(xy 8.580971 -51.874494) (xy 8.693899 -51.938141) (xy 8.802651 -52.008685) (xy 8.906807 -52.085854)
			(xy 9.005964 -52.169349) (xy 9.099738 -52.258847) (xy 9.187767 -52.354002) (xy 9.26971 -52.454445)
			(xy 9.345249 -52.559788) (xy 9.414094 -52.669624) (xy 9.475977 -52.783528) (xy 9.530658 -52.901058)
			(xy 9.577928 -53.021761) (xy 9.617601 -53.145169) (xy 9.649526 -53.270805) (xy 9.673578 -53.398182)
			(xy 9.689665 -53.526808) (xy 9.697724 -53.656186) (xy 9.698228 -53.721) (xy 9.697724 -53.785814)
			(xy 9.689665 -53.915192) (xy 9.673578 -54.043818) (xy 9.649526 -54.171195) (xy 9.617601 -54.296831)
			(xy 9.577928 -54.420239) (xy 9.530658 -54.540942) (xy 9.475977 -54.658472) (xy 9.414094 -54.772376)
			(xy 9.345249 -54.882212) (xy 9.26971 -54.987555) (xy 9.187767 -55.087998) (xy 9.099738 -55.183153)
			(xy 9.005964 -55.272651) (xy 8.906807 -55.356146) (xy 8.802651 -55.433315) (xy 8.693899 -55.503859)
			(xy 8.580971 -55.567506) (xy 8.464306 -55.624009) (xy 8.344353 -55.67315) (xy 8.221577 -55.714738)
			(xy 8.096453 -55.748613) (xy 7.969465 -55.774643) (xy 7.841104 -55.792728) (xy 7.711868 -55.802798)
			(xy 7.582255 -55.804814) (xy 7.452768 -55.798768) (xy 7.323907 -55.784684) (xy 7.196171 -55.762615)
			(xy 7.070054 -55.732648) (xy 6.946044 -55.694899) (xy 6.824621 -55.649512) (xy 6.706254 -55.596665)
			(xy 6.591402 -55.536561) (xy 6.480509 -55.469433) (xy 6.374003 -55.395541) (xy 6.272297 -55.31517)
			(xy 6.175785 -55.228632) (xy 6.08484 -55.13626) (xy 5.999813 -55.038414) (xy 5.921033 -54.935471)
			(xy 5.848806 -54.827829) (xy 5.783411 -54.715905) (xy 5.7251 -54.600132) (xy 5.6741 -54.480958) (xy 5.630608 -54.358844)
			(xy 5.594791 -54.234261) (xy 5.566789 -54.107694) (xy 5.54671 -53.97963) (xy 5.534631 -53.850566)
			(xy 5.5306 -53.721) (xy 1.678432 -53.721) (xy 1.678432 -60.833) (xy 5.5306 -60.833) (xy 5.534631 -60.703434)
			(xy 5.54671 -60.57437) (xy 5.566789 -60.446306) (xy 5.594791 -60.319739) (xy 5.630608 -60.195156)
			(xy 5.6741 -60.073042) (xy 5.7251 -59.953868) (xy 5.783411 -59.838095) (xy 5.848806 -59.726171) (xy 5.921033 -59.618529)
			(xy 5.999813 -59.515586) (xy 6.08484 -59.41774) (xy 6.175785 -59.325368) (xy 6.272297 -59.23883)
			(xy 6.374003 -59.158459) (xy 6.480509 -59.084567) (xy 6.591402 -59.017439) (xy 6.706254 -58.957335)
			(xy 6.824621 -58.904488) (xy 6.946044 -58.859101) (xy 7.070054 -58.821352) (xy 7.196171 -58.791385)
			(xy 7.323907 -58.769316) (xy 7.452768 -58.755232) (xy 7.582255 -58.749186) (xy 7.711868 -58.751202)
			(xy 7.841104 -58.761272) (xy 7.969465 -58.779357) (xy 8.096453 -58.805387) (xy 8.221577 -58.839262)
			(xy 8.344353 -58.88085) (xy 8.464306 -58.929991) (xy 8.580971 -58.986494) (xy 8.693899 -59.050141)
			(xy 8.802651 -59.120685) (xy 8.906807 -59.197854) (xy 9.005964 -59.281349) (xy 9.099738 -59.370847)
			(xy 9.187767 -59.466002) (xy 9.26971 -59.566445) (xy 9.345249 -59.671788) (xy 9.414094 -59.781624)
			(xy 9.475977 -59.895528) (xy 9.530658 -60.013058) (xy 9.577928 -60.133761) (xy 9.617601 -60.257169)
			(xy 9.649526 -60.382805) (xy 9.673578 -60.510182) (xy 9.689665 -60.638808) (xy 9.697724 -60.768186)
			(xy 9.698228 -60.833) (xy 9.697724 -60.897814) (xy 9.689665 -61.027192) (xy 9.673578 -61.155818)
			(xy 9.649526 -61.283195) (xy 9.617601 -61.408831) (xy 9.577928 -61.532239) (xy 9.530658 -61.652942)
			(xy 9.475977 -61.770472) (xy 9.414094 -61.884376) (xy 9.345249 -61.994212) (xy 9.26971 -62.099555)
			(xy 9.233814 -62.143555) (xy 15.679156 -62.143555) (xy 15.679156 -62.062445) (xy 15.687106 -61.981726)
			(xy 15.702929 -61.902175) (xy 15.726474 -61.824559) (xy 15.757513 -61.749623) (xy 15.795748 -61.678091)
			(xy 15.84081 -61.610651) (xy 15.892265 -61.547952) (xy 15.949618 -61.490599) (xy 16.012317 -61.439144)
			(xy 16.079757 -61.394082) (xy 16.151289 -61.355847) (xy 16.226225 -61.324808) (xy 16.303841 -61.301263)
			(xy 16.383392 -61.28544) (xy 16.464111 -61.27749) (xy 16.545221 -61.27749) (xy 16.62594 -61.28544)
			(xy 16.705491 -61.301263) (xy 16.783107 -61.324808) (xy 16.858043 -61.355847) (xy 16.929575 -61.394082)
			(xy 16.997015 -61.439144) (xy 17.059714 -61.490599) (xy 17.117067 -61.547952) (xy 17.168522 -61.610651)
			(xy 17.213584 -61.678091) (xy 17.251819 -61.749623) (xy 17.282858 -61.824559) (xy 17.306403 -61.902175)
			(xy 17.322226 -61.981726) (xy 17.330176 -62.062445) (xy 17.330674 -62.103) (xy 17.330176 -62.143555)
			(xy 17.322226 -62.224274) (xy 17.306403 -62.303825) (xy 17.282858 -62.381441) (xy 17.251819 -62.456377)
			(xy 17.213584 -62.527909) (xy 17.168522 -62.595349) (xy 17.117067 -62.658048) (xy 17.059714 -62.715401)
			(xy 16.997015 -62.766856) (xy 16.929575 -62.811918) (xy 16.858043 -62.850153) (xy 16.783107 -62.881192)
			(xy 16.705491 -62.904737) (xy 16.62594 -62.92056) (xy 16.545221 -62.92851) (xy 16.464111 -62.92851)
			(xy 16.383392 -62.92056) (xy 16.303841 -62.904737) (xy 16.226225 -62.881192) (xy 16.151289 -62.850153)
			(xy 16.079757 -62.811918) (xy 16.012317 -62.766856) (xy 15.949618 -62.715401) (xy 15.892265 -62.658048)
			(xy 15.84081 -62.595349) (xy 15.795748 -62.527909) (xy 15.757513 -62.456377) (xy 15.726474 -62.381441)
			(xy 15.702929 -62.303825) (xy 15.687106 -62.224274) (xy 15.679156 -62.143555) (xy 9.233814 -62.143555)
			(xy 9.187767 -62.199998) (xy 9.099738 -62.295153) (xy 9.005964 -62.384651) (xy 8.906807 -62.468146)
			(xy 8.802651 -62.545315) (xy 8.693899 -62.615859) (xy 8.580971 -62.679506) (xy 8.464306 -62.736009)
			(xy 8.344353 -62.78515) (xy 8.221577 -62.826738) (xy 8.096453 -62.860613) (xy 7.969465 -62.886643)
			(xy 7.841104 -62.904728) (xy 7.711868 -62.914798) (xy 7.582255 -62.916814) (xy 7.452768 -62.910768)
			(xy 7.323907 -62.896684) (xy 7.196171 -62.874615) (xy 7.070054 -62.844648) (xy 6.946044 -62.806899)
			(xy 6.824621 -62.761512) (xy 6.706254 -62.708665) (xy 6.591402 -62.648561) (xy 6.480509 -62.581433)
			(xy 6.374003 -62.507541) (xy 6.272297 -62.42717) (xy 6.175785 -62.340632) (xy 6.08484 -62.24826)
			(xy 5.999813 -62.150414) (xy 5.921033 -62.047471) (xy 5.848806 -61.939829) (xy 5.783411 -61.827905)
			(xy 5.7251 -61.712132) (xy 5.6741 -61.592958) (xy 5.630608 -61.470844) (xy 5.594791 -61.346261) (xy 5.566789 -61.219694)
			(xy 5.54671 -61.09163) (xy 5.534631 -60.962566) (xy 5.5306 -60.833) (xy 1.678432 -60.833) (xy 1.678432 -63.413555)
			(xy 13.139156 -63.413555) (xy 13.139156 -63.332445) (xy 13.147106 -63.251726) (xy 13.162929 -63.172175)
			(xy 13.186474 -63.094559) (xy 13.217513 -63.019623) (xy 13.255748 -62.948091) (xy 13.30081 -62.880651)
			(xy 13.352265 -62.817952) (xy 13.409618 -62.760599) (xy 13.472317 -62.709144) (xy 13.539757 -62.664082)
			(xy 13.611289 -62.625847) (xy 13.686225 -62.594808) (xy 13.763841 -62.571263) (xy 13.843392 -62.55544)
			(xy 13.924111 -62.54749) (xy 14.005221 -62.54749) (xy 14.08594 -62.55544) (xy 14.165491 -62.571263)
			(xy 14.243107 -62.594808) (xy 14.318043 -62.625847) (xy 14.389575 -62.664082) (xy 14.457015 -62.709144)
			(xy 14.519714 -62.760599) (xy 14.577067 -62.817952) (xy 14.628522 -62.880651) (xy 14.673584 -62.948091)
			(xy 14.711819 -63.019623) (xy 14.742858 -63.094559) (xy 14.766403 -63.172175) (xy 14.782226 -63.251726)
			(xy 14.790176 -63.332445) (xy 14.790674 -63.373) (xy 14.790176 -63.413555) (xy 14.782226 -63.494274)
			(xy 14.766403 -63.573825) (xy 14.742858 -63.651441) (xy 14.711819 -63.726377) (xy 14.673584 -63.797909)
			(xy 14.628522 -63.865349) (xy 14.577067 -63.928048) (xy 14.519714 -63.985401) (xy 14.457015 -64.036856)
			(xy 14.389575 -64.081918) (xy 14.318043 -64.120153) (xy 14.243107 -64.151192) (xy 14.165491 -64.174737)
			(xy 14.08594 -64.19056) (xy 14.005221 -64.19851) (xy 13.924111 -64.19851) (xy 13.843392 -64.19056)
			(xy 13.763841 -64.174737) (xy 13.686225 -64.151192) (xy 13.611289 -64.120153) (xy 13.539757 -64.081918)
			(xy 13.472317 -64.036856) (xy 13.409618 -63.985401) (xy 13.352265 -63.928048) (xy 13.30081 -63.865349)
			(xy 13.255748 -63.797909) (xy 13.217513 -63.726377) (xy 13.186474 -63.651441) (xy 13.162929 -63.573825)
			(xy 13.147106 -63.494274) (xy 13.139156 -63.413555) (xy 1.678432 -63.413555) (xy 1.678432 -64.683555)
			(xy 15.679156 -64.683555) (xy 15.679156 -64.602445) (xy 15.687106 -64.521726) (xy 15.702929 -64.442175)
			(xy 15.726474 -64.364559) (xy 15.757513 -64.289623) (xy 15.795748 -64.218091) (xy 15.84081 -64.150651)
			(xy 15.892265 -64.087952) (xy 15.949618 -64.030599) (xy 16.012317 -63.979144) (xy 16.079757 -63.934082)
			(xy 16.151289 -63.895847) (xy 16.226225 -63.864808) (xy 16.303841 -63.841263) (xy 16.383392 -63.82544)
			(xy 16.464111 -63.81749) (xy 16.545221 -63.81749) (xy 16.62594 -63.82544) (xy 16.705491 -63.841263)
			(xy 16.783107 -63.864808) (xy 16.858043 -63.895847) (xy 16.929575 -63.934082) (xy 16.997015 -63.979144)
			(xy 17.059714 -64.030599) (xy 17.117067 -64.087952) (xy 17.168522 -64.150651) (xy 17.213584 -64.218091)
			(xy 17.251819 -64.289623) (xy 17.282858 -64.364559) (xy 17.306403 -64.442175) (xy 17.322226 -64.521726)
			(xy 17.330176 -64.602445) (xy 17.330674 -64.643) (xy 17.330176 -64.683555) (xy 17.322226 -64.764274)
			(xy 17.306403 -64.843825) (xy 17.282858 -64.921441) (xy 17.251819 -64.996377) (xy 17.213584 -65.067909)
			(xy 17.168522 -65.135349) (xy 17.117067 -65.198048) (xy 17.059714 -65.255401) (xy 16.997015 -65.306856)
			(xy 16.929575 -65.351918) (xy 16.858043 -65.390153) (xy 16.783107 -65.421192) (xy 16.705491 -65.444737)
			(xy 16.62594 -65.46056) (xy 16.545221 -65.46851) (xy 16.464111 -65.46851) (xy 16.383392 -65.46056)
			(xy 16.303841 -65.444737) (xy 16.226225 -65.421192) (xy 16.151289 -65.390153) (xy 16.079757 -65.351918)
			(xy 16.012317 -65.306856) (xy 15.949618 -65.255401) (xy 15.892265 -65.198048) (xy 15.84081 -65.135349)
			(xy 15.795748 -65.067909) (xy 15.757513 -64.996377) (xy 15.726474 -64.921441) (xy 15.702929 -64.843825)
			(xy 15.687106 -64.764274) (xy 15.679156 -64.683555) (xy 1.678432 -64.683555) (xy 1.678432 -65.953555)
			(xy 13.139156 -65.953555) (xy 13.139156 -65.872445) (xy 13.147106 -65.791726) (xy 13.162929 -65.712175)
			(xy 13.186474 -65.634559) (xy 13.217513 -65.559623) (xy 13.255748 -65.488091) (xy 13.30081 -65.420651)
			(xy 13.352265 -65.357952) (xy 13.409618 -65.300599) (xy 13.472317 -65.249144) (xy 13.539757 -65.204082)
			(xy 13.611289 -65.165847) (xy 13.686225 -65.134808) (xy 13.763841 -65.111263) (xy 13.843392 -65.09544)
			(xy 13.924111 -65.08749) (xy 14.005221 -65.08749) (xy 14.08594 -65.09544) (xy 14.165491 -65.111263)
			(xy 14.243107 -65.134808) (xy 14.318043 -65.165847) (xy 14.389575 -65.204082) (xy 14.457015 -65.249144)
			(xy 14.519714 -65.300599) (xy 14.577067 -65.357952) (xy 14.628522 -65.420651) (xy 14.673584 -65.488091)
			(xy 14.711819 -65.559623) (xy 14.742858 -65.634559) (xy 14.766403 -65.712175) (xy 14.782226 -65.791726)
			(xy 14.790176 -65.872445) (xy 14.790674 -65.913) (xy 14.790176 -65.953555) (xy 14.782226 -66.034274)
			(xy 14.766403 -66.113825) (xy 14.742858 -66.191441) (xy 14.711819 -66.266377) (xy 14.673584 -66.337909)
			(xy 14.628522 -66.405349) (xy 14.577067 -66.468048) (xy 14.519714 -66.525401) (xy 14.457015 -66.576856)
			(xy 14.389575 -66.621918) (xy 14.318043 -66.660153) (xy 14.243107 -66.691192) (xy 14.165491 -66.714737)
			(xy 14.08594 -66.73056) (xy 14.005221 -66.73851) (xy 13.924111 -66.73851) (xy 13.843392 -66.73056)
			(xy 13.763841 -66.714737) (xy 13.686225 -66.691192) (xy 13.611289 -66.660153) (xy 13.539757 -66.621918)
			(xy 13.472317 -66.576856) (xy 13.409618 -66.525401) (xy 13.352265 -66.468048) (xy 13.30081 -66.405349)
			(xy 13.255748 -66.337909) (xy 13.217513 -66.266377) (xy 13.186474 -66.191441) (xy 13.162929 -66.113825)
			(xy 13.147106 -66.034274) (xy 13.139156 -65.953555) (xy 1.678432 -65.953555) (xy 1.678432 -67.223555)
			(xy 15.679156 -67.223555) (xy 15.679156 -67.142445) (xy 15.687106 -67.061726) (xy 15.702929 -66.982175)
			(xy 15.726474 -66.904559) (xy 15.757513 -66.829623) (xy 15.795748 -66.758091) (xy 15.84081 -66.690651)
			(xy 15.892265 -66.627952) (xy 15.949618 -66.570599) (xy 16.012317 -66.519144) (xy 16.079757 -66.474082)
			(xy 16.151289 -66.435847) (xy 16.226225 -66.404808) (xy 16.303841 -66.381263) (xy 16.383392 -66.36544)
			(xy 16.464111 -66.35749) (xy 16.545221 -66.35749) (xy 16.62594 -66.36544) (xy 16.705491 -66.381263)
			(xy 16.783107 -66.404808) (xy 16.858043 -66.435847) (xy 16.929575 -66.474082) (xy 16.997015 -66.519144)
			(xy 17.059714 -66.570599) (xy 17.117067 -66.627952) (xy 17.168522 -66.690651) (xy 17.213584 -66.758091)
			(xy 17.251819 -66.829623) (xy 17.282858 -66.904559) (xy 17.306403 -66.982175) (xy 17.322226 -67.061726)
			(xy 17.330176 -67.142445) (xy 17.330674 -67.183) (xy 17.330176 -67.223555) (xy 17.322226 -67.304274)
			(xy 17.306403 -67.383825) (xy 17.282858 -67.461441) (xy 17.251819 -67.536377) (xy 17.213584 -67.607909)
			(xy 17.168522 -67.675349) (xy 17.117067 -67.738048) (xy 17.059714 -67.795401) (xy 16.997015 -67.846856)
			(xy 16.929575 -67.891918) (xy 16.858043 -67.930153) (xy 16.783107 -67.961192) (xy 16.705491 -67.984737)
			(xy 16.62594 -68.00056) (xy 16.545221 -68.00851) (xy 16.464111 -68.00851) (xy 16.383392 -68.00056)
			(xy 16.303841 -67.984737) (xy 16.226225 -67.961192) (xy 16.151289 -67.930153) (xy 16.079757 -67.891918)
			(xy 16.012317 -67.846856) (xy 15.949618 -67.795401) (xy 15.892265 -67.738048) (xy 15.84081 -67.675349)
			(xy 15.795748 -67.607909) (xy 15.757513 -67.536377) (xy 15.726474 -67.461441) (xy 15.702929 -67.383825)
			(xy 15.687106 -67.304274) (xy 15.679156 -67.223555) (xy 1.678432 -67.223555) (xy 1.678432 -68.493555)
			(xy 13.139156 -68.493555) (xy 13.139156 -68.412445) (xy 13.147106 -68.331726) (xy 13.162929 -68.252175)
			(xy 13.186474 -68.174559) (xy 13.217513 -68.099623) (xy 13.255748 -68.028091) (xy 13.30081 -67.960651)
			(xy 13.352265 -67.897952) (xy 13.409618 -67.840599) (xy 13.472317 -67.789144) (xy 13.539757 -67.744082)
			(xy 13.611289 -67.705847) (xy 13.686225 -67.674808) (xy 13.763841 -67.651263) (xy 13.843392 -67.63544)
			(xy 13.924111 -67.62749) (xy 14.005221 -67.62749) (xy 14.08594 -67.63544) (xy 14.165491 -67.651263)
			(xy 14.243107 -67.674808) (xy 14.318043 -67.705847) (xy 14.389575 -67.744082) (xy 14.457015 -67.789144)
			(xy 14.519714 -67.840599) (xy 14.577067 -67.897952) (xy 14.628522 -67.960651) (xy 14.673584 -68.028091)
			(xy 14.711819 -68.099623) (xy 14.742858 -68.174559) (xy 14.766403 -68.252175) (xy 14.782226 -68.331726)
			(xy 14.790176 -68.412445) (xy 14.790674 -68.453) (xy 14.790176 -68.493555) (xy 14.782226 -68.574274)
			(xy 14.766403 -68.653825) (xy 14.742858 -68.731441) (xy 14.711819 -68.806377) (xy 14.673584 -68.877909)
			(xy 14.628522 -68.945349) (xy 14.577067 -69.008048) (xy 14.519714 -69.065401) (xy 14.457015 -69.116856)
			(xy 14.389575 -69.161918) (xy 14.318043 -69.200153) (xy 14.243107 -69.231192) (xy 14.165491 -69.254737)
			(xy 14.08594 -69.27056) (xy 14.005221 -69.27851) (xy 13.924111 -69.27851) (xy 13.843392 -69.27056)
			(xy 13.763841 -69.254737) (xy 13.686225 -69.231192) (xy 13.611289 -69.200153) (xy 13.539757 -69.161918)
			(xy 13.472317 -69.116856) (xy 13.409618 -69.065401) (xy 13.352265 -69.008048) (xy 13.30081 -68.945349)
			(xy 13.255748 -68.877909) (xy 13.217513 -68.806377) (xy 13.186474 -68.731441) (xy 13.162929 -68.653825)
			(xy 13.147106 -68.574274) (xy 13.139156 -68.493555) (xy 1.678432 -68.493555) (xy 1.678432 -69.763555)
			(xy 15.679156 -69.763555) (xy 15.679156 -69.682445) (xy 15.687106 -69.601726) (xy 15.702929 -69.522175)
			(xy 15.726474 -69.444559) (xy 15.757513 -69.369623) (xy 15.795748 -69.298091) (xy 15.84081 -69.230651)
			(xy 15.892265 -69.167952) (xy 15.949618 -69.110599) (xy 16.012317 -69.059144) (xy 16.079757 -69.014082)
			(xy 16.151289 -68.975847) (xy 16.226225 -68.944808) (xy 16.303841 -68.921263) (xy 16.383392 -68.90544)
			(xy 16.464111 -68.89749) (xy 16.545221 -68.89749) (xy 16.62594 -68.90544) (xy 16.705491 -68.921263)
			(xy 16.783107 -68.944808) (xy 16.858043 -68.975847) (xy 16.929575 -69.014082) (xy 16.997015 -69.059144)
			(xy 17.059714 -69.110599) (xy 17.117067 -69.167952) (xy 17.168522 -69.230651) (xy 17.213584 -69.298091)
			(xy 17.251819 -69.369623) (xy 17.282858 -69.444559) (xy 17.306403 -69.522175) (xy 17.322226 -69.601726)
			(xy 17.330176 -69.682445) (xy 17.330674 -69.723) (xy 17.330176 -69.763555) (xy 17.322226 -69.844274)
			(xy 17.306403 -69.923825) (xy 17.282858 -70.001441) (xy 17.251819 -70.076377) (xy 17.213584 -70.147909)
			(xy 17.168522 -70.215349) (xy 17.117067 -70.278048) (xy 17.059714 -70.335401) (xy 16.997015 -70.386856)
			(xy 16.929575 -70.431918) (xy 16.858043 -70.470153) (xy 16.783107 -70.501192) (xy 16.705491 -70.524737)
			(xy 16.62594 -70.54056) (xy 16.545221 -70.54851) (xy 16.464111 -70.54851) (xy 16.383392 -70.54056)
			(xy 16.303841 -70.524737) (xy 16.226225 -70.501192) (xy 16.151289 -70.470153) (xy 16.079757 -70.431918)
			(xy 16.012317 -70.386856) (xy 15.949618 -70.335401) (xy 15.892265 -70.278048) (xy 15.84081 -70.215349)
			(xy 15.795748 -70.147909) (xy 15.757513 -70.076377) (xy 15.726474 -70.001441) (xy 15.702929 -69.923825)
			(xy 15.687106 -69.844274) (xy 15.679156 -69.763555) (xy 1.678432 -69.763555) (xy 1.678432 -70.166992)
			(xy 13.138912 -70.166992) (xy 14.79042 -70.166992) (xy 14.79042 -71.819008) (xy 13.138912 -71.819008)
			(xy 13.138912 -70.166992) (xy 1.678432 -70.166992) (xy 1.678432 -72.263) (xy 5.5306 -72.263) (xy 5.534631 -72.133434)
			(xy 5.54671 -72.00437) (xy 5.566789 -71.876306) (xy 5.594791 -71.749739) (xy 5.630608 -71.625156)
			(xy 5.6741 -71.503042) (xy 5.7251 -71.383868) (xy 5.783411 -71.268095) (xy 5.848806 -71.156171) (xy 5.921033 -71.048529)
			(xy 5.999813 -70.945586) (xy 6.08484 -70.84774) (xy 6.175785 -70.755368) (xy 6.272297 -70.66883)
			(xy 6.374003 -70.588459) (xy 6.480509 -70.514567) (xy 6.591402 -70.447439) (xy 6.706254 -70.387335)
			(xy 6.824621 -70.334488) (xy 6.946044 -70.289101) (xy 7.070054 -70.251352) (xy 7.196171 -70.221385)
			(xy 7.323907 -70.199316) (xy 7.452768 -70.185232) (xy 7.582255 -70.179186) (xy 7.711868 -70.181202)
			(xy 7.841104 -70.191272) (xy 7.969465 -70.209357) (xy 8.096453 -70.235387) (xy 8.221577 -70.269262)
			(xy 8.344353 -70.31085) (xy 8.464306 -70.359991) (xy 8.580971 -70.416494) (xy 8.693899 -70.480141)
			(xy 8.802651 -70.550685) (xy 8.906807 -70.627854) (xy 9.005964 -70.711349) (xy 9.099738 -70.800847)
			(xy 9.187767 -70.896002) (xy 9.26971 -70.996445) (xy 9.345249 -71.101788) (xy 9.414094 -71.211624)
			(xy 9.475977 -71.325528) (xy 9.530658 -71.443058) (xy 9.577928 -71.563761) (xy 9.617601 -71.687169)
			(xy 9.649526 -71.812805) (xy 9.673578 -71.940182) (xy 9.689665 -72.068808) (xy 9.697724 -72.198186)
			(xy 9.698228 -72.263) (xy 9.697724 -72.327814) (xy 9.689665 -72.457192) (xy 9.673578 -72.585818)
			(xy 9.649526 -72.713195) (xy 9.617601 -72.838831) (xy 9.577928 -72.962239) (xy 9.530658 -73.082942)
			(xy 9.475977 -73.200472) (xy 9.414094 -73.314376) (xy 9.345249 -73.424212) (xy 9.26971 -73.529555)
			(xy 9.187767 -73.629998) (xy 9.099738 -73.725153) (xy 9.005964 -73.814651) (xy 8.906807 -73.898146)
			(xy 8.802651 -73.975315) (xy 8.693899 -74.045859) (xy 8.580971 -74.109506) (xy 8.464306 -74.166009)
			(xy 8.344353 -74.21515) (xy 8.221577 -74.256738) (xy 8.096453 -74.290613) (xy 7.969465 -74.316643)
			(xy 7.841104 -74.334728) (xy 7.711868 -74.344798) (xy 7.582255 -74.346814) (xy 7.452768 -74.340768)
			(xy 7.323907 -74.326684) (xy 7.196171 -74.304615) (xy 7.070054 -74.274648) (xy 6.946044 -74.236899)
			(xy 6.824621 -74.191512) (xy 6.706254 -74.138665) (xy 6.591402 -74.078561) (xy 6.480509 -74.011433)
			(xy 6.374003 -73.937541) (xy 6.272297 -73.85717) (xy 6.175785 -73.770632) (xy 6.08484 -73.67826)
			(xy 5.999813 -73.580414) (xy 5.921033 -73.477471) (xy 5.848806 -73.369829) (xy 5.783411 -73.257905)
			(xy 5.7251 -73.142132) (xy 5.6741 -73.022958) (xy 5.630608 -72.900844) (xy 5.594791 -72.776261) (xy 5.566789 -72.649694)
			(xy 5.54671 -72.52163) (xy 5.534631 -72.392566) (xy 5.5306 -72.263) (xy 1.678432 -72.263) (xy 1.678432 -77.476858)
			(xy 6.601982 -77.476858) (xy 6.605935 -77.385043) (xy 6.617767 -77.293907) (xy 6.63739 -77.204126)
			(xy 6.664658 -77.116364) (xy 6.699369 -77.031272) (xy 6.741267 -76.949478) (xy 6.790042 -76.871589)
			(xy 6.845331 -76.79818) (xy 6.906726 -76.729797) (xy 6.973773 -76.666945) (xy 7.045975 -76.610088)
			(xy 7.122796 -76.55965) (xy 7.20367 -76.516001) (xy 7.287996 -76.479467) (xy 7.375151 -76.450317)
			(xy 7.464489 -76.428767) (xy 7.555349 -76.414977) (xy 7.647058 -76.409049) (xy 7.738937 -76.411026)
			(xy 7.830306 -76.420894) (xy 7.920488 -76.438581) (xy 8.008816 -76.463954) (xy 8.094636 -76.496827)
			(xy 8.177313 -76.536955) (xy 8.256233 -76.584042) (xy 8.330814 -76.63774) (xy 8.400503 -76.697649)
			(xy 8.464783 -76.763328) (xy 8.52318 -76.83429) (xy 8.57526 -76.910008) (xy 8.620638 -76.989924)
			(xy 8.658978 -77.073445) (xy 8.689996 -77.159952) (xy 8.713464 -77.248806) (xy 8.729205 -77.339348)
			(xy 8.737106 -77.430908) (xy 8.7376 -77.476858) (xy 8.737106 -77.522808) (xy 8.729205 -77.614368)
			(xy 8.713464 -77.70491) (xy 8.689996 -77.793764) (xy 8.658978 -77.880271) (xy 8.620638 -77.963792)
			(xy 8.57526 -78.043708) (xy 8.52318 -78.119426) (xy 8.464783 -78.190388) (xy 8.400503 -78.256067)
			(xy 8.330814 -78.315976) (xy 8.256233 -78.369674) (xy 8.177313 -78.416761) (xy 8.094636 -78.456889)
			(xy 8.008816 -78.489762) (xy 7.920488 -78.515135) (xy 7.830306 -78.532822) (xy 7.738937 -78.54269)
			(xy 7.647058 -78.544667) (xy 7.555349 -78.538739) (xy 7.464489 -78.524949) (xy 7.375151 -78.503399)
			(xy 7.287996 -78.474249) (xy 7.20367 -78.437715) (xy 7.122796 -78.394066) (xy 7.045975 -78.343628)
			(xy 6.973773 -78.286771) (xy 6.906726 -78.223919) (xy 6.845331 -78.155536) (xy 6.790042 -78.082127)
			(xy 6.741267 -78.004238) (xy 6.699369 -77.922444) (xy 6.664658 -77.837352) (xy 6.63739 -77.74959)
			(xy 6.617767 -77.659809) (xy 6.605935 -77.568673) (xy 6.601982 -77.476858) (xy 1.678432 -77.476858)
			(xy 1.678432 -80.519715) (xy 4.782807 -80.519715) (xy 4.782807 -80.433989) (xy 4.790717 -80.348629)
			(xy 4.806469 -80.264362) (xy 4.829929 -80.181909) (xy 4.860897 -80.101972) (xy 4.899108 -80.025233)
			(xy 4.944237 -79.952347) (xy 4.995898 -79.883936) (xy 5.053652 -79.820584) (xy 5.117004 -79.76283)
			(xy 5.185415 -79.711169) (xy 5.258301 -79.66604) (xy 5.33504 -79.627829) (xy 5.414977 -79.596861)
			(xy 5.49743 -79.573401) (xy 5.581697 -79.557649) (xy 5.667057 -79.549739) (xy 5.752783 -79.549739)
			(xy 5.838143 -79.557649) (xy 5.92241 -79.573401) (xy 6.004863 -79.596861) (xy 6.0848 -79.627829)
			(xy 6.161539 -79.66604) (xy 6.234425 -79.711169) (xy 6.302836 -79.76283) (xy 6.366188 -79.820584)
			(xy 6.423942 -79.883936) (xy 6.475603 -79.952347) (xy 6.520732 -80.025233) (xy 6.558943 -80.101972)
			(xy 6.589911 -80.181909) (xy 6.613371 -80.264362) (xy 6.629123 -80.348629) (xy 6.637033 -80.433989)
			(xy 6.637528 -80.476852) (xy 6.637033 -80.519715) (xy 6.629123 -80.605075) (xy 6.613371 -80.689342)
			(xy 6.589911 -80.771795) (xy 6.558943 -80.851732) (xy 6.520732 -80.928471) (xy 6.475603 -81.001357)
			(xy 6.423942 -81.069768) (xy 6.366188 -81.13312) (xy 6.302836 -81.190874) (xy 6.234425 -81.242535)
			(xy 6.161539 -81.287664) (xy 6.0848 -81.325875) (xy 6.004863 -81.356843) (xy 5.92241 -81.380303)
			(xy 5.838143 -81.396055) (xy 5.752783 -81.403965) (xy 5.667057 -81.403965) (xy 5.581697 -81.396055)
			(xy 5.49743 -81.380303) (xy 5.414977 -81.356843) (xy 5.33504 -81.325875) (xy 5.258301 -81.287664)
			(xy 5.185415 -81.242535) (xy 5.117004 -81.190874) (xy 5.053652 -81.13312) (xy 4.995898 -81.069768)
			(xy 4.944237 -81.001357) (xy 4.899108 -80.928471) (xy 4.860897 -80.851732) (xy 4.829929 -80.771795)
			(xy 4.806469 -80.689342) (xy 4.790717 -80.605075) (xy 4.782807 -80.519715) (xy 1.678432 -80.519715)
			(xy 1.678432 -85.549232) (xy 4.782312 -85.549232) (xy 6.637528 -85.549232) (xy 6.637528 -87.404448)
			(xy 4.782312 -87.404448) (xy 4.782312 -85.549232) (xy 1.678432 -85.549232) (xy 1.678432 -89.476834)
			(xy 6.601982 -89.476834) (xy 6.605935 -89.385019) (xy 6.617767 -89.293883) (xy 6.63739 -89.204102)
			(xy 6.664658 -89.11634) (xy 6.699369 -89.031248) (xy 6.741267 -88.949454) (xy 6.790042 -88.871565)
			(xy 6.845331 -88.798156) (xy 6.906726 -88.729773) (xy 6.973773 -88.666921) (xy 7.045975 -88.610064)
			(xy 7.122796 -88.559626) (xy 7.20367 -88.515977) (xy 7.287996 -88.479443) (xy 7.375151 -88.450293)
			(xy 7.464489 -88.428743) (xy 7.555349 -88.414953) (xy 7.647058 -88.409025) (xy 7.738937 -88.411002)
			(xy 7.830306 -88.42087) (xy 7.920488 -88.438557) (xy 8.008816 -88.46393) (xy 8.094636 -88.496803)
			(xy 8.177313 -88.536931) (xy 8.256233 -88.584018) (xy 8.330814 -88.637716) (xy 8.400503 -88.697625)
			(xy 8.464783 -88.763304) (xy 8.52318 -88.834266) (xy 8.57526 -88.909984) (xy 8.620638 -88.9899) (xy 8.658978 -89.073421)
			(xy 8.689996 -89.159928) (xy 8.713464 -89.248782) (xy 8.729205 -89.339324) (xy 8.737106 -89.430884)
			(xy 8.7376 -89.476834) (xy 8.737106 -89.522784) (xy 8.729205 -89.614344) (xy 8.713464 -89.704886)
			(xy 8.689996 -89.79374) (xy 8.658978 -89.880247) (xy 8.620638 -89.963768) (xy 8.57526 -90.043684)
			(xy 8.52318 -90.119402) (xy 8.464783 -90.190364) (xy 8.400503 -90.256043) (xy 8.330814 -90.315952)
			(xy 8.256233 -90.36965) (xy 8.177313 -90.416737) (xy 8.094636 -90.456865) (xy 8.008816 -90.489738)
			(xy 7.920488 -90.515111) (xy 7.830306 -90.532798) (xy 7.738937 -90.542666) (xy 7.647058 -90.544643)
			(xy 7.555349 -90.538715) (xy 7.464489 -90.524925) (xy 7.375151 -90.503375) (xy 7.287996 -90.474225)
			(xy 7.20367 -90.437691) (xy 7.122796 -90.394042) (xy 7.045975 -90.343604) (xy 6.973773 -90.286747)
			(xy 6.906726 -90.223895) (xy 6.845331 -90.155512) (xy 6.790042 -90.082103) (xy 6.741267 -90.004214)
			(xy 6.699369 -89.92242) (xy 6.664658 -89.837328) (xy 6.63739 -89.749566) (xy 6.617767 -89.659785)
			(xy 6.605935 -89.568649) (xy 6.601982 -89.476834) (xy 1.678432 -89.476834) (xy 1.678432 -95.377)
			(xy 5.5306 -95.377) (xy 5.534631 -95.247434) (xy 5.54671 -95.11837) (xy 5.566789 -94.990306) (xy 5.594791 -94.863739)
			(xy 5.630608 -94.739156) (xy 5.6741 -94.617042) (xy 5.7251 -94.497868) (xy 5.783411 -94.382095) (xy 5.848806 -94.270171)
			(xy 5.921033 -94.162529) (xy 5.999813 -94.059586) (xy 6.08484 -93.96174) (xy 6.175785 -93.869368)
			(xy 6.272297 -93.78283) (xy 6.374003 -93.702459) (xy 6.480509 -93.628567) (xy 6.591402 -93.561439)
			(xy 6.706254 -93.501335) (xy 6.824621 -93.448488) (xy 6.946044 -93.403101) (xy 7.070054 -93.365352)
			(xy 7.196171 -93.335385) (xy 7.323907 -93.313316) (xy 7.452768 -93.299232) (xy 7.582255 -93.293186)
			(xy 7.711868 -93.295202) (xy 7.841104 -93.305272) (xy 7.969465 -93.323357) (xy 8.096453 -93.349387)
			(xy 8.221577 -93.383262) (xy 8.344353 -93.42485) (xy 8.464306 -93.473991) (xy 8.580971 -93.530494)
			(xy 8.693899 -93.594141) (xy 8.802651 -93.664685) (xy 8.906807 -93.741854) (xy 9.005964 -93.825349)
			(xy 9.099738 -93.914847) (xy 9.187767 -94.010002) (xy 9.26971 -94.110445) (xy 9.345249 -94.215788)
			(xy 9.414094 -94.325624) (xy 9.475977 -94.439528) (xy 9.530658 -94.557058) (xy 9.577928 -94.677761)
			(xy 9.617601 -94.801169) (xy 9.649526 -94.926805) (xy 9.673578 -95.054182) (xy 9.689665 -95.182808)
			(xy 9.697724 -95.312186) (xy 9.698228 -95.377) (xy 9.697724 -95.441814) (xy 9.689665 -95.571192)
			(xy 9.673578 -95.699818) (xy 9.649526 -95.827195) (xy 9.617601 -95.952831) (xy 9.577928 -96.076239)
			(xy 9.530658 -96.196942) (xy 9.475977 -96.314472) (xy 9.414094 -96.428376) (xy 9.345249 -96.538212)
			(xy 9.26971 -96.643555) (xy 9.233814 -96.687555) (xy 15.679156 -96.687555) (xy 15.679156 -96.606445)
			(xy 15.687106 -96.525726) (xy 15.702929 -96.446175) (xy 15.726474 -96.368559) (xy 15.757513 -96.293623)
			(xy 15.795748 -96.222091) (xy 15.84081 -96.154651) (xy 15.892265 -96.091952) (xy 15.949618 -96.034599)
			(xy 16.012317 -95.983144) (xy 16.079757 -95.938082) (xy 16.151289 -95.899847) (xy 16.226225 -95.868808)
			(xy 16.303841 -95.845263) (xy 16.383392 -95.82944) (xy 16.464111 -95.82149) (xy 16.545221 -95.82149)
			(xy 16.62594 -95.82944) (xy 16.705491 -95.845263) (xy 16.783107 -95.868808) (xy 16.858043 -95.899847)
			(xy 16.929575 -95.938082) (xy 16.997015 -95.983144) (xy 17.059714 -96.034599) (xy 17.117067 -96.091952)
			(xy 17.168522 -96.154651) (xy 17.213584 -96.222091) (xy 17.251819 -96.293623) (xy 17.282858 -96.368559)
			(xy 17.306403 -96.446175) (xy 17.322226 -96.525726) (xy 17.330176 -96.606445) (xy 17.330674 -96.647)
			(xy 17.330176 -96.687555) (xy 17.322226 -96.768274) (xy 17.306403 -96.847825) (xy 17.282858 -96.925441)
			(xy 17.251819 -97.000377) (xy 17.213584 -97.071909) (xy 17.168522 -97.139349) (xy 17.117067 -97.202048)
			(xy 17.059714 -97.259401) (xy 16.997015 -97.310856) (xy 16.929575 -97.355918) (xy 16.858043 -97.394153)
			(xy 16.783107 -97.425192) (xy 16.705491 -97.448737) (xy 16.62594 -97.46456) (xy 16.545221 -97.47251)
			(xy 16.464111 -97.47251) (xy 16.383392 -97.46456) (xy 16.303841 -97.448737) (xy 16.226225 -97.425192)
			(xy 16.151289 -97.394153) (xy 16.079757 -97.355918) (xy 16.012317 -97.310856) (xy 15.949618 -97.259401)
			(xy 15.892265 -97.202048) (xy 15.84081 -97.139349) (xy 15.795748 -97.071909) (xy 15.757513 -97.000377)
			(xy 15.726474 -96.925441) (xy 15.702929 -96.847825) (xy 15.687106 -96.768274) (xy 15.679156 -96.687555)
			(xy 9.233814 -96.687555) (xy 9.187767 -96.743998) (xy 9.099738 -96.839153) (xy 9.005964 -96.928651)
			(xy 8.906807 -97.012146) (xy 8.802651 -97.089315) (xy 8.693899 -97.159859) (xy 8.580971 -97.223506)
			(xy 8.464306 -97.280009) (xy 8.344353 -97.32915) (xy 8.221577 -97.370738) (xy 8.096453 -97.404613)
			(xy 7.969465 -97.430643) (xy 7.841104 -97.448728) (xy 7.711868 -97.458798) (xy 7.582255 -97.460814)
			(xy 7.452768 -97.454768) (xy 7.323907 -97.440684) (xy 7.196171 -97.418615) (xy 7.070054 -97.388648)
			(xy 6.946044 -97.350899) (xy 6.824621 -97.305512) (xy 6.706254 -97.252665) (xy 6.591402 -97.192561)
			(xy 6.480509 -97.125433) (xy 6.374003 -97.051541) (xy 6.272297 -96.97117) (xy 6.175785 -96.884632)
			(xy 6.08484 -96.79226) (xy 5.999813 -96.694414) (xy 5.921033 -96.591471) (xy 5.848806 -96.483829)
			(xy 5.783411 -96.371905) (xy 5.7251 -96.256132) (xy 5.6741 -96.136958) (xy 5.630608 -96.014844) (xy 5.594791 -95.890261)
			(xy 5.566789 -95.763694) (xy 5.54671 -95.63563) (xy 5.534631 -95.506566) (xy 5.5306 -95.377) (xy 1.678432 -95.377)
			(xy 1.678432 -97.957555) (xy 13.139156 -97.957555) (xy 13.139156 -97.876445) (xy 13.147106 -97.795726)
			(xy 13.162929 -97.716175) (xy 13.186474 -97.638559) (xy 13.217513 -97.563623) (xy 13.255748 -97.492091)
			(xy 13.30081 -97.424651) (xy 13.352265 -97.361952) (xy 13.409618 -97.304599) (xy 13.472317 -97.253144)
			(xy 13.539757 -97.208082) (xy 13.611289 -97.169847) (xy 13.686225 -97.138808) (xy 13.763841 -97.115263)
			(xy 13.843392 -97.09944) (xy 13.924111 -97.09149) (xy 14.005221 -97.09149) (xy 14.08594 -97.09944)
			(xy 14.165491 -97.115263) (xy 14.243107 -97.138808) (xy 14.318043 -97.169847) (xy 14.389575 -97.208082)
			(xy 14.457015 -97.253144) (xy 14.519714 -97.304599) (xy 14.577067 -97.361952) (xy 14.628522 -97.424651)
			(xy 14.673584 -97.492091) (xy 14.711819 -97.563623) (xy 14.742858 -97.638559) (xy 14.766403 -97.716175)
			(xy 14.782226 -97.795726) (xy 14.790176 -97.876445) (xy 14.790674 -97.917) (xy 14.790176 -97.957555)
			(xy 14.782226 -98.038274) (xy 14.766403 -98.117825) (xy 14.742858 -98.195441) (xy 14.711819 -98.270377)
			(xy 14.673584 -98.341909) (xy 14.628522 -98.409349) (xy 14.577067 -98.472048) (xy 14.519714 -98.529401)
			(xy 14.457015 -98.580856) (xy 14.389575 -98.625918) (xy 14.318043 -98.664153) (xy 14.243107 -98.695192)
			(xy 14.165491 -98.718737) (xy 14.08594 -98.73456) (xy 14.005221 -98.74251) (xy 13.924111 -98.74251)
			(xy 13.843392 -98.73456) (xy 13.763841 -98.718737) (xy 13.686225 -98.695192) (xy 13.611289 -98.664153)
			(xy 13.539757 -98.625918) (xy 13.472317 -98.580856) (xy 13.409618 -98.529401) (xy 13.352265 -98.472048)
			(xy 13.30081 -98.409349) (xy 13.255748 -98.341909) (xy 13.217513 -98.270377) (xy 13.186474 -98.195441)
			(xy 13.162929 -98.117825) (xy 13.147106 -98.038274) (xy 13.139156 -97.957555) (xy 1.678432 -97.957555)
			(xy 1.678432 -99.227555) (xy 15.679156 -99.227555) (xy 15.679156 -99.146445) (xy 15.687106 -99.065726)
			(xy 15.702929 -98.986175) (xy 15.726474 -98.908559) (xy 15.757513 -98.833623) (xy 15.795748 -98.762091)
			(xy 15.84081 -98.694651) (xy 15.892265 -98.631952) (xy 15.949618 -98.574599) (xy 16.012317 -98.523144)
			(xy 16.079757 -98.478082) (xy 16.151289 -98.439847) (xy 16.226225 -98.408808) (xy 16.303841 -98.385263)
			(xy 16.383392 -98.36944) (xy 16.464111 -98.36149) (xy 16.545221 -98.36149) (xy 16.62594 -98.36944)
			(xy 16.705491 -98.385263) (xy 16.783107 -98.408808) (xy 16.858043 -98.439847) (xy 16.929575 -98.478082)
			(xy 16.997015 -98.523144) (xy 17.059714 -98.574599) (xy 17.117067 -98.631952) (xy 17.168522 -98.694651)
			(xy 17.213584 -98.762091) (xy 17.251819 -98.833623) (xy 17.282858 -98.908559) (xy 17.306403 -98.986175)
			(xy 17.322226 -99.065726) (xy 17.330176 -99.146445) (xy 17.330674 -99.187) (xy 17.330176 -99.227555)
			(xy 17.322226 -99.308274) (xy 17.306403 -99.387825) (xy 17.282858 -99.465441) (xy 17.251819 -99.540377)
			(xy 17.213584 -99.611909) (xy 17.168522 -99.679349) (xy 17.117067 -99.742048) (xy 17.059714 -99.799401)
			(xy 16.997015 -99.850856) (xy 16.929575 -99.895918) (xy 16.858043 -99.934153) (xy 16.783107 -99.965192)
			(xy 16.705491 -99.988737) (xy 16.62594 -100.00456) (xy 16.545221 -100.01251) (xy 16.464111 -100.01251)
			(xy 16.383392 -100.00456) (xy 16.303841 -99.988737) (xy 16.226225 -99.965192) (xy 16.151289 -99.934153)
			(xy 16.079757 -99.895918) (xy 16.012317 -99.850856) (xy 15.949618 -99.799401) (xy 15.892265 -99.742048)
			(xy 15.84081 -99.679349) (xy 15.795748 -99.611909) (xy 15.757513 -99.540377) (xy 15.726474 -99.465441)
			(xy 15.702929 -99.387825) (xy 15.687106 -99.308274) (xy 15.679156 -99.227555) (xy 1.678432 -99.227555)
			(xy 1.678432 -100.497555) (xy 13.139156 -100.497555) (xy 13.139156 -100.416445) (xy 13.147106 -100.335726)
			(xy 13.162929 -100.256175) (xy 13.186474 -100.178559) (xy 13.217513 -100.103623) (xy 13.255748 -100.032091)
			(xy 13.30081 -99.964651) (xy 13.352265 -99.901952) (xy 13.409618 -99.844599) (xy 13.472317 -99.793144)
			(xy 13.539757 -99.748082) (xy 13.611289 -99.709847) (xy 13.686225 -99.678808) (xy 13.763841 -99.655263)
			(xy 13.843392 -99.63944) (xy 13.924111 -99.63149) (xy 14.005221 -99.63149) (xy 14.08594 -99.63944)
			(xy 14.165491 -99.655263) (xy 14.243107 -99.678808) (xy 14.318043 -99.709847) (xy 14.389575 -99.748082)
			(xy 14.457015 -99.793144) (xy 14.519714 -99.844599) (xy 14.577067 -99.901952) (xy 14.628522 -99.964651)
			(xy 14.673584 -100.032091) (xy 14.711819 -100.103623) (xy 14.742858 -100.178559) (xy 14.766403 -100.256175)
			(xy 14.782226 -100.335726) (xy 14.790176 -100.416445) (xy 14.790674 -100.457) (xy 14.790176 -100.497555)
			(xy 14.782226 -100.578274) (xy 14.766403 -100.657825) (xy 14.742858 -100.735441) (xy 14.711819 -100.810377)
			(xy 14.673584 -100.881909) (xy 14.628522 -100.949349) (xy 14.577067 -101.012048) (xy 14.519714 -101.069401)
			(xy 14.457015 -101.120856) (xy 14.389575 -101.165918) (xy 14.318043 -101.204153) (xy 14.243107 -101.235192)
			(xy 14.165491 -101.258737) (xy 14.08594 -101.27456) (xy 14.005221 -101.28251) (xy 13.924111 -101.28251)
			(xy 13.843392 -101.27456) (xy 13.763841 -101.258737) (xy 13.686225 -101.235192) (xy 13.611289 -101.204153)
			(xy 13.539757 -101.165918) (xy 13.472317 -101.120856) (xy 13.409618 -101.069401) (xy 13.352265 -101.012048)
			(xy 13.30081 -100.949349) (xy 13.255748 -100.881909) (xy 13.217513 -100.810377) (xy 13.186474 -100.735441)
			(xy 13.162929 -100.657825) (xy 13.147106 -100.578274) (xy 13.139156 -100.497555) (xy 1.678432 -100.497555)
			(xy 1.678432 -101.767555) (xy 15.679156 -101.767555) (xy 15.679156 -101.686445) (xy 15.687106 -101.605726)
			(xy 15.702929 -101.526175) (xy 15.726474 -101.448559) (xy 15.757513 -101.373623) (xy 15.795748 -101.302091)
			(xy 15.84081 -101.234651) (xy 15.892265 -101.171952) (xy 15.949618 -101.114599) (xy 16.012317 -101.063144)
			(xy 16.079757 -101.018082) (xy 16.151289 -100.979847) (xy 16.226225 -100.948808) (xy 16.303841 -100.925263)
			(xy 16.383392 -100.90944) (xy 16.464111 -100.90149) (xy 16.545221 -100.90149) (xy 16.62594 -100.90944)
			(xy 16.705491 -100.925263) (xy 16.783107 -100.948808) (xy 16.858043 -100.979847) (xy 16.929575 -101.018082)
			(xy 16.997015 -101.063144) (xy 17.059714 -101.114599) (xy 17.117067 -101.171952) (xy 17.168522 -101.234651)
			(xy 17.213584 -101.302091) (xy 17.251819 -101.373623) (xy 17.282858 -101.448559) (xy 17.306403 -101.526175)
			(xy 17.322226 -101.605726) (xy 17.330176 -101.686445) (xy 17.330674 -101.727) (xy 17.330176 -101.767555)
			(xy 17.322226 -101.848274) (xy 17.306403 -101.927825) (xy 17.282858 -102.005441) (xy 17.251819 -102.080377)
			(xy 17.213584 -102.151909) (xy 17.168522 -102.219349) (xy 17.117067 -102.282048) (xy 17.059714 -102.339401)
			(xy 16.997015 -102.390856) (xy 16.929575 -102.435918) (xy 16.858043 -102.474153) (xy 16.783107 -102.505192)
			(xy 16.705491 -102.528737) (xy 16.62594 -102.54456) (xy 16.545221 -102.55251) (xy 16.464111 -102.55251)
			(xy 16.383392 -102.54456) (xy 16.303841 -102.528737) (xy 16.226225 -102.505192) (xy 16.151289 -102.474153)
			(xy 16.079757 -102.435918) (xy 16.012317 -102.390856) (xy 15.949618 -102.339401) (xy 15.892265 -102.282048)
			(xy 15.84081 -102.219349) (xy 15.795748 -102.151909) (xy 15.757513 -102.080377) (xy 15.726474 -102.005441)
			(xy 15.702929 -101.927825) (xy 15.687106 -101.848274) (xy 15.679156 -101.767555) (xy 1.678432 -101.767555)
			(xy 1.678432 -103.037555) (xy 13.139156 -103.037555) (xy 13.139156 -102.956445) (xy 13.147106 -102.875726)
			(xy 13.162929 -102.796175) (xy 13.186474 -102.718559) (xy 13.217513 -102.643623) (xy 13.255748 -102.572091)
			(xy 13.30081 -102.504651) (xy 13.352265 -102.441952) (xy 13.409618 -102.384599) (xy 13.472317 -102.333144)
			(xy 13.539757 -102.288082) (xy 13.611289 -102.249847) (xy 13.686225 -102.218808) (xy 13.763841 -102.195263)
			(xy 13.843392 -102.17944) (xy 13.924111 -102.17149) (xy 14.005221 -102.17149) (xy 14.08594 -102.17944)
			(xy 14.165491 -102.195263) (xy 14.243107 -102.218808) (xy 14.318043 -102.249847) (xy 14.389575 -102.288082)
			(xy 14.457015 -102.333144) (xy 14.519714 -102.384599) (xy 14.577067 -102.441952) (xy 14.628522 -102.504651)
			(xy 14.673584 -102.572091) (xy 14.711819 -102.643623) (xy 14.742858 -102.718559) (xy 14.766403 -102.796175)
			(xy 14.782226 -102.875726) (xy 14.790176 -102.956445) (xy 14.790674 -102.997) (xy 14.790176 -103.037555)
			(xy 14.782226 -103.118274) (xy 14.766403 -103.197825) (xy 14.742858 -103.275441) (xy 14.711819 -103.350377)
			(xy 14.673584 -103.421909) (xy 14.628522 -103.489349) (xy 14.577067 -103.552048) (xy 14.519714 -103.609401)
			(xy 14.457015 -103.660856) (xy 14.389575 -103.705918) (xy 14.318043 -103.744153) (xy 14.243107 -103.775192)
			(xy 14.165491 -103.798737) (xy 14.08594 -103.81456) (xy 14.005221 -103.82251) (xy 13.924111 -103.82251)
			(xy 13.843392 -103.81456) (xy 13.763841 -103.798737) (xy 13.686225 -103.775192) (xy 13.611289 -103.744153)
			(xy 13.539757 -103.705918) (xy 13.472317 -103.660856) (xy 13.409618 -103.609401) (xy 13.352265 -103.552048)
			(xy 13.30081 -103.489349) (xy 13.255748 -103.421909) (xy 13.217513 -103.350377) (xy 13.186474 -103.275441)
			(xy 13.162929 -103.197825) (xy 13.147106 -103.118274) (xy 13.139156 -103.037555) (xy 1.678432 -103.037555)
			(xy 1.678432 -104.307555) (xy 15.679156 -104.307555) (xy 15.679156 -104.226445) (xy 15.687106 -104.145726)
			(xy 15.702929 -104.066175) (xy 15.726474 -103.988559) (xy 15.757513 -103.913623) (xy 15.795748 -103.842091)
			(xy 15.84081 -103.774651) (xy 15.892265 -103.711952) (xy 15.949618 -103.654599) (xy 16.012317 -103.603144)
			(xy 16.079757 -103.558082) (xy 16.151289 -103.519847) (xy 16.226225 -103.488808) (xy 16.303841 -103.465263)
			(xy 16.383392 -103.44944) (xy 16.464111 -103.44149) (xy 16.545221 -103.44149) (xy 16.62594 -103.44944)
			(xy 16.705491 -103.465263) (xy 16.783107 -103.488808) (xy 16.858043 -103.519847) (xy 16.929575 -103.558082)
			(xy 16.997015 -103.603144) (xy 17.059714 -103.654599) (xy 17.117067 -103.711952) (xy 17.168522 -103.774651)
			(xy 17.213584 -103.842091) (xy 17.251819 -103.913623) (xy 17.282858 -103.988559) (xy 17.306403 -104.066175)
			(xy 17.322226 -104.145726) (xy 17.330176 -104.226445) (xy 17.330674 -104.267) (xy 17.330176 -104.307555)
			(xy 17.322226 -104.388274) (xy 17.306403 -104.467825) (xy 17.282858 -104.545441) (xy 17.251819 -104.620377)
			(xy 17.213584 -104.691909) (xy 17.168522 -104.759349) (xy 17.117067 -104.822048) (xy 17.059714 -104.879401)
			(xy 16.997015 -104.930856) (xy 16.929575 -104.975918) (xy 16.858043 -105.014153) (xy 16.783107 -105.045192)
			(xy 16.705491 -105.068737) (xy 16.62594 -105.08456) (xy 16.545221 -105.09251) (xy 16.464111 -105.09251)
			(xy 16.383392 -105.08456) (xy 16.303841 -105.068737) (xy 16.226225 -105.045192) (xy 16.151289 -105.014153)
			(xy 16.079757 -104.975918) (xy 16.012317 -104.930856) (xy 15.949618 -104.879401) (xy 15.892265 -104.822048)
			(xy 15.84081 -104.759349) (xy 15.795748 -104.691909) (xy 15.757513 -104.620377) (xy 15.726474 -104.545441)
			(xy 15.702929 -104.467825) (xy 15.687106 -104.388274) (xy 15.679156 -104.307555) (xy 1.678432 -104.307555)
			(xy 1.678432 -104.710992) (xy 13.138912 -104.710992) (xy 14.79042 -104.710992) (xy 14.79042 -106.363008)
			(xy 13.138912 -106.363008) (xy 13.138912 -104.710992) (xy 1.678432 -104.710992) (xy 1.678432 -106.807)
			(xy 5.5306 -106.807) (xy 5.534631 -106.677434) (xy 5.54671 -106.54837) (xy 5.566789 -106.420306)
			(xy 5.594791 -106.293739) (xy 5.630608 -106.169156) (xy 5.6741 -106.047042) (xy 5.7251 -105.927868)
			(xy 5.783411 -105.812095) (xy 5.848806 -105.700171) (xy 5.921033 -105.592529) (xy 5.999813 -105.489586)
			(xy 6.08484 -105.39174) (xy 6.175785 -105.299368) (xy 6.272297 -105.21283) (xy 6.374003 -105.132459)
			(xy 6.480509 -105.058567) (xy 6.591402 -104.991439) (xy 6.706254 -104.931335) (xy 6.824621 -104.878488)
			(xy 6.946044 -104.833101) (xy 7.070054 -104.795352) (xy 7.196171 -104.765385) (xy 7.323907 -104.743316)
			(xy 7.452768 -104.729232) (xy 7.582255 -104.723186) (xy 7.711868 -104.725202) (xy 7.841104 -104.735272)
			(xy 7.969465 -104.753357) (xy 8.096453 -104.779387) (xy 8.221577 -104.813262) (xy 8.344353 -104.85485)
			(xy 8.464306 -104.903991) (xy 8.580971 -104.960494) (xy 8.693899 -105.024141) (xy 8.802651 -105.094685)
			(xy 8.906807 -105.171854) (xy 9.005964 -105.255349) (xy 9.099738 -105.344847) (xy 9.187767 -105.440002)
			(xy 9.26971 -105.540445) (xy 9.345249 -105.645788) (xy 9.414094 -105.755624) (xy 9.475977 -105.869528)
			(xy 9.530658 -105.987058) (xy 9.577928 -106.107761) (xy 9.617601 -106.231169) (xy 9.649526 -106.356805)
			(xy 9.673578 -106.484182) (xy 9.689665 -106.612808) (xy 9.697724 -106.742186) (xy 9.698228 -106.807)
			(xy 9.697724 -106.871814) (xy 9.689665 -107.001192) (xy 9.673578 -107.129818) (xy 9.649526 -107.257195)
			(xy 9.617601 -107.382831) (xy 9.577928 -107.506239) (xy 9.530658 -107.626942) (xy 9.475977 -107.744472)
			(xy 9.414094 -107.858376) (xy 9.345249 -107.968212) (xy 9.26971 -108.073555) (xy 9.187767 -108.173998)
			(xy 9.099738 -108.269153) (xy 9.005964 -108.358651) (xy 8.906807 -108.442146) (xy 8.802651 -108.519315)
			(xy 8.693899 -108.589859) (xy 8.580971 -108.653506) (xy 8.464306 -108.710009) (xy 8.344353 -108.75915)
			(xy 8.221577 -108.800738) (xy 8.096453 -108.834613) (xy 7.969465 -108.860643) (xy 7.841104 -108.878728)
			(xy 7.711868 -108.888798) (xy 7.582255 -108.890814) (xy 7.452768 -108.884768) (xy 7.323907 -108.870684)
			(xy 7.196171 -108.848615) (xy 7.070054 -108.818648) (xy 6.946044 -108.780899) (xy 6.824621 -108.735512)
			(xy 6.706254 -108.682665) (xy 6.591402 -108.622561) (xy 6.480509 -108.555433) (xy 6.374003 -108.481541)
			(xy 6.272297 -108.40117) (xy 6.175785 -108.314632) (xy 6.08484 -108.22226) (xy 5.999813 -108.124414)
			(xy 5.921033 -108.021471) (xy 5.848806 -107.913829) (xy 5.783411 -107.801905) (xy 5.7251 -107.686132)
			(xy 5.6741 -107.566958) (xy 5.630608 -107.444844) (xy 5.594791 -107.320261) (xy 5.566789 -107.193694)
			(xy 5.54671 -107.06563) (xy 5.534631 -106.936566) (xy 5.5306 -106.807) (xy 1.678432 -106.807) (xy 1.678432 -118.09984)
			(xy 8.597656 -118.09984) (xy 8.601644 -117.84722) (xy 8.613605 -117.594852) (xy 8.633527 -117.342988)
			(xy 8.661391 -117.091878) (xy 8.697167 -116.841772) (xy 8.740821 -116.592921) (xy 8.79231 -116.345572)
			(xy 8.851581 -116.099971) (xy 8.918576 -115.856364) (xy 8.993227 -115.614994) (xy 9.075462 -115.3761)
			(xy 9.165196 -115.139922) (xy 9.262342 -114.906694) (xy 9.366802 -114.676648) (xy 9.478473 -114.450016)
			(xy 9.597242 -114.227021) (xy 9.722991 -114.007887) (xy 9.855596 -113.792832) (xy 9.994923 -113.58207)
			(xy 10.140835 -113.375812) (xy 10.293185 -113.174263) (xy 10.451821 -112.977623) (xy 10.616586 -112.78609)
			(xy 10.787316 -112.599853) (xy 10.96384 -112.419099) (xy 11.145982 -112.244008) (xy 11.33356 -112.074754)
			(xy 11.526388 -111.911505) (xy 11.724273 -111.754426) (xy 11.927019 -111.603671) (xy 12.134423 -111.459393)
			(xy 12.346278 -111.321733) (xy 12.562373 -111.19083) (xy 12.782493 -111.066814) (xy 13.006418 -110.949809)
			(xy 13.233925 -110.839931) (xy 13.464787 -110.73729) (xy 13.698775 -110.641988) (xy 13.935654 -110.554121)
			(xy 14.17519 -110.473774) (xy 14.417142 -110.40103) (xy 14.66127 -110.33596) (xy 14.907331 -110.27863)
			(xy 15.155079 -110.229096) (xy 15.404267 -110.187407) (xy 15.654647 -110.153606) (xy 15.905969 -110.127725)
			(xy 16.157983 -110.109792) (xy 16.410437 -110.099823) (xy 16.663081 -110.097829) (xy 16.915661 -110.103811)
			(xy 17.167927 -110.117764) (xy 17.419626 -110.139674) (xy 17.670509 -110.169518) (xy 17.920324 -110.207268)
			(xy 18.168823 -110.252885) (xy 18.415758 -110.306324) (xy 18.660883 -110.367532) (xy 18.903953 -110.436447)
			(xy 19.144727 -110.513002) (xy 19.382964 -110.597119) (xy 19.618427 -110.688716) (xy 19.850881 -110.7877)
			(xy 20.080095 -110.893972) (xy 20.305839 -111.007428) (xy 20.527889 -111.127953) (xy 20.746023 -111.255429)
			(xy 20.960025 -111.389727) (xy 21.169681 -111.530713) (xy 21.374781 -111.678248) (xy 21.575121 -111.832184)
			(xy 21.770502 -111.992368) (xy 21.960729 -112.15864) (xy 22.145612 -112.330835) (xy 22.324968 -112.508779)
			(xy 22.498616 -112.692298) (xy 22.666384 -112.881206) (xy 22.828105 -113.075317) (xy 22.983618 -113.274436)
			(xy 23.132767 -113.478365) (xy 23.275404 -113.686901) (xy 23.411387 -113.899836) (xy 23.54058 -114.116958)
			(xy 23.662855 -114.33805) (xy 23.778089 -114.562891) (xy 23.886168 -114.791259) (xy 23.986983 -115.022924)
			(xy 24.080435 -115.257657) (xy 24.16643 -115.495222) (xy 24.244883 -115.735384) (xy 24.315715 -115.977903)
			(xy 24.378856 -116.222538) (xy 24.434243 -116.469043) (xy 24.48182 -116.717174) (xy 24.52154 -116.966684)
			(xy 24.553364 -117.217323) (xy 24.57726 -117.468841) (xy 24.593204 -117.720989) (xy 24.601179 -117.973514)
			(xy 24.601678 -118.09984) (xy 24.601179 -118.226166) (xy 24.593204 -118.478691) (xy 24.57726 -118.730839)
			(xy 24.553364 -118.982357) (xy 24.52154 -119.232996) (xy 24.48182 -119.482506) (xy 24.434243 -119.730637)
			(xy 24.378856 -119.977142) (xy 24.315715 -120.221777) (xy 24.244883 -120.464296) (xy 24.16643 -120.704458)
			(xy 24.080435 -120.942023) (xy 23.986983 -121.176756) (xy 23.886168 -121.408421) (xy 23.778089 -121.636789)
			(xy 23.662855 -121.86163) (xy 23.54058 -122.082722) (xy 23.411387 -122.299844) (xy 23.275404 -122.512779)
			(xy 23.132767 -122.721315) (xy 22.983618 -122.925244) (xy 22.828105 -123.124363) (xy 22.666384 -123.318474)
			(xy 22.498616 -123.507382) (xy 22.324968 -123.690901) (xy 22.145612 -123.868845) (xy 21.960729 -124.04104)
			(xy 21.770502 -124.207312) (xy 21.575121 -124.367496) (xy 21.374781 -124.521432) (xy 21.169681 -124.668967)
			(xy 20.960025 -124.809953) (xy 20.746023 -124.944251) (xy 20.527889 -125.071727) (xy 20.305839 -125.192252)
			(xy 20.080095 -125.305708) (xy 19.850881 -125.41198) (xy 19.618427 -125.510964) (xy 19.382964 -125.602561)
			(xy 19.144727 -125.686678) (xy 18.903953 -125.763233) (xy 18.660883 -125.832148) (xy 18.415758 -125.893356)
			(xy 18.168823 -125.946795) (xy 17.920324 -125.992412) (xy 17.670509 -126.030162) (xy 17.419626 -126.060006)
			(xy 17.167927 -126.081916) (xy 16.915661 -126.095869) (xy 16.663081 -126.101851) (xy 16.410437 -126.099857)
			(xy 16.157983 -126.089888) (xy 15.905969 -126.071955) (xy 15.654647 -126.046074) (xy 15.404267 -126.012273)
			(xy 15.155079 -125.970584) (xy 14.907331 -125.92105) (xy 14.66127 -125.86372) (xy 14.417142 -125.79865)
			(xy 14.17519 -125.725906) (xy 13.935654 -125.645559) (xy 13.698775 -125.557692) (xy 13.464787 -125.46239)
			(xy 13.233925 -125.359749) (xy 13.006418 -125.249871) (xy 12.782493 -125.132866) (xy 12.562373 -125.00885)
			(xy 12.346278 -124.877947) (xy 12.134423 -124.740287) (xy 11.927019 -124.596009) (xy 11.724273 -124.445254)
			(xy 11.526388 -124.288175) (xy 11.33356 -124.124926) (xy 11.145982 -123.955672) (xy 10.96384 -123.780581)
			(xy 10.787316 -123.599827) (xy 10.616586 -123.41359) (xy 10.451821 -123.222057) (xy 10.293185 -123.025417)
			(xy 10.140835 -122.823868) (xy 9.994923 -122.61761) (xy 9.855596 -122.406848) (xy 9.722991 -122.191793)
			(xy 9.597242 -121.972659) (xy 9.478473 -121.749664) (xy 9.366802 -121.523032) (xy 9.262342 -121.292986)
			(xy 9.165196 -121.059758) (xy 9.075462 -120.82358) (xy 8.993227 -120.584686) (xy 8.918576 -120.343316)
			(xy 8.851581 -120.099709) (xy 8.79231 -119.854108) (xy 8.740821 -119.606759) (xy 8.697167 -119.357908)
			(xy 8.661391 -119.107802) (xy 8.633527 -118.856692) (xy 8.613605 -118.604828) (xy 8.601644 -118.35246)
			(xy 8.597656 -118.09984) (xy 1.678432 -118.09984) (xy 1.678432 -130.115994) (xy 2.786253 -130.115994)
			(xy 2.788413 -130.037049) (xy 2.79846 -129.958716) (xy 2.816293 -129.881781) (xy 2.841733 -129.807016)
			(xy 2.874524 -129.735171) (xy 2.914339 -129.666966) (xy 2.960777 -129.603087) (xy 3.013372 -129.544174)
			(xy 3.042158 -129.51714) (xy 3.054795 -129.504855) (xy 3.073358 -129.474913) (xy 3.082997 -129.441029)
			(xy 3.08356 -129.423414) (xy 3.08356 -127.893572) (xy 3.032506 -127.842518) (xy 3.032506 -127.024892)
			(xy 3.007106 -126.99111) (xy 2.987922 -126.964632) (xy 2.95578 -126.907691) (xy 2.931205 -126.847098)
			(xy 2.914603 -126.783854) (xy 2.90625 -126.719004) (xy 2.90576 -126.68631) (xy 2.90576 -125.974094)
			(xy 2.906261 -125.942149) (xy 2.914269 -125.878763) (xy 2.930158 -125.81688) (xy 2.953677 -125.757476)
			(xy 2.984457 -125.701489) (xy 3.02201 -125.6498) (xy 3.065746 -125.603226) (xy 3.114974 -125.562501)
			(xy 3.168919 -125.528267) (xy 3.226728 -125.501064) (xy 3.287491 -125.481321) (xy 3.35025 -125.469349)
			(xy 3.414014 -125.465338) (xy 3.477778 -125.469349) (xy 3.540537 -125.481321) (xy 3.6013 -125.501064)
			(xy 3.659109 -125.528267) (xy 3.713054 -125.562501) (xy 3.762282 -125.603226) (xy 3.806018 -125.6498)
			(xy 3.843571 -125.701489) (xy 3.874351 -125.757476) (xy 3.89787 -125.81688) (xy 3.913759 -125.878763)
			(xy 3.921767 -125.942149) (xy 3.922268 -125.974094) (xy 3.922268 -126.68631) (xy 3.921757 -126.719003)
			(xy 3.913408 -126.783853) (xy 3.896812 -126.847097) (xy 3.872242 -126.90769) (xy 3.840104 -126.964632)
			(xy 3.820922 -126.99111) (xy 3.795522 -127.024892) (xy 3.795522 -127.842518) (xy 3.744468 -127.893572)
			(xy 3.744468 -128.57438) (xy 10.22629 -128.57438) (xy 10.22629 -128.471588) (xy 10.234355 -128.369114)
			(xy 10.250435 -128.267589) (xy 10.274431 -128.167638) (xy 10.306196 -128.069878) (xy 10.345532 -127.974911)
			(xy 10.392198 -127.883324) (xy 10.445906 -127.79568) (xy 10.506325 -127.71252) (xy 10.573083 -127.634357)
			(xy 10.645767 -127.561673) (xy 10.72393 -127.494915) (xy 10.80709 -127.434496) (xy 10.894734 -127.380788)
			(xy 10.986321 -127.334122) (xy 11.081288 -127.294786) (xy 11.179048 -127.263021) (xy 11.278999 -127.239025)
			(xy 11.380524 -127.222945) (xy 11.482998 -127.21488) (xy 11.58579 -127.21488) (xy 11.688264 -127.222945)
			(xy 11.789789 -127.239025) (xy 11.88974 -127.263021) (xy 11.9875 -127.294786) (xy 12.082467 -127.334122)
			(xy 12.174054 -127.380788) (xy 12.261698 -127.434496) (xy 12.344858 -127.494915) (xy 12.423021 -127.561673)
			(xy 12.495705 -127.634357) (xy 12.562463 -127.71252) (xy 12.622882 -127.79568) (xy 12.67659 -127.883324)
			(xy 12.723256 -127.974911) (xy 12.762592 -128.069878) (xy 12.794357 -128.167638) (xy 12.818353 -128.267589)
			(xy 12.834433 -128.369114) (xy 12.842498 -128.471588) (xy 12.843002 -128.522984) (xy 12.842498 -128.57438)
			(xy 12.834433 -128.676854) (xy 12.818353 -128.778379) (xy 12.794357 -128.87833) (xy 12.762592 -128.97609)
			(xy 12.723256 -129.071057) (xy 12.67659 -129.162644) (xy 12.622882 -129.250288) (xy 12.562463 -129.333448)
			(xy 12.495705 -129.411611) (xy 12.423021 -129.484295) (xy 12.344858 -129.551053) (xy 12.261698 -129.611472)
			(xy 12.174054 -129.66518) (xy 12.082467 -129.711846) (xy 11.9875 -129.751182) (xy 11.88974 -129.782947)
			(xy 11.789789 -129.806943) (xy 11.688264 -129.823023) (xy 11.58579 -129.831088) (xy 11.482998 -129.831088)
			(xy 11.380524 -129.823023) (xy 11.278999 -129.806943) (xy 11.179048 -129.782947) (xy 11.081288 -129.751182)
			(xy 10.986321 -129.711846) (xy 10.894734 -129.66518) (xy 10.80709 -129.611472) (xy 10.72393 -129.551053)
			(xy 10.645767 -129.484295) (xy 10.573083 -129.411611) (xy 10.506325 -129.333448) (xy 10.445906 -129.250288)
			(xy 10.392198 -129.162644) (xy 10.345532 -129.071057) (xy 10.306196 -128.97609) (xy 10.274431 -128.87833)
			(xy 10.250435 -128.778379) (xy 10.234355 -128.676854) (xy 10.22629 -128.57438) (xy 3.744468 -128.57438)
			(xy 3.744468 -129.273554) (xy 3.791712 -129.339594) (xy 3.83032 -129.352802) (xy 3.867512 -129.366077)
			(xy 3.939269 -129.399062) (xy 4.007366 -129.43906) (xy 4.07112 -129.485669) (xy 4.129892 -129.538422)
			(xy 4.183091 -129.59679) (xy 4.230185 -129.660188) (xy 4.2707 -129.727978) (xy 4.30423 -129.799481)
			(xy 4.330438 -129.873981) (xy 4.349063 -129.950728) (xy 4.359916 -130.028953) (xy 4.36289 -130.107872)
			(xy 4.357953 -130.186692) (xy 4.345156 -130.264624) (xy 4.324627 -130.340883) (xy 4.296573 -130.414707)
			(xy 4.261273 -130.485354) (xy 4.219084 -130.552115) (xy 4.170427 -130.614321) (xy 4.115792 -130.671347)
			(xy 4.055725 -130.722621) (xy 4.021918 -130.746068) (xy 5.677649 -130.746068) (xy 5.677649 -130.619932)
			(xy 5.685569 -130.494044) (xy 5.701379 -130.368902) (xy 5.725014 -130.244999) (xy 5.756383 -130.122826)
			(xy 5.795361 -130.002863) (xy 5.841795 -129.885584) (xy 5.895502 -129.771452) (xy 5.956269 -129.660917)
			(xy 6.023856 -129.554417) (xy 6.097997 -129.45237) (xy 6.1784 -129.35518) (xy 6.264746 -129.26323)
			(xy 6.356696 -129.176884) (xy 6.453886 -129.096481) (xy 6.555933 -129.02234) (xy 6.662433 -128.954753)
			(xy 6.772968 -128.893986) (xy 6.8871 -128.840279) (xy 7.004379 -128.793845) (xy 7.124342 -128.754867)
			(xy 7.246515 -128.723498) (xy 7.370418 -128.699863) (xy 7.49556 -128.684053) (xy 7.621448 -128.676133)
			(xy 7.747584 -128.676133) (xy 7.873472 -128.684053) (xy 7.998614 -128.699863) (xy 8.122517 -128.723498)
			(xy 8.24469 -128.754867) (xy 8.364653 -128.793845) (xy 8.481932 -128.840279) (xy 8.596064 -128.893986)
			(xy 8.706599 -128.954753) (xy 8.813099 -129.02234) (xy 8.915146 -129.096481) (xy 9.012336 -129.176884)
			(xy 9.104286 -129.26323) (xy 9.190632 -129.35518) (xy 9.271035 -129.45237) (xy 9.345176 -129.554417)
			(xy 9.412763 -129.660917) (xy 9.47353 -129.771452) (xy 9.527237 -129.885584) (xy 9.573671 -130.002863)
			(xy 9.612649 -130.122826) (xy 9.644018 -130.244999) (xy 9.667653 -130.368902) (xy 9.683463 -130.494044)
			(xy 9.691383 -130.619932) (xy 9.691878 -130.683) (xy 9.691383 -130.746068) (xy 9.683463 -130.871956)
			(xy 9.667653 -130.997098) (xy 9.644018 -131.121001) (xy 9.612649 -131.243174) (xy 9.573671 -131.363137)
			(xy 9.527237 -131.480416) (xy 9.47353 -131.594548) (xy 9.412763 -131.705083) (xy 9.345176 -131.811583)
			(xy 9.271035 -131.91363) (xy 9.205429 -131.992933) (xy 15.787113 -131.992933) (xy 15.787113 -131.913067)
			(xy 15.795193 -131.833612) (xy 15.81127 -131.755382) (xy 15.835179 -131.67918) (xy 15.866674 -131.605787)
			(xy 15.905433 -131.535957) (xy 15.951057 -131.470407) (xy 16.003079 -131.409808) (xy 16.060964 -131.354784)
			(xy 16.12412 -131.305898) (xy 16.191897 -131.263652) (xy 16.2636 -131.22848) (xy 16.338494 -131.200743)
			(xy 16.415809 -131.180724) (xy 16.494753 -131.168631) (xy 16.574516 -131.164586) (xy 16.654279 -131.168631)
			(xy 16.733223 -131.180724) (xy 16.810538 -131.200743) (xy 16.885432 -131.22848) (xy 16.957135 -131.263652)
			(xy 17.024912 -131.305898) (xy 17.088068 -131.354784) (xy 17.145953 -131.409808) (xy 17.197975 -131.470407)
			(xy 17.243599 -131.535957) (xy 17.282358 -131.605787) (xy 17.313853 -131.67918) (xy 17.337762 -131.755382)
			(xy 17.353839 -131.833612) (xy 17.361919 -131.913067) (xy 17.362424 -131.953) (xy 17.361919 -131.992933)
			(xy 17.353839 -132.072388) (xy 17.337762 -132.150618) (xy 17.313853 -132.22682) (xy 17.282358 -132.300213)
			(xy 17.243599 -132.370043) (xy 17.197975 -132.435593) (xy 17.145953 -132.496192) (xy 17.088068 -132.551216)
			(xy 17.024912 -132.600102) (xy 16.957135 -132.642348) (xy 16.885432 -132.67752) (xy 16.810538 -132.705257)
			(xy 16.733223 -132.725276) (xy 16.654279 -132.737369) (xy 16.574516 -132.741415) (xy 16.494753 -132.737369)
			(xy 16.415809 -132.725276) (xy 16.338494 -132.705257) (xy 16.2636 -132.67752) (xy 16.191897 -132.642348)
			(xy 16.12412 -132.600102) (xy 16.060964 -132.551216) (xy 16.003079 -132.496192) (xy 15.951057 -132.435593)
			(xy 15.905433 -132.370043) (xy 15.866674 -132.300213) (xy 15.835179 -132.22682) (xy 15.81127 -132.150618)
			(xy 15.795193 -132.072388) (xy 15.787113 -131.992933) (xy 9.205429 -131.992933) (xy 9.190632 -132.01082)
			(xy 9.104286 -132.10277) (xy 9.012336 -132.189116) (xy 8.915146 -132.269519) (xy 8.813099 -132.34366)
			(xy 8.706599 -132.411247) (xy 8.596064 -132.472014) (xy 8.481932 -132.525721) (xy 8.364653 -132.572155)
			(xy 8.24469 -132.611133) (xy 8.122517 -132.642502) (xy 7.998614 -132.666137) (xy 7.873472 -132.681947)
			(xy 7.747584 -132.689867) (xy 7.621448 -132.689867) (xy 7.49556 -132.681947) (xy 7.370418 -132.666137)
			(xy 7.246515 -132.642502) (xy 7.124342 -132.611133) (xy 7.004379 -132.572155) (xy 6.8871 -132.525721)
			(xy 6.772968 -132.472014) (xy 6.662433 -132.411247) (xy 6.555933 -132.34366) (xy 6.453886 -132.269519)
			(xy 6.356696 -132.189116) (xy 6.264746 -132.10277) (xy 6.1784 -132.01082) (xy 6.097997 -131.91363)
			(xy 6.023856 -131.811583) (xy 5.956269 -131.705083) (xy 5.895502 -131.594548) (xy 5.841795 -131.480416)
			(xy 5.795361 -131.363137) (xy 5.756383 -131.243174) (xy 5.725014 -131.121001) (xy 5.701379 -130.997098)
			(xy 5.685569 -130.871956) (xy 5.677649 -130.746068) (xy 4.021918 -130.746068) (xy 3.990831 -130.767629)
			(xy 3.921759 -130.80592) (xy 3.849204 -130.837108) (xy 3.773892 -130.860882) (xy 3.69658 -130.877002)
			(xy 3.618044 -130.885307) (xy 3.53907 -130.885714) (xy 3.460452 -130.878219) (xy 3.382978 -130.862896)
			(xy 3.307425 -130.839899) (xy 3.234552 -130.80946) (xy 3.16509 -130.771883) (xy 3.099735 -130.727546)
			(xy 3.039144 -130.676893) (xy 2.983924 -130.620433) (xy 2.934629 -130.558732) (xy 2.891753 -130.492409)
			(xy 2.855728 -130.42213) (xy 2.826914 -130.348599) (xy 2.805601 -130.272555) (xy 2.792002 -130.19476)
			(xy 2.786253 -130.115994) (xy 1.678432 -130.115994) (xy 1.678432 -132.627933) (xy 2.787139 -132.627933)
			(xy 2.787139 -132.548067) (xy 2.795219 -132.468612) (xy 2.811296 -132.390382) (xy 2.835205 -132.31418)
			(xy 2.8667 -132.240787) (xy 2.905459 -132.170957) (xy 2.951083 -132.105407) (xy 3.003105 -132.044808)
			(xy 3.06099 -131.989784) (xy 3.124146 -131.940898) (xy 3.191923 -131.898652) (xy 3.263626 -131.86348)
			(xy 3.33852 -131.835743) (xy 3.415835 -131.815724) (xy 3.494779 -131.803631) (xy 3.574542 -131.799586)
			(xy 3.654305 -131.803631) (xy 3.733249 -131.815724) (xy 3.810564 -131.835743) (xy 3.885458 -131.86348)
			(xy 3.957161 -131.898652) (xy 4.024938 -131.940898) (xy 4.088094 -131.989784) (xy 4.145979 -132.044808)
			(xy 4.198001 -132.105407) (xy 4.243625 -132.170957) (xy 4.282384 -132.240787) (xy 4.313879 -132.31418)
			(xy 4.337788 -132.390382) (xy 4.353865 -132.468612) (xy 4.361945 -132.548067) (xy 4.36245 -132.588)
			(xy 4.361945 -132.627933) (xy 4.353865 -132.707388) (xy 4.337788 -132.785618) (xy 4.313879 -132.86182)
			(xy 4.282384 -132.935213) (xy 4.243625 -133.005043) (xy 4.198001 -133.070593) (xy 4.145979 -133.131192)
			(xy 4.088094 -133.186216) (xy 4.024938 -133.235102) (xy 3.980288 -133.262933) (xy 13.247113 -133.262933)
			(xy 13.247113 -133.183067) (xy 13.255193 -133.103612) (xy 13.27127 -133.025382) (xy 13.295179 -132.94918)
			(xy 13.326674 -132.875787) (xy 13.365433 -132.805957) (xy 13.411057 -132.740407) (xy 13.463079 -132.679808)
			(xy 13.520964 -132.624784) (xy 13.58412 -132.575898) (xy 13.651897 -132.533652) (xy 13.7236 -132.49848)
			(xy 13.798494 -132.470743) (xy 13.875809 -132.450724) (xy 13.954753 -132.438631) (xy 14.034516 -132.434586)
			(xy 14.114279 -132.438631) (xy 14.193223 -132.450724) (xy 14.270538 -132.470743) (xy 14.345432 -132.49848)
			(xy 14.417135 -132.533652) (xy 14.484912 -132.575898) (xy 14.548068 -132.624784) (xy 14.605953 -132.679808)
			(xy 14.657975 -132.740407) (xy 14.703599 -132.805957) (xy 14.742358 -132.875787) (xy 14.773853 -132.94918)
			(xy 14.797762 -133.025382) (xy 14.813839 -133.103612) (xy 14.821919 -133.183067) (xy 14.822424 -133.223)
			(xy 14.821919 -133.262933) (xy 14.813839 -133.342388) (xy 14.797762 -133.420618) (xy 14.773853 -133.49682)
			(xy 14.742358 -133.570213) (xy 14.703599 -133.640043) (xy 14.657975 -133.705593) (xy 14.605953 -133.766192)
			(xy 14.548068 -133.821216) (xy 14.484912 -133.870102) (xy 14.417135 -133.912348) (xy 14.345432 -133.94752)
			(xy 14.270538 -133.975257) (xy 14.193223 -133.995276) (xy 14.114279 -134.007369) (xy 14.034516 -134.011415)
			(xy 13.954753 -134.007369) (xy 13.875809 -133.995276) (xy 13.798494 -133.975257) (xy 13.7236 -133.94752)
			(xy 13.651897 -133.912348) (xy 13.58412 -133.870102) (xy 13.520964 -133.821216) (xy 13.463079 -133.766192)
			(xy 13.411057 -133.705593) (xy 13.365433 -133.640043) (xy 13.326674 -133.570213) (xy 13.295179 -133.49682)
			(xy 13.27127 -133.420618) (xy 13.255193 -133.342388) (xy 13.247113 -133.262933) (xy 3.980288 -133.262933)
			(xy 3.957161 -133.277348) (xy 3.885458 -133.31252) (xy 3.810564 -133.340257) (xy 3.733249 -133.360276)
			(xy 3.654305 -133.372369) (xy 3.574542 -133.376415) (xy 3.494779 -133.372369) (xy 3.415835 -133.360276)
			(xy 3.33852 -133.340257) (xy 3.263626 -133.31252) (xy 3.191923 -133.277348) (xy 3.124146 -133.235102)
			(xy 3.06099 -133.186216) (xy 3.003105 -133.131192) (xy 2.951083 -133.070593) (xy 2.905459 -133.005043)
			(xy 2.8667 -132.935213) (xy 2.835205 -132.86182) (xy 2.811296 -132.785618) (xy 2.795219 -132.707388)
			(xy 2.787139 -132.627933) (xy 1.678432 -132.627933) (xy 1.678432 -134.532933) (xy 15.787113 -134.532933)
			(xy 15.787113 -134.453067) (xy 15.795193 -134.373612) (xy 15.81127 -134.295382) (xy 15.835179 -134.21918)
			(xy 15.866674 -134.145787) (xy 15.905433 -134.075957) (xy 15.951057 -134.010407) (xy 16.003079 -133.949808)
			(xy 16.060964 -133.894784) (xy 16.12412 -133.845898) (xy 16.191897 -133.803652) (xy 16.2636 -133.76848)
			(xy 16.338494 -133.740743) (xy 16.415809 -133.720724) (xy 16.494753 -133.708631) (xy 16.574516 -133.704586)
			(xy 16.654279 -133.708631) (xy 16.733223 -133.720724) (xy 16.810538 -133.740743) (xy 16.885432 -133.76848)
			(xy 16.957135 -133.803652) (xy 17.024912 -133.845898) (xy 17.088068 -133.894784) (xy 17.145953 -133.949808)
			(xy 17.197975 -134.010407) (xy 17.243599 -134.075957) (xy 17.282358 -134.145787) (xy 17.313853 -134.21918)
			(xy 17.337762 -134.295382) (xy 17.353839 -134.373612) (xy 17.361919 -134.453067) (xy 17.362424 -134.493)
			(xy 17.361919 -134.532933) (xy 17.353839 -134.612388) (xy 17.337762 -134.690618) (xy 17.313853 -134.76682)
			(xy 17.282358 -134.840213) (xy 17.243599 -134.910043) (xy 17.197975 -134.975593) (xy 17.145953 -135.036192)
			(xy 17.088068 -135.091216) (xy 17.024912 -135.140102) (xy 16.957135 -135.182348) (xy 16.885432 -135.21752)
			(xy 16.810538 -135.245257) (xy 16.733223 -135.265276) (xy 16.654279 -135.277369) (xy 16.574516 -135.281415)
			(xy 16.494753 -135.277369) (xy 16.415809 -135.265276) (xy 16.338494 -135.245257) (xy 16.2636 -135.21752)
			(xy 16.191897 -135.182348) (xy 16.12412 -135.140102) (xy 16.060964 -135.091216) (xy 16.003079 -135.036192)
			(xy 15.951057 -134.975593) (xy 15.905433 -134.910043) (xy 15.866674 -134.840213) (xy 15.835179 -134.76682)
			(xy 15.81127 -134.690618) (xy 15.795193 -134.612388) (xy 15.787113 -134.532933) (xy 1.678432 -134.532933)
			(xy 1.678432 -135.802933) (xy 13.247113 -135.802933) (xy 13.247113 -135.723067) (xy 13.255193 -135.643612)
			(xy 13.27127 -135.565382) (xy 13.295179 -135.48918) (xy 13.326674 -135.415787) (xy 13.365433 -135.345957)
			(xy 13.411057 -135.280407) (xy 13.463079 -135.219808) (xy 13.520964 -135.164784) (xy 13.58412 -135.115898)
			(xy 13.651897 -135.073652) (xy 13.7236 -135.03848) (xy 13.798494 -135.010743) (xy 13.875809 -134.990724)
			(xy 13.954753 -134.978631) (xy 14.034516 -134.974586) (xy 14.114279 -134.978631) (xy 14.193223 -134.990724)
			(xy 14.270538 -135.010743) (xy 14.345432 -135.03848) (xy 14.417135 -135.073652) (xy 14.484912 -135.115898)
			(xy 14.548068 -135.164784) (xy 14.605953 -135.219808) (xy 14.657975 -135.280407) (xy 14.703599 -135.345957)
			(xy 14.742358 -135.415787) (xy 14.773853 -135.48918) (xy 14.797762 -135.565382) (xy 14.813839 -135.643612)
			(xy 14.821919 -135.723067) (xy 14.822424 -135.763) (xy 14.821919 -135.802933) (xy 14.813839 -135.882388)
			(xy 14.797762 -135.960618) (xy 14.773853 -136.03682) (xy 14.742358 -136.110213) (xy 14.703599 -136.180043)
			(xy 14.657975 -136.245593) (xy 14.605953 -136.306192) (xy 14.548068 -136.361216) (xy 14.484912 -136.410102)
			(xy 14.417135 -136.452348) (xy 14.345432 -136.48752) (xy 14.270538 -136.515257) (xy 14.193223 -136.535276)
			(xy 14.114279 -136.547369) (xy 14.034516 -136.551415) (xy 13.954753 -136.547369) (xy 13.875809 -136.535276)
			(xy 13.798494 -136.515257) (xy 13.7236 -136.48752) (xy 13.651897 -136.452348) (xy 13.58412 -136.410102)
			(xy 13.520964 -136.361216) (xy 13.463079 -136.306192) (xy 13.411057 -136.245593) (xy 13.365433 -136.180043)
			(xy 13.326674 -136.110213) (xy 13.295179 -136.03682) (xy 13.27127 -135.960618) (xy 13.255193 -135.882388)
			(xy 13.247113 -135.802933) (xy 1.678432 -135.802933) (xy 1.678432 -137.072933) (xy 15.787113 -137.072933)
			(xy 15.787113 -136.993067) (xy 15.795193 -136.913612) (xy 15.81127 -136.835382) (xy 15.835179 -136.75918)
			(xy 15.866674 -136.685787) (xy 15.905433 -136.615957) (xy 15.951057 -136.550407) (xy 16.003079 -136.489808)
			(xy 16.060964 -136.434784) (xy 16.12412 -136.385898) (xy 16.191897 -136.343652) (xy 16.2636 -136.30848)
			(xy 16.338494 -136.280743) (xy 16.415809 -136.260724) (xy 16.494753 -136.248631) (xy 16.574516 -136.244586)
			(xy 16.654279 -136.248631) (xy 16.733223 -136.260724) (xy 16.810538 -136.280743) (xy 16.885432 -136.30848)
			(xy 16.957135 -136.343652) (xy 17.024912 -136.385898) (xy 17.088068 -136.434784) (xy 17.145953 -136.489808)
			(xy 17.197975 -136.550407) (xy 17.243599 -136.615957) (xy 17.282358 -136.685787) (xy 17.313853 -136.75918)
			(xy 17.337762 -136.835382) (xy 17.353839 -136.913612) (xy 17.361919 -136.993067) (xy 17.362424 -137.033)
			(xy 17.361919 -137.072933) (xy 17.353839 -137.152388) (xy 17.337762 -137.230618) (xy 17.313853 -137.30682)
			(xy 17.282358 -137.380213) (xy 17.243599 -137.450043) (xy 17.197975 -137.515593) (xy 17.145953 -137.576192)
			(xy 17.088068 -137.631216) (xy 17.024912 -137.680102) (xy 16.957135 -137.722348) (xy 16.885432 -137.75752)
			(xy 16.810538 -137.785257) (xy 16.733223 -137.805276) (xy 16.654279 -137.817369) (xy 16.574516 -137.821415)
			(xy 16.494753 -137.817369) (xy 16.415809 -137.805276) (xy 16.338494 -137.785257) (xy 16.2636 -137.75752)
			(xy 16.191897 -137.722348) (xy 16.12412 -137.680102) (xy 16.060964 -137.631216) (xy 16.003079 -137.576192)
			(xy 15.951057 -137.515593) (xy 15.905433 -137.450043) (xy 15.866674 -137.380213) (xy 15.835179 -137.30682)
			(xy 15.81127 -137.230618) (xy 15.795193 -137.152388) (xy 15.787113 -137.072933) (xy 1.678432 -137.072933)
			(xy 1.678432 -138.342933) (xy 13.247113 -138.342933) (xy 13.247113 -138.263067) (xy 13.255193 -138.183612)
			(xy 13.27127 -138.105382) (xy 13.295179 -138.02918) (xy 13.326674 -137.955787) (xy 13.365433 -137.885957)
			(xy 13.411057 -137.820407) (xy 13.463079 -137.759808) (xy 13.520964 -137.704784) (xy 13.58412 -137.655898)
			(xy 13.651897 -137.613652) (xy 13.7236 -137.57848) (xy 13.798494 -137.550743) (xy 13.875809 -137.530724)
			(xy 13.954753 -137.518631) (xy 14.034516 -137.514586) (xy 14.114279 -137.518631) (xy 14.193223 -137.530724)
			(xy 14.270538 -137.550743) (xy 14.345432 -137.57848) (xy 14.417135 -137.613652) (xy 14.484912 -137.655898)
			(xy 14.548068 -137.704784) (xy 14.605953 -137.759808) (xy 14.657975 -137.820407) (xy 14.703599 -137.885957)
			(xy 14.742358 -137.955787) (xy 14.773853 -138.02918) (xy 14.797762 -138.105382) (xy 14.813839 -138.183612)
			(xy 14.821919 -138.263067) (xy 14.822424 -138.303) (xy 14.821919 -138.342933) (xy 14.813839 -138.422388)
			(xy 14.797762 -138.500618) (xy 14.773853 -138.57682) (xy 14.742358 -138.650213) (xy 14.703599 -138.720043)
			(xy 14.657975 -138.785593) (xy 14.605953 -138.846192) (xy 14.548068 -138.901216) (xy 14.484912 -138.950102)
			(xy 14.417135 -138.992348) (xy 14.345432 -139.02752) (xy 14.270538 -139.055257) (xy 14.193223 -139.075276)
			(xy 14.114279 -139.087369) (xy 14.034516 -139.091415) (xy 13.954753 -139.087369) (xy 13.875809 -139.075276)
			(xy 13.798494 -139.055257) (xy 13.7236 -139.02752) (xy 13.651897 -138.992348) (xy 13.58412 -138.950102)
			(xy 13.520964 -138.901216) (xy 13.463079 -138.846192) (xy 13.411057 -138.785593) (xy 13.365433 -138.720043)
			(xy 13.326674 -138.650213) (xy 13.295179 -138.57682) (xy 13.27127 -138.500618) (xy 13.255193 -138.422388)
			(xy 13.247113 -138.342933) (xy 1.678432 -138.342933) (xy 1.678432 -143.742664) (xy 2.125472 -143.742664)
			(xy 2.125472 -141.18971) (xy 2.804668 -140.51026) (xy 2.822194 -140.444728) (xy 2.813558 -140.411708)
			(xy 2.803775 -140.373264) (xy 2.791068 -140.294955) (xy 2.786295 -140.215766) (xy 2.789506 -140.136498)
			(xy 2.800669 -140.057954) (xy 2.81967 -139.98093) (xy 2.846316 -139.906206) (xy 2.880338 -139.834538)
			(xy 2.921391 -139.766653) (xy 2.96906 -139.703239) (xy 3.022861 -139.644937) (xy 3.08225 -139.592337)
			(xy 3.146625 -139.545974) (xy 3.215334 -139.506315) (xy 3.287681 -139.473764) (xy 3.362934 -139.448649)
			(xy 3.44033 -139.431226) (xy 3.519085 -139.42167) (xy 3.598402 -139.420078) (xy 3.677478 -139.426467)
			(xy 3.75551 -139.440771) (xy 3.83171 -139.462847) (xy 3.905305 -139.492469) (xy 3.97555 -139.529339)
			(xy 4.041733 -139.573082) (xy 4.090541 -139.612933) (xy 15.787113 -139.612933) (xy 15.787113 -139.533067)
			(xy 15.795193 -139.453612) (xy 15.81127 -139.375382) (xy 15.835179 -139.29918) (xy 15.866674 -139.225787)
			(xy 15.905433 -139.155957) (xy 15.951057 -139.090407) (xy 16.003079 -139.029808) (xy 16.060964 -138.974784)
			(xy 16.12412 -138.925898) (xy 16.191897 -138.883652) (xy 16.2636 -138.84848) (xy 16.338494 -138.820743)
			(xy 16.415809 -138.800724) (xy 16.494753 -138.788631) (xy 16.574516 -138.784586) (xy 16.654279 -138.788631)
			(xy 16.733223 -138.800724) (xy 16.810538 -138.820743) (xy 16.885432 -138.84848) (xy 16.957135 -138.883652)
			(xy 17.024912 -138.925898) (xy 17.088068 -138.974784) (xy 17.145953 -139.029808) (xy 17.197975 -139.090407)
			(xy 17.243599 -139.155957) (xy 17.282358 -139.225787) (xy 17.313853 -139.29918) (xy 17.337762 -139.375382)
			(xy 17.353839 -139.453612) (xy 17.361919 -139.533067) (xy 17.362424 -139.573) (xy 17.361919 -139.612933)
			(xy 17.353839 -139.692388) (xy 17.337762 -139.770618) (xy 17.313853 -139.84682) (xy 17.282358 -139.920213)
			(xy 17.243599 -139.990043) (xy 17.197975 -140.055593) (xy 17.145953 -140.116192) (xy 17.088068 -140.171216)
			(xy 17.024912 -140.220102) (xy 16.957135 -140.262348) (xy 16.885432 -140.29752) (xy 16.810538 -140.325257)
			(xy 16.733223 -140.345276) (xy 16.654279 -140.357369) (xy 16.574516 -140.361415) (xy 16.494753 -140.357369)
			(xy 16.415809 -140.345276) (xy 16.338494 -140.325257) (xy 16.2636 -140.29752) (xy 16.191897 -140.262348)
			(xy 16.12412 -140.220102) (xy 16.060964 -140.171216) (xy 16.003079 -140.116192) (xy 15.951057 -140.055593)
			(xy 15.905433 -139.990043) (xy 15.866674 -139.920213) (xy 15.835179 -139.84682) (xy 15.81127 -139.770618)
			(xy 15.795193 -139.692388) (xy 15.787113 -139.612933) (xy 4.090541 -139.612933) (xy 4.103185 -139.623257)
			(xy 4.159282 -139.679353) (xy 4.209456 -139.740805) (xy 4.2532 -139.806988) (xy 4.29007 -139.877232)
			(xy 4.319693 -139.950827) (xy 4.341768 -140.027027) (xy 4.346913 -140.055092) (xy 13.246608 -140.055092)
			(xy 14.822424 -140.055092) (xy 14.822424 -141.630908) (xy 13.246608 -141.630908) (xy 13.246608 -140.055092)
			(xy 4.346913 -140.055092) (xy 4.356073 -140.10506) (xy 4.362462 -140.184135) (xy 4.36087 -140.263452)
			(xy 4.351314 -140.342208) (xy 4.333891 -140.419604) (xy 4.308777 -140.494856) (xy 4.276226 -140.567204)
			(xy 4.236568 -140.635913) (xy 4.190204 -140.700288) (xy 4.137605 -140.759677) (xy 4.079303 -140.813479)
			(xy 4.015889 -140.861148) (xy 3.948004 -140.902201) (xy 3.876336 -140.936223) (xy 3.801612 -140.96287)
			(xy 3.724588 -140.981871) (xy 3.646045 -140.993033) (xy 3.566777 -140.996245) (xy 3.487587 -140.991473)
			(xy 3.409279 -140.978765) (xy 3.370834 -140.968984) (xy 3.337814 -140.960348) (xy 3.272282 -140.977874)
			(xy 2.78638 -141.463522) (xy 2.78638 -141.803374) (xy 2.786861 -141.825711) (xy 2.794689 -141.869695)
			(xy 2.810087 -141.911632) (xy 2.832581 -141.950231) (xy 2.861478 -141.984302) (xy 2.895886 -142.012795)
			(xy 2.934747 -142.034833) (xy 2.976863 -142.049736) (xy 3.020936 -142.057046) (xy 3.065608 -142.056536)
			(xy 3.109503 -142.048223) (xy 3.151268 -142.032363) (xy 3.170682 -142.021306) (xy 3.204344 -142.001776)
			(xy 3.27479 -141.968691) (xy 3.348156 -141.942713) (xy 3.423725 -141.924095) (xy 3.500761 -141.913018)
			(xy 3.578514 -141.909589) (xy 3.656227 -141.913844) (xy 3.733141 -141.925739) (xy 3.808508 -141.945159)
			(xy 3.881593 -141.971915) (xy 3.951685 -142.005746) (xy 4.018099 -142.046322) (xy 4.080189 -142.093249)
			(xy 4.137351 -142.146068) (xy 4.163989 -142.176068) (xy 5.677649 -142.176068) (xy 5.677649 -142.049932)
			(xy 5.685569 -141.924044) (xy 5.701379 -141.798902) (xy 5.725014 -141.674999) (xy 5.756383 -141.552826)
			(xy 5.795361 -141.432863) (xy 5.841795 -141.315584) (xy 5.895502 -141.201452) (xy 5.956269 -141.090917)
			(xy 6.023856 -140.984417) (xy 6.097997 -140.88237) (xy 6.1784 -140.78518) (xy 6.264746 -140.69323)
			(xy 6.356696 -140.606884) (xy 6.453886 -140.526481) (xy 6.555933 -140.45234) (xy 6.662433 -140.384753)
			(xy 6.772968 -140.323986) (xy 6.8871 -140.270279) (xy 7.004379 -140.223845) (xy 7.124342 -140.184867)
			(xy 7.246515 -140.153498) (xy 7.370418 -140.129863) (xy 7.49556 -140.114053) (xy 7.621448 -140.106133)
			(xy 7.747584 -140.106133) (xy 7.873472 -140.114053) (xy 7.998614 -140.129863) (xy 8.122517 -140.153498)
			(xy 8.24469 -140.184867) (xy 8.364653 -140.223845) (xy 8.481932 -140.270279) (xy 8.596064 -140.323986)
			(xy 8.706599 -140.384753) (xy 8.813099 -140.45234) (xy 8.915146 -140.526481) (xy 9.012336 -140.606884)
			(xy 9.104286 -140.69323) (xy 9.190632 -140.78518) (xy 9.271035 -140.88237) (xy 9.345176 -140.984417)
			(xy 9.412763 -141.090917) (xy 9.47353 -141.201452) (xy 9.527237 -141.315584) (xy 9.573671 -141.432863)
			(xy 9.612649 -141.552826) (xy 9.644018 -141.674999) (xy 9.667653 -141.798902) (xy 9.683463 -141.924044)
			(xy 9.691383 -142.049932) (xy 9.691878 -142.113) (xy 9.691383 -142.176068) (xy 9.683463 -142.301956)
			(xy 9.667653 -142.427098) (xy 9.644018 -142.551001) (xy 9.612649 -142.673174) (xy 9.573671 -142.793137)
			(xy 9.527237 -142.910416) (xy 9.47353 -143.024548) (xy 9.412763 -143.135083) (xy 9.345176 -143.241583)
			(xy 9.271035 -143.34363) (xy 9.190632 -143.44082) (xy 9.104286 -143.53277) (xy 9.012336 -143.619116)
			(xy 8.915146 -143.699519) (xy 8.813099 -143.77366) (xy 8.706599 -143.841247) (xy 8.596064 -143.902014)
			(xy 8.481932 -143.955721) (xy 8.364653 -144.002155) (xy 8.24469 -144.041133) (xy 8.122517 -144.072502)
			(xy 7.998614 -144.096137) (xy 7.873472 -144.111947) (xy 7.747584 -144.119867) (xy 7.621448 -144.119867)
			(xy 7.49556 -144.111947) (xy 7.370418 -144.096137) (xy 7.246515 -144.072502) (xy 7.124342 -144.041133)
			(xy 7.004379 -144.002155) (xy 6.8871 -143.955721) (xy 6.772968 -143.902014) (xy 6.662433 -143.841247)
			(xy 6.555933 -143.77366) (xy 6.453886 -143.699519) (xy 6.356696 -143.619116) (xy 6.264746 -143.53277)
			(xy 6.1784 -143.44082) (xy 6.097997 -143.34363) (xy 6.023856 -143.241583) (xy 5.956269 -143.135083)
			(xy 5.895502 -143.024548) (xy 5.841795 -142.910416) (xy 5.795361 -142.793137) (xy 5.756383 -142.673174)
			(xy 5.725014 -142.551001) (xy 5.701379 -142.427098) (xy 5.685569 -142.301956) (xy 5.677649 -142.176068)
			(xy 4.163989 -142.176068) (xy 4.189026 -142.204266) (xy 4.234712 -142.267275) (xy 4.273964 -142.334481)
			(xy 4.306398 -142.405229) (xy 4.331699 -142.47883) (xy 4.349621 -142.554568) (xy 4.359988 -142.631703)
			(xy 4.362701 -142.709484) (xy 4.357731 -142.787154) (xy 4.345128 -142.863956) (xy 4.335526 -142.90167)
			(xy 4.32689 -142.93469) (xy 4.344416 -143.000222) (xy 4.390644 -143.04645) (xy 4.390644 -144.324412)
			(xy 10.22629 -144.324412) (xy 10.22629 -144.22162) (xy 10.234355 -144.119146) (xy 10.250435 -144.017621)
			(xy 10.274431 -143.91767) (xy 10.306196 -143.81991) (xy 10.345532 -143.724943) (xy 10.392198 -143.633356)
			(xy 10.445906 -143.545712) (xy 10.506325 -143.462552) (xy 10.573083 -143.384389) (xy 10.645767 -143.311705)
			(xy 10.72393 -143.244947) (xy 10.80709 -143.184528) (xy 10.894734 -143.13082) (xy 10.986321 -143.084154)
			(xy 11.081288 -143.044818) (xy 11.179048 -143.013053) (xy 11.278999 -142.989057) (xy 11.380524 -142.972977)
			(xy 11.482998 -142.964912) (xy 11.58579 -142.964912) (xy 11.688264 -142.972977) (xy 11.789789 -142.989057)
			(xy 11.88974 -143.013053) (xy 11.9875 -143.044818) (xy 12.082467 -143.084154) (xy 12.174054 -143.13082)
			(xy 12.261698 -143.184528) (xy 12.344858 -143.244947) (xy 12.423021 -143.311705) (xy 12.495705 -143.384389)
			(xy 12.562463 -143.462552) (xy 12.622882 -143.545712) (xy 12.67659 -143.633356) (xy 12.723256 -143.724943)
			(xy 12.762592 -143.81991) (xy 12.794357 -143.91767) (xy 12.818353 -144.017621) (xy 12.834433 -144.119146)
			(xy 12.842498 -144.22162) (xy 12.843002 -144.273016) (xy 12.842498 -144.324412) (xy 12.834433 -144.426886)
			(xy 12.818353 -144.528411) (xy 12.794357 -144.628362) (xy 12.762592 -144.726122) (xy 12.723256 -144.821089)
			(xy 12.67659 -144.912676) (xy 12.622882 -145.00032) (xy 12.562463 -145.08348) (xy 12.495705 -145.161643)
			(xy 12.423021 -145.234327) (xy 12.344858 -145.301085) (xy 12.261698 -145.361504) (xy 12.174054 -145.415212)
			(xy 12.082467 -145.461878) (xy 11.9875 -145.501214) (xy 11.88974 -145.532979) (xy 11.789789 -145.556975)
			(xy 11.688264 -145.573055) (xy 11.58579 -145.58112) (xy 11.482998 -145.58112) (xy 11.380524 -145.573055)
			(xy 11.278999 -145.556975) (xy 11.179048 -145.532979) (xy 11.081288 -145.501214) (xy 10.986321 -145.461878)
			(xy 10.894734 -145.415212) (xy 10.80709 -145.361504) (xy 10.72393 -145.301085) (xy 10.645767 -145.234327)
			(xy 10.573083 -145.161643) (xy 10.506325 -145.08348) (xy 10.445906 -145.00032) (xy 10.392198 -144.912676)
			(xy 10.345532 -144.821089) (xy 10.306196 -144.726122) (xy 10.274431 -144.628362) (xy 10.250435 -144.528411)
			(xy 10.234355 -144.426886) (xy 10.22629 -144.324412) (xy 4.390644 -144.324412) (xy 4.390644 -145.167096)
			(xy 4.441444 -145.21815) (xy 4.441444 -146.035776) (xy 4.466844 -146.069558) (xy 4.486045 -146.096032)
			(xy 4.518222 -146.152969) (xy 4.542841 -146.213559) (xy 4.559498 -146.276802) (xy 4.567918 -146.341658)
			(xy 4.568444 -146.374358) (xy 4.568444 -147.027646) (xy 4.567942 -147.059607) (xy 4.559931 -147.123025)
			(xy 4.544034 -147.184939) (xy 4.520502 -147.244372) (xy 4.489708 -147.300387) (xy 4.452135 -147.352102)
			(xy 4.408378 -147.398699) (xy 4.359125 -147.439444) (xy 4.305154 -147.473695) (xy 4.247315 -147.500912)
			(xy 4.186522 -147.520665) (xy 4.123732 -147.532643) (xy 4.059936 -147.536657) (xy 3.99614 -147.532643)
			(xy 3.93335 -147.520665) (xy 3.872557 -147.500912) (xy 3.814718 -147.473695) (xy 3.760747 -147.439444)
			(xy 3.711494 -147.398699) (xy 3.667737 -147.352102) (xy 3.630164 -147.300387) (xy 3.59937 -147.244372)
			(xy 3.575838 -147.184939) (xy 3.559941 -147.123025) (xy 3.55193 -147.059607) (xy 3.551428 -147.027646)
			(xy 3.551428 -146.374358) (xy 3.551927 -146.341656) (xy 3.560326 -146.276792) (xy 3.576978 -146.213542)
			(xy 3.60161 -146.152953) (xy 3.633813 -146.096025) (xy 3.653028 -146.069558) (xy 3.678428 -146.035776)
			(xy 3.678428 -145.21815) (xy 3.729228 -145.167096) (xy 3.729228 -143.735044) (xy 3.728622 -143.711628)
			(xy 3.720016 -143.665593) (xy 3.703124 -143.621913) (xy 3.678518 -143.582066) (xy 3.64703 -143.547399)
			(xy 3.609725 -143.519086) (xy 3.567865 -143.498085) (xy 3.522867 -143.485106) (xy 3.499612 -143.482314)
			(xy 3.459753 -143.478038) (xy 3.381134 -143.462351) (xy 3.304515 -143.438761) (xy 3.230687 -143.40751)
			(xy 3.160415 -143.368924) (xy 3.094426 -143.323399) (xy 3.033401 -143.271409) (xy 3.005328 -143.242792)
			(xy 2.987294 -143.223742) (xy 2.939542 -143.203422) (xy 2.91338 -143.203422) (xy 2.896723 -143.203877)
			(xy 2.864544 -143.212505) (xy 2.835695 -143.229167) (xy 2.812142 -143.252729) (xy 2.795489 -143.281583)
			(xy 2.786872 -143.313764) (xy 2.78638 -143.330422) (xy 2.78638 -143.468852) (xy 3.102864 -143.785082)
			(xy 3.102864 -145.150332) (xy 3.153664 -145.201386) (xy 3.153664 -146.019012) (xy 3.179064 -146.052794)
			(xy 3.198263 -146.07927) (xy 3.230441 -146.136206) (xy 3.255061 -146.196795) (xy 3.271719 -146.260038)
			(xy 3.280138 -146.324894) (xy 3.280664 -146.357594) (xy 3.280664 -147.027392) (xy 3.280162 -147.059353)
			(xy 3.272151 -147.122771) (xy 3.256254 -147.184685) (xy 3.232722 -147.244118) (xy 3.201928 -147.300133)
			(xy 3.164355 -147.351848) (xy 3.120598 -147.398445) (xy 3.071345 -147.43919) (xy 3.017374 -147.473441)
			(xy 2.959535 -147.500658) (xy 2.898742 -147.520411) (xy 2.835952 -147.532389) (xy 2.772156 -147.536403)
			(xy 2.70836 -147.532389) (xy 2.64557 -147.520411) (xy 2.584777 -147.500658) (xy 2.526938 -147.473441)
			(xy 2.472967 -147.43919) (xy 2.423714 -147.398445) (xy 2.379957 -147.351848) (xy 2.342384 -147.300133)
			(xy 2.31159 -147.244118) (xy 2.288058 -147.184685) (xy 2.272161 -147.122771) (xy 2.26415 -147.059353)
			(xy 2.263648 -147.027392) (xy 2.263648 -146.357594) (xy 2.264163 -146.324892) (xy 2.272557 -146.260029)
			(xy 2.289206 -146.196779) (xy 2.313834 -146.136189) (xy 2.346034 -146.079261) (xy 2.365248 -146.052794)
			(xy 2.390648 -146.019012) (xy 2.390648 -145.201386) (xy 2.441448 -145.150332) (xy 2.441448 -144.058894)
			(xy 2.125472 -143.742664) (xy 1.678432 -143.742664) (xy 1.678432 -169.167048) (xy 15.337534 -169.167048)
			(xy 15.341605 -169.111426) (xy 15.353731 -169.056989) (xy 15.373654 -169.004898) (xy 15.40095 -168.956263)
			(xy 15.435036 -168.91212) (xy 15.475185 -168.873411) (xy 15.520543 -168.84096) (xy 15.570143 -168.815459)
			(xy 15.622927 -168.797452) (xy 15.67777 -168.787322) (xy 15.733504 -168.785285) (xy 15.788941 -168.791385)
			(xy 15.842898 -168.805491) (xy 15.894227 -168.827303) (xy 15.941833 -168.856357) (xy 15.984701 -168.892032)
			(xy 16.021918 -168.933569) (xy 16.052691 -168.980082) (xy 16.076363 -169.030579) (xy 16.092431 -169.083986)
			(xy 16.100551 -169.139162) (xy 16.10106 -169.167048) (xy 16.100551 -169.194934) (xy 16.092431 -169.25011)
			(xy 16.076363 -169.303517) (xy 16.052691 -169.354014) (xy 16.021918 -169.400527) (xy 15.984701 -169.442064)
			(xy 15.941833 -169.477739) (xy 15.894227 -169.506793) (xy 15.842898 -169.528605) (xy 15.788941 -169.542711)
			(xy 15.733504 -169.548811) (xy 15.67777 -169.546774) (xy 15.622927 -169.536644) (xy 15.570143 -169.518637)
			(xy 15.520543 -169.493136) (xy 15.475185 -169.460685) (xy 15.435036 -169.421976) (xy 15.40095 -169.377833)
			(xy 15.373654 -169.329198) (xy 15.353731 -169.277107) (xy 15.341605 -169.22267) (xy 15.337534 -169.167048)
			(xy 1.678432 -169.167048) (xy 1.678432 -170.372532) (xy 14.663926 -170.372532) (xy 14.667997 -170.31691)
			(xy 14.680123 -170.262473) (xy 14.700046 -170.210382) (xy 14.727342 -170.161747) (xy 14.761428 -170.117604)
			(xy 14.801577 -170.078895) (xy 14.846935 -170.046444) (xy 14.896535 -170.020943) (xy 14.949319 -170.002936)
			(xy 15.004162 -169.992806) (xy 15.059896 -169.990769) (xy 15.115333 -169.996869) (xy 15.16929 -170.010975)
			(xy 15.220619 -170.032787) (xy 15.268225 -170.061841) (xy 15.311093 -170.097516) (xy 15.34831 -170.139053)
			(xy 15.379083 -170.185566) (xy 15.402755 -170.236063) (xy 15.418823 -170.28947) (xy 15.426943 -170.344646)
			(xy 15.427452 -170.372532) (xy 15.426943 -170.400418) (xy 15.418823 -170.455594) (xy 15.402755 -170.509001)
			(xy 15.379083 -170.559498) (xy 15.34831 -170.606011) (xy 15.311093 -170.647548) (xy 15.268225 -170.683223)
			(xy 15.220619 -170.712277) (xy 15.16929 -170.734089) (xy 15.115333 -170.748195) (xy 15.059896 -170.754295)
			(xy 15.004162 -170.752258) (xy 14.949319 -170.742128) (xy 14.896535 -170.724121) (xy 14.846935 -170.69862)
			(xy 14.801577 -170.666169) (xy 14.761428 -170.62746) (xy 14.727342 -170.583317) (xy 14.700046 -170.534682)
			(xy 14.680123 -170.482591) (xy 14.667997 -170.428154) (xy 14.663926 -170.372532) (xy 1.678432 -170.372532)
			(xy 1.678432 -170.897042) (xy 25.769822 -170.897042) (xy 25.773893 -170.84142) (xy 25.786019 -170.786983)
			(xy 25.805942 -170.734892) (xy 25.833238 -170.686257) (xy 25.867324 -170.642114) (xy 25.907473 -170.603405)
			(xy 25.952831 -170.570954) (xy 26.002431 -170.545453) (xy 26.055215 -170.527446) (xy 26.110058 -170.517316)
			(xy 26.165792 -170.515279) (xy 26.221229 -170.521379) (xy 26.275186 -170.535485) (xy 26.326515 -170.557297)
			(xy 26.374121 -170.586351) (xy 26.416989 -170.622026) (xy 26.454206 -170.663563) (xy 26.484979 -170.710076)
			(xy 26.508651 -170.760573) (xy 26.524719 -170.81398) (xy 26.532839 -170.869156) (xy 26.533348 -170.897042)
			(xy 26.532839 -170.924928) (xy 26.524719 -170.980104) (xy 26.508651 -171.033511) (xy 26.484979 -171.084008)
			(xy 26.454206 -171.130521) (xy 26.416989 -171.172058) (xy 26.374121 -171.207733) (xy 26.326515 -171.236787)
			(xy 26.275186 -171.258599) (xy 26.221229 -171.272705) (xy 26.165792 -171.278805) (xy 26.110058 -171.276768)
			(xy 26.055215 -171.266638) (xy 26.002431 -171.248631) (xy 25.952831 -171.22313) (xy 25.907473 -171.190679)
			(xy 25.867324 -171.15197) (xy 25.833238 -171.107827) (xy 25.805942 -171.059192) (xy 25.786019 -171.007101)
			(xy 25.773893 -170.952664) (xy 25.769822 -170.897042) (xy 1.678432 -170.897042) (xy 1.678432 -171.533058)
			(xy 14.127478 -171.533058) (xy 14.131549 -171.477436) (xy 14.143675 -171.422999) (xy 14.163598 -171.370908)
			(xy 14.190894 -171.322273) (xy 14.22498 -171.27813) (xy 14.265129 -171.239421) (xy 14.310487 -171.20697)
			(xy 14.360087 -171.181469) (xy 14.412871 -171.163462) (xy 14.467714 -171.153332) (xy 14.523448 -171.151295)
			(xy 14.578885 -171.157395) (xy 14.632842 -171.171501) (xy 14.684171 -171.193313) (xy 14.731777 -171.222367)
			(xy 14.733057 -171.223432) (xy 17.342612 -171.223432) (xy 19.324828 -171.223432) (xy 22.625812 -171.223432)
			(xy 24.608028 -171.223432) (xy 24.608028 -172.037248) (xy 22.625812 -172.037248) (xy 22.625812 -171.223432)
			(xy 19.324828 -171.223432) (xy 19.324828 -172.037248) (xy 17.342612 -172.037248) (xy 17.342612 -171.223432)
			(xy 14.733057 -171.223432) (xy 14.774645 -171.258042) (xy 14.811862 -171.299579) (xy 14.842635 -171.346092)
			(xy 14.866307 -171.396589) (xy 14.882375 -171.449996) (xy 14.890495 -171.505172) (xy 14.891004 -171.533058)
			(xy 14.890495 -171.560944) (xy 14.882375 -171.61612) (xy 14.866307 -171.669527) (xy 14.842635 -171.720024)
			(xy 14.811862 -171.766537) (xy 14.774645 -171.808074) (xy 14.731777 -171.843749) (xy 14.684171 -171.872803)
			(xy 14.632842 -171.894615) (xy 14.578885 -171.908721) (xy 14.523448 -171.914821) (xy 14.467714 -171.912784)
			(xy 14.412871 -171.902654) (xy 14.360087 -171.884647) (xy 14.310487 -171.859146) (xy 14.265129 -171.826695)
			(xy 14.22498 -171.787986) (xy 14.190894 -171.743843) (xy 14.163598 -171.695208) (xy 14.143675 -171.643117)
			(xy 14.131549 -171.58868) (xy 14.127478 -171.533058) (xy 1.678432 -171.533058) (xy 1.678432 -172.67174)
			(xy 13.456664 -172.67174) (xy 13.460735 -172.616118) (xy 13.472861 -172.561681) (xy 13.492784 -172.50959)
			(xy 13.52008 -172.460955) (xy 13.554166 -172.416812) (xy 13.594315 -172.378103) (xy 13.639673 -172.345652)
			(xy 13.689273 -172.320151) (xy 13.742057 -172.302144) (xy 13.7969 -172.292014) (xy 13.852634 -172.289977)
			(xy 13.908071 -172.296077) (xy 13.962028 -172.310183) (xy 14.013357 -172.331995) (xy 14.060963 -172.361049)
			(xy 14.103831 -172.396724) (xy 14.141048 -172.438261) (xy 14.171821 -172.484774) (xy 14.195493 -172.535271)
			(xy 14.211561 -172.588678) (xy 14.219681 -172.643854) (xy 14.22019 -172.67174) (xy 14.219681 -172.699626)
			(xy 14.211561 -172.754802) (xy 14.195493 -172.808209) (xy 14.171821 -172.858706) (xy 14.141048 -172.905219)
			(xy 14.103831 -172.946756) (xy 14.060963 -172.982431) (xy 14.013357 -173.011485) (xy 13.962028 -173.033297)
			(xy 13.908071 -173.047403) (xy 13.852634 -173.053503) (xy 13.7969 -173.051466) (xy 13.742057 -173.041336)
			(xy 13.689273 -173.023329) (xy 13.639673 -172.997828) (xy 13.594315 -172.965377) (xy 13.554166 -172.926668)
			(xy 13.52008 -172.882525) (xy 13.492784 -172.83389) (xy 13.472861 -172.781799) (xy 13.460735 -172.727362)
			(xy 13.456664 -172.67174) (xy 1.678432 -172.67174) (xy 1.678432 -174.577248) (xy 17.342612 -174.577248)
			(xy 17.342612 -173.763432) (xy 18.02638 -173.763432) (xy 18.057876 -173.743366) (xy 18.086972 -173.725255)
			(xy 18.149018 -173.696147) (xy 18.214411 -173.675633) (xy 18.281966 -173.664085) (xy 18.316194 -173.66234)
			(xy 18.332435 -173.661178) (xy 18.363604 -173.651812) (xy 18.391389 -173.634865) (xy 18.413983 -173.61144)
			(xy 18.429915 -173.583061) (xy 18.438149 -173.551574) (xy 18.438149 -173.519029) (xy 18.429916 -173.487542)
			(xy 18.413984 -173.459162) (xy 18.391391 -173.435737) (xy 18.363607 -173.418789) (xy 18.332438 -173.409422)
			(xy 18.316194 -173.40834) (xy 18.281963 -173.406625) (xy 18.214402 -173.395087) (xy 18.149006 -173.374569)
			(xy 18.086963 -173.345443) (xy 18.057876 -173.327314) (xy 18.02638 -173.307248) (xy 17.342612 -173.307248)
			(xy 17.342612 -172.493432) (xy 18.02638 -172.493432) (xy 18.057876 -172.473366) (xy 18.082588 -172.457859)
			(xy 18.134876 -172.431977) (xy 18.189785 -172.412255) (xy 18.246592 -172.398954) (xy 18.304549 -172.392249)
			(xy 18.33372 -172.391832) (xy 19.96948 -172.391832) (xy 20.477768 -172.90034) (xy 21.382489 -172.90034)
			(xy 21.386503 -172.836544) (xy 21.398481 -172.773755) (xy 21.418234 -172.712961) (xy 21.44545 -172.655123)
			(xy 21.479701 -172.601152) (xy 21.520447 -172.551899) (xy 21.567044 -172.508141) (xy 21.618757 -172.470569)
			(xy 21.674773 -172.439774) (xy 21.734206 -172.416243) (xy 21.796119 -172.400346) (xy 21.859537 -172.392334)
			(xy 21.891498 -172.391832) (xy 23.61692 -172.391832) (xy 23.646091 -172.392238) (xy 23.704043 -172.398968)
			(xy 23.760846 -172.41228) (xy 23.815754 -172.431999) (xy 23.868048 -172.457867) (xy 23.892764 -172.473366)
			(xy 23.92426 -172.493432) (xy 24.608028 -172.493432) (xy 24.608028 -173.307248) (xy 23.92426 -173.307248)
			(xy 23.892764 -173.327314) (xy 23.86368 -173.345446) (xy 23.80163 -173.37455) (xy 23.736233 -173.395058)
			(xy 23.668675 -173.406598) (xy 23.634446 -173.40834) (xy 23.618185 -173.409338) (xy 23.586989 -173.418705)
			(xy 23.559178 -173.43566) (xy 23.536562 -173.459102) (xy 23.520615 -173.487503) (xy 23.512373 -173.519015)
			(xy 23.512373 -173.551588) (xy 23.520616 -173.5831) (xy 23.536564 -173.6115) (xy 23.55918 -173.634941)
			(xy 23.586991 -173.651897) (xy 23.618188 -173.661262) (xy 23.634446 -173.66234) (xy 23.668675 -173.664084)
			(xy 23.736235 -173.675614) (xy 23.801631 -173.696124) (xy 23.863676 -173.725241) (xy 23.892764 -173.743366)
			(xy 23.92426 -173.763432) (xy 24.608028 -173.763432) (xy 24.608028 -174.577248) (xy 23.92426 -174.577248)
			(xy 23.892764 -174.597314) (xy 23.86804 -174.612801) (xy 23.815756 -174.638688) (xy 23.76085 -174.658414)
			(xy 23.704045 -174.671719) (xy 23.646091 -174.678428) (xy 23.61692 -174.678848) (xy 22.014942 -174.678848)
			(xy 21.983487 -174.678344) (xy 21.921057 -174.670575) (xy 21.860063 -174.655163) (xy 21.801437 -174.632343)
			(xy 21.746074 -174.602464) (xy 21.69482 -174.565983) (xy 21.64846 -174.523456) (xy 21.6077 -174.475535)
			(xy 21.573164 -174.422951) (xy 21.54538 -174.366507) (xy 21.524773 -174.307067) (xy 21.511656 -174.245539)
			(xy 21.506232 -174.182862) (xy 21.508581 -174.119995) (xy 21.51867 -174.057898) (xy 21.536342 -173.99752)
			(xy 21.561329 -173.939784) (xy 21.593249 -173.885572) (xy 21.631614 -173.835713) (xy 21.675837 -173.790968)
			(xy 21.725243 -173.752021) (xy 21.779076 -173.719467) (xy 21.836515 -173.693804) (xy 21.896681 -173.675424)
			(xy 21.958655 -173.664608) (xy 21.99005 -173.662594) (xy 22.04085 -173.660054) (xy 22.110954 -173.586648)
			(xy 22.110954 -173.535848) (xy 22.110463 -173.519192) (xy 22.101849 -173.487012) (xy 22.085197 -173.45816)
			(xy 22.061641 -173.434604) (xy 22.03279 -173.417951) (xy 22.00061 -173.409337) (xy 21.983954 -173.408848)
			(xy 21.891498 -173.408848) (xy 21.859537 -173.408346) (xy 21.796119 -173.400334) (xy 21.734206 -173.384437)
			(xy 21.674773 -173.360906) (xy 21.618757 -173.330111) (xy 21.567044 -173.292539) (xy 21.520447 -173.248781)
			(xy 21.479701 -173.199528) (xy 21.44545 -173.145557) (xy 21.418234 -173.087719) (xy 21.398481 -173.026925)
			(xy 21.386503 -172.964136) (xy 21.382489 -172.90034) (xy 20.477768 -172.90034) (xy 20.55749 -172.980096)
			(xy 20.579501 -173.002823) (xy 20.618361 -173.052752) (xy 20.650721 -173.107119) (xy 20.676083 -173.165082)
			(xy 20.694052 -173.225746) (xy 20.704351 -173.288171) (xy 20.706821 -173.351391) (xy 20.701423 -173.41443)
			(xy 20.688242 -173.47631) (xy 20.66748 -173.536076) (xy 20.63946 -173.592801) (xy 20.604614 -173.64561)
			(xy 20.584414 -173.66996) (xy 20.574931 -173.681731) (xy 20.561219 -173.708657) (xy 20.554233 -173.738055)
			(xy 20.554368 -173.768272) (xy 20.561615 -173.797606) (xy 20.575566 -173.82441) (xy 20.585176 -173.836076)
			(xy 20.605993 -173.86082) (xy 20.642003 -173.914525) (xy 20.670913 -173.972362) (xy 20.692255 -174.033399)
			(xy 20.705684 -174.096649) (xy 20.710985 -174.161092) (xy 20.70807 -174.225686) (xy 20.696988 -174.28939)
			(xy 20.677917 -174.351174) (xy 20.651166 -174.410041) (xy 20.617165 -174.46504) (xy 20.576465 -174.515284)
			(xy 20.529722 -174.559961) (xy 20.477691 -174.598349) (xy 20.421211 -174.62983) (xy 20.361196 -174.653895)
			(xy 20.298613 -174.670155) (xy 20.234474 -174.678347) (xy 20.202144 -174.678848) (xy 18.33372 -174.678848)
			(xy 18.30455 -174.678425) (xy 18.246598 -174.6717) (xy 18.189795 -174.658392) (xy 18.134887 -174.638676)
			(xy 18.082592 -174.612812) (xy 18.057876 -174.597314) (xy 18.02638 -174.577248) (xy 17.342612 -174.577248)
			(xy 1.678432 -174.577248) (xy 1.678432 -176.803812) (xy 1.745226 -176.870614) (xy 3.864362 -176.870614)
			(xy 3.868375 -176.7672) (xy 3.88039 -176.664407) (xy 3.900334 -176.562855) (xy 3.928088 -176.463153)
			(xy 3.963484 -176.365903) (xy 4.00631 -176.271687) (xy 4.056309 -176.181074) (xy 4.113179 -176.094607)
			(xy 4.176578 -176.012808) (xy 4.246126 -175.936167) (xy 4.321403 -175.865146) (xy 4.401958 -175.800173)
			(xy 4.487305 -175.741637) (xy 4.576932 -175.689891) (xy 4.6703 -175.645245) (xy 4.766846 -175.60797)
			(xy 4.86599 -175.578288) (xy 4.967137 -175.556378) (xy 5.069677 -175.542372) (xy 5.172994 -175.536355)
			(xy 5.276467 -175.538362) (xy 5.379473 -175.548381) (xy 5.481393 -175.566352) (xy 5.581614 -175.592167)
			(xy 5.679533 -175.625671) (xy 5.774561 -175.666663) (xy 5.866127 -175.714894) (xy 5.95368 -175.770077)
			(xy 6.036694 -175.831878) (xy 6.114668 -175.899927) (xy 6.187135 -175.973813) (xy 6.253659 -176.053092)
			(xy 6.313839 -176.137289) (xy 6.367313 -176.225895) (xy 6.41376 -176.318379) (xy 6.452901 -176.414185)
			(xy 6.4845 -176.512735) (xy 6.508367 -176.613438) (xy 6.524359 -176.715687) (xy 6.532378 -176.818868)
			(xy 6.53288 -176.870614) (xy 6.532378 -176.92236) (xy 6.524359 -177.025541) (xy 6.508367 -177.12779)
			(xy 6.4845 -177.228493) (xy 6.452901 -177.327043) (xy 6.41376 -177.422849) (xy 6.367313 -177.515333)
			(xy 6.313839 -177.603939) (xy 6.253659 -177.688136) (xy 6.187135 -177.767415) (xy 6.114668 -177.841301)
			(xy 6.036694 -177.90935) (xy 5.95368 -177.971151) (xy 5.866127 -178.026334) (xy 5.774561 -178.074565)
			(xy 5.679533 -178.115557) (xy 5.581614 -178.149061) (xy 5.481393 -178.174876) (xy 5.379473 -178.192847)
			(xy 5.276467 -178.202866) (xy 5.172994 -178.204873) (xy 5.069677 -178.198856) (xy 4.967137 -178.18485)
			(xy 4.86599 -178.16294) (xy 4.766846 -178.133258) (xy 4.6703 -178.095983) (xy 4.576932 -178.051337)
			(xy 4.487305 -177.999591) (xy 4.401958 -177.941055) (xy 4.321403 -177.876082) (xy 4.246126 -177.805061)
			(xy 4.176578 -177.72842) (xy 4.113179 -177.646621) (xy 4.056309 -177.560154) (xy 4.00631 -177.469541)
			(xy 3.963484 -177.375325) (xy 3.928088 -177.278075) (xy 3.900334 -177.178373) (xy 3.88039 -177.076821)
			(xy 3.868375 -176.974028) (xy 3.864362 -176.870614) (xy 1.745226 -176.870614) (xy 3.908552 -179.034186)
			(xy 3.95986 -179.034948) (xy 3.995412 -179.036054) (xy 4.065951 -179.045209) (xy 4.135027 -179.062183)
			(xy 4.201775 -179.086763) (xy 4.265363 -179.118641) (xy 4.324994 -179.157419) (xy 4.379922 -179.202613)
			(xy 4.429462 -179.253656) (xy 4.472993 -179.309911) (xy 4.509971 -179.370674) (xy 4.539935 -179.435186)
			(xy 4.562508 -179.50264) (xy 4.577409 -179.572193) (xy 4.584452 -179.642974) (xy 4.583549 -179.714099)
			(xy 4.57962 -179.74945) (xy 4.578096 -179.760372) (xy 4.576447 -179.774978) (xy 4.579097 -179.804245)
			(xy 4.588382 -179.832125) (xy 4.603809 -179.857137) (xy 4.61391 -179.867814) (xy 4.829556 -180.08346)
			(xy 6.66242 -180.08346)
		)
		(stroke
			(width 0)
			(type solid)
		)
		(fill yes)
		(layer "F.Cu")
		(net "P12V")
	)
	(gr_poly
		(pts
			(xy 101.000052 -528.729956) (xy 101.038285 -528.729475) (xy 101.114333 -528.721487) (xy 101.189128 -528.705592)
			(xy 101.261853 -528.681966) (xy 101.331709 -528.650867) (xy 101.397931 -528.612636) (xy 101.459795 -528.567691)
			(xy 101.51662 -528.516526) (xy 101.567786 -528.459701) (xy 101.612731 -528.397838) (xy 101.650963 -528.331616)
			(xy 101.682063 -528.26176) (xy 101.70569 -528.189036) (xy 101.721586 -528.11424) (xy 101.729575 -528.038193)
			(xy 101.730048 -527.99996) (xy 101.730048 -4.039362) (xy 100.116894 -2.426208) (xy 28.730448 -2.426208)
			(xy 28.232354 -2.924302) (xy 28.232354 -4.633484) (xy 29.519874 -4.633484) (xy 29.519874 -4.546584)
			(xy 29.527892 -4.460055) (xy 29.54386 -4.374635) (xy 29.567641 -4.291053) (xy 29.599033 -4.210021)
			(xy 29.637767 -4.132232) (xy 29.683514 -4.058348) (xy 29.735883 -3.989001) (xy 29.794427 -3.924781)
			(xy 29.858647 -3.866237) (xy 29.927994 -3.813868) (xy 30.001878 -3.768121) (xy 30.079667 -3.729387)
			(xy 30.160699 -3.697995) (xy 30.244281 -3.674214) (xy 30.329701 -3.658246) (xy 30.41623 -3.650228)
			(xy 30.50313 -3.650228) (xy 30.589659 -3.658246) (xy 30.675079 -3.674214) (xy 30.758661 -3.697995)
			(xy 30.839693 -3.729387) (xy 30.917482 -3.768121) (xy 30.991366 -3.813868) (xy 31.060713 -3.866237)
			(xy 31.124933 -3.924781) (xy 31.183477 -3.989001) (xy 31.235846 -4.058348) (xy 31.281593 -4.132232)
			(xy 31.320327 -4.210021) (xy 31.351719 -4.291053) (xy 31.3755 -4.374635) (xy 31.391468 -4.460055)
			(xy 31.399486 -4.546584) (xy 31.399988 -4.590034) (xy 31.399486 -4.633484) (xy 34.599874 -4.633484)
			(xy 34.599874 -4.546584) (xy 34.607892 -4.460055) (xy 34.62386 -4.374635) (xy 34.647641 -4.291053)
			(xy 34.679033 -4.210021) (xy 34.717767 -4.132232) (xy 34.763514 -4.058348) (xy 34.815883 -3.989001)
			(xy 34.874427 -3.924781) (xy 34.938647 -3.866237) (xy 35.007994 -3.813868) (xy 35.081878 -3.768121)
			(xy 35.159667 -3.729387) (xy 35.240699 -3.697995) (xy 35.324281 -3.674214) (xy 35.409701 -3.658246)
			(xy 35.49623 -3.650228) (xy 35.58313 -3.650228) (xy 35.669659 -3.658246) (xy 35.755079 -3.674214)
			(xy 35.838661 -3.697995) (xy 35.919693 -3.729387) (xy 35.997482 -3.768121) (xy 36.071366 -3.813868)
			(xy 36.140713 -3.866237) (xy 36.204933 -3.924781) (xy 36.263477 -3.989001) (xy 36.315846 -4.058348)
			(xy 36.361593 -4.132232) (xy 36.400327 -4.210021) (xy 36.431719 -4.291053) (xy 36.4555 -4.374635)
			(xy 36.471468 -4.460055) (xy 36.479486 -4.546584) (xy 36.479988 -4.590034) (xy 36.479486 -4.633484)
			(xy 36.471468 -4.720013) (xy 36.4555 -4.805433) (xy 36.431719 -4.889015) (xy 36.400327 -4.970047)
			(xy 36.361593 -5.047836) (xy 36.315846 -5.12172) (xy 36.263477 -5.191067) (xy 36.204933 -5.255287)
			(xy 36.140713 -5.313831) (xy 36.071366 -5.3662) (xy 35.997482 -5.411947) (xy 35.919693 -5.450681)
			(xy 35.838661 -5.482073) (xy 35.755079 -5.505854) (xy 35.669659 -5.521822) (xy 35.58313 -5.52984)
			(xy 35.49623 -5.52984) (xy 35.409701 -5.521822) (xy 35.324281 -5.505854) (xy 35.240699 -5.482073)
			(xy 35.159667 -5.450681) (xy 35.081878 -5.411947) (xy 35.007994 -5.3662) (xy 34.938647 -5.313831)
			(xy 34.874427 -5.255287) (xy 34.815883 -5.191067) (xy 34.763514 -5.12172) (xy 34.717767 -5.047836)
			(xy 34.679033 -4.970047) (xy 34.647641 -4.889015) (xy 34.62386 -4.805433) (xy 34.607892 -4.720013)
			(xy 34.599874 -4.633484) (xy 31.399486 -4.633484) (xy 31.391468 -4.720013) (xy 31.3755 -4.805433)
			(xy 31.351719 -4.889015) (xy 31.320327 -4.970047) (xy 31.281593 -5.047836) (xy 31.235846 -5.12172)
			(xy 31.183477 -5.191067) (xy 31.124933 -5.255287) (xy 31.060713 -5.313831) (xy 30.991366 -5.3662)
			(xy 30.917482 -5.411947) (xy 30.839693 -5.450681) (xy 30.758661 -5.482073) (xy 30.675079 -5.505854)
			(xy 30.589659 -5.521822) (xy 30.50313 -5.52984) (xy 30.41623 -5.52984) (xy 30.329701 -5.521822) (xy 30.244281 -5.505854)
			(xy 30.160699 -5.482073) (xy 30.079667 -5.450681) (xy 30.001878 -5.411947) (xy 29.927994 -5.3662)
			(xy 29.858647 -5.313831) (xy 29.794427 -5.255287) (xy 29.735883 -5.191067) (xy 29.683514 -5.12172)
			(xy 29.637767 -5.047836) (xy 29.599033 -4.970047) (xy 29.567641 -4.889015) (xy 29.54386 -4.805433)
			(xy 29.527892 -4.720013) (xy 29.519874 -4.633484) (xy 28.232354 -4.633484) (xy 28.232354 -6.44398)
			(xy 28.550616 -6.762242) (xy 28.562745 -6.773639) (xy 28.591528 -6.790324) (xy 28.623645 -6.799003)
			(xy 28.640278 -6.79958) (xy 29.532326 -6.79958) (xy 29.594302 -6.76021) (xy 29.61005 -6.726936) (xy 29.628894 -6.688278)
			(xy 29.672657 -6.614237) (xy 29.722998 -6.544501) (xy 29.779497 -6.479654) (xy 29.841682 -6.420237)
			(xy 29.909032 -6.366747) (xy 29.980986 -6.319631) (xy 30.056941 -6.279282) (xy 30.136264 -6.246037)
			(xy 30.218291 -6.220175) (xy 30.302336 -6.201911) (xy 30.387699 -6.191399) (xy 30.473665 -6.188725)
			(xy 30.559516 -6.193913) (xy 30.644534 -6.206918) (xy 30.728009 -6.227633) (xy 30.809245 -6.255884)
			(xy 30.887561 -6.291435) (xy 30.962303 -6.333989) (xy 31.032847 -6.38319) (xy 31.098604 -6.438628)
			(xy 31.159023 -6.499839) (xy 31.213601 -6.566311) (xy 31.26188 -6.637489) (xy 31.303458 -6.712779)
			(xy 31.337987 -6.791551) (xy 31.365179 -6.873147) (xy 31.384806 -6.956885) (xy 31.396704 -7.042065)
			(xy 31.400775 -7.127976) (xy 31.398767 -7.173484) (xy 34.599874 -7.173484) (xy 34.599874 -7.086584)
			(xy 34.607892 -7.000055) (xy 34.62386 -6.914635) (xy 34.647641 -6.831053) (xy 34.679033 -6.750021)
			(xy 34.717767 -6.672232) (xy 34.763514 -6.598348) (xy 34.815883 -6.529001) (xy 34.874427 -6.464781)
			(xy 34.938647 -6.406237) (xy 35.007994 -6.353868) (xy 35.081878 -6.308121) (xy 35.159667 -6.269387)
			(xy 35.240699 -6.237995) (xy 35.324281 -6.214214) (xy 35.409701 -6.198246) (xy 35.49623 -6.190228)
			(xy 35.58313 -6.190228) (xy 35.669659 -6.198246) (xy 35.755079 -6.214214) (xy 35.838661 -6.237995)
			(xy 35.919693 -6.269387) (xy 35.997482 -6.308121) (xy 36.071366 -6.353868) (xy 36.140713 -6.406237)
			(xy 36.204933 -6.464781) (xy 36.263477 -6.529001) (xy 36.315846 -6.598348) (xy 36.361593 -6.672232)
			(xy 36.400327 -6.750021) (xy 36.431719 -6.831053) (xy 36.454201 -6.91007) (xy 39.818564 -6.91007)
			(xy 39.819054 -6.852663) (xy 39.826889 -6.738117) (xy 39.842523 -6.624372) (xy 39.865882 -6.51196)
			(xy 39.896859 -6.401403) (xy 39.935308 -6.293218) (xy 39.98105 -6.18791) (xy 40.033872 -6.085968)
			(xy 40.093527 -5.987869) (xy 40.159738 -5.894069) (xy 40.232196 -5.805007) (xy 40.310562 -5.721096)
			(xy 40.394473 -5.64273) (xy 40.483535 -5.570272) (xy 40.577335 -5.504061) (xy 40.675434 -5.444406)
			(xy 40.777376 -5.391584) (xy 40.882684 -5.345842) (xy 40.990869 -5.307393) (xy 41.101426 -5.276416)
			(xy 41.213838 -5.253057) (xy 41.327583 -5.237423) (xy 41.442129 -5.229588) (xy 41.556943 -5.229588)
			(xy 41.671489 -5.237423) (xy 41.785234 -5.253057) (xy 41.897646 -5.276416) (xy 42.008203 -5.307393)
			(xy 42.116388 -5.345842) (xy 42.221696 -5.391584) (xy 42.323638 -5.444406) (xy 42.421737 -5.504061)
			(xy 42.50107 -5.56006) (xy 43.327577 -5.56006) (xy 43.331612 -5.484356) (xy 43.343671 -5.409511)
			(xy 43.363617 -5.33637) (xy 43.391224 -5.265765) (xy 43.42618 -5.198494) (xy 43.468088 -5.135319)
			(xy 43.516474 -5.076957) (xy 43.57079 -5.024069) (xy 43.630419 -4.977254) (xy 43.694687 -4.937042)
			(xy 43.762864 -4.90389) (xy 43.83418 -4.878172) (xy 43.907825 -4.86018) (xy 43.982965 -4.850118)
			(xy 44.058749 -4.848099) (xy 44.134319 -4.854148) (xy 44.208817 -4.868195) (xy 44.2814 -4.890081)
			(xy 44.351246 -4.919558) (xy 44.417563 -4.956293) (xy 44.479599 -4.999868) (xy 44.536652 -5.04979)
			(xy 44.588076 -5.105494) (xy 44.633287 -5.166349) (xy 44.671774 -5.231664) (xy 44.7031 -5.3007) (xy 44.72691 -5.372675)
			(xy 44.742935 -5.446773) (xy 44.750994 -5.522154) (xy 44.751498 -5.56006) (xy 45.867577 -5.56006)
			(xy 45.871612 -5.484356) (xy 45.883671 -5.409511) (xy 45.903617 -5.33637) (xy 45.931224 -5.265765)
			(xy 45.96618 -5.198494) (xy 46.008088 -5.135319) (xy 46.056474 -5.076957) (xy 46.11079 -5.024069)
			(xy 46.170419 -4.977254) (xy 46.234687 -4.937042) (xy 46.302864 -4.90389) (xy 46.37418 -4.878172)
			(xy 46.447825 -4.86018) (xy 46.522965 -4.850118) (xy 46.598749 -4.848099) (xy 46.674319 -4.854148)
			(xy 46.748817 -4.868195) (xy 46.8214 -4.890081) (xy 46.891246 -4.919558) (xy 46.957563 -4.956293)
			(xy 47.019599 -4.999868) (xy 47.076652 -5.04979) (xy 47.128076 -5.105494) (xy 47.173287 -5.166349)
			(xy 47.211774 -5.231664) (xy 47.2431 -5.3007) (xy 47.26691 -5.372675) (xy 47.282935 -5.446773) (xy 47.290994 -5.522154)
			(xy 47.291498 -5.56006) (xy 48.407577 -5.56006) (xy 48.411612 -5.484356) (xy 48.423671 -5.409511)
			(xy 48.443617 -5.33637) (xy 48.471224 -5.265765) (xy 48.50618 -5.198494) (xy 48.548088 -5.135319)
			(xy 48.596474 -5.076957) (xy 48.65079 -5.024069) (xy 48.710419 -4.977254) (xy 48.774687 -4.937042)
			(xy 48.842864 -4.90389) (xy 48.91418 -4.878172) (xy 48.987825 -4.86018) (xy 49.062965 -4.850118)
			(xy 49.138749 -4.848099) (xy 49.214319 -4.854148) (xy 49.288817 -4.868195) (xy 49.3614 -4.890081)
			(xy 49.431246 -4.919558) (xy 49.497563 -4.956293) (xy 49.559599 -4.999868) (xy 49.616652 -5.04979)
			(xy 49.668076 -5.105494) (xy 49.713287 -5.166349) (xy 49.751774 -5.231664) (xy 49.7831 -5.3007) (xy 49.80691 -5.372675)
			(xy 49.822935 -5.446773) (xy 49.830994 -5.522154) (xy 49.831498 -5.56006) (xy 50.947577 -5.56006)
			(xy 50.951612 -5.484356) (xy 50.963671 -5.409511) (xy 50.983617 -5.33637) (xy 51.011224 -5.265765)
			(xy 51.04618 -5.198494) (xy 51.088088 -5.135319) (xy 51.136474 -5.076957) (xy 51.19079 -5.024069)
			(xy 51.250419 -4.977254) (xy 51.314687 -4.937042) (xy 51.382864 -4.90389) (xy 51.45418 -4.878172)
			(xy 51.527825 -4.86018) (xy 51.602965 -4.850118) (xy 51.678749 -4.848099) (xy 51.754319 -4.854148)
			(xy 51.828817 -4.868195) (xy 51.9014 -4.890081) (xy 51.971246 -4.919558) (xy 52.037563 -4.956293)
			(xy 52.099599 -4.999868) (xy 52.156652 -5.04979) (xy 52.208076 -5.105494) (xy 52.253287 -5.166349)
			(xy 52.291774 -5.231664) (xy 52.3231 -5.3007) (xy 52.34691 -5.372675) (xy 52.362935 -5.446773) (xy 52.370994 -5.522154)
			(xy 52.371498 -5.56006) (xy 53.487577 -5.56006) (xy 53.491612 -5.484356) (xy 53.503671 -5.409511)
			(xy 53.523617 -5.33637) (xy 53.551224 -5.265765) (xy 53.58618 -5.198494) (xy 53.628088 -5.135319)
			(xy 53.676474 -5.076957) (xy 53.73079 -5.024069) (xy 53.790419 -4.977254) (xy 53.854687 -4.937042)
			(xy 53.922864 -4.90389) (xy 53.99418 -4.878172) (xy 54.067825 -4.86018) (xy 54.142965 -4.850118)
			(xy 54.218749 -4.848099) (xy 54.294319 -4.854148) (xy 54.368817 -4.868195) (xy 54.4414 -4.890081)
			(xy 54.511246 -4.919558) (xy 54.577563 -4.956293) (xy 54.639599 -4.999868) (xy 54.696652 -5.04979)
			(xy 54.748076 -5.105494) (xy 54.793287 -5.166349) (xy 54.831774 -5.231664) (xy 54.8631 -5.3007) (xy 54.88691 -5.372675)
			(xy 54.902935 -5.446773) (xy 54.910994 -5.522154) (xy 54.911498 -5.56006) (xy 56.027577 -5.56006)
			(xy 56.031612 -5.484356) (xy 56.043671 -5.409511) (xy 56.063617 -5.33637) (xy 56.091224 -5.265765)
			(xy 56.12618 -5.198494) (xy 56.168088 -5.135319) (xy 56.216474 -5.076957) (xy 56.27079 -5.024069)
			(xy 56.330419 -4.977254) (xy 56.394687 -4.937042) (xy 56.462864 -4.90389) (xy 56.53418 -4.878172)
			(xy 56.607825 -4.86018) (xy 56.682965 -4.850118) (xy 56.758749 -4.848099) (xy 56.834319 -4.854148)
			(xy 56.908817 -4.868195) (xy 56.9814 -4.890081) (xy 57.051246 -4.919558) (xy 57.117563 -4.956293)
			(xy 57.179599 -4.999868) (xy 57.236652 -5.04979) (xy 57.288076 -5.105494) (xy 57.333287 -5.166349)
			(xy 57.371774 -5.231664) (xy 57.4031 -5.3007) (xy 57.42691 -5.372675) (xy 57.442935 -5.446773) (xy 57.450994 -5.522154)
			(xy 57.451498 -5.56006) (xy 58.567577 -5.56006) (xy 58.571612 -5.484356) (xy 58.583671 -5.409511)
			(xy 58.603617 -5.33637) (xy 58.631224 -5.265765) (xy 58.66618 -5.198494) (xy 58.708088 -5.135319)
			(xy 58.756474 -5.076957) (xy 58.81079 -5.024069) (xy 58.870419 -4.977254) (xy 58.934687 -4.937042)
			(xy 59.002864 -4.90389) (xy 59.07418 -4.878172) (xy 59.147825 -4.86018) (xy 59.222965 -4.850118)
			(xy 59.298749 -4.848099) (xy 59.374319 -4.854148) (xy 59.448817 -4.868195) (xy 59.5214 -4.890081)
			(xy 59.591246 -4.919558) (xy 59.657563 -4.956293) (xy 59.719599 -4.999868) (xy 59.776652 -5.04979)
			(xy 59.828076 -5.105494) (xy 59.873287 -5.166349) (xy 59.911774 -5.231664) (xy 59.9431 -5.3007) (xy 59.96691 -5.372675)
			(xy 59.982935 -5.446773) (xy 59.990994 -5.522154) (xy 59.991498 -5.56006) (xy 61.107577 -5.56006)
			(xy 61.111612 -5.484356) (xy 61.123671 -5.409511) (xy 61.143617 -5.33637) (xy 61.171224 -5.265765)
			(xy 61.20618 -5.198494) (xy 61.248088 -5.135319) (xy 61.296474 -5.076957) (xy 61.35079 -5.024069)
			(xy 61.410419 -4.977254) (xy 61.474687 -4.937042) (xy 61.542864 -4.90389) (xy 61.61418 -4.878172)
			(xy 61.687825 -4.86018) (xy 61.762965 -4.850118) (xy 61.838749 -4.848099) (xy 61.914319 -4.854148)
			(xy 61.988817 -4.868195) (xy 62.0614 -4.890081) (xy 62.131246 -4.919558) (xy 62.197563 -4.956293)
			(xy 62.259599 -4.999868) (xy 62.265544 -5.00507) (xy 86.197697 -5.00507) (xy 86.201732 -4.929366)
			(xy 86.213791 -4.854521) (xy 86.233737 -4.78138) (xy 86.261344 -4.710775) (xy 86.2963 -4.643504)
			(xy 86.338208 -4.580329) (xy 86.386594 -4.521967) (xy 86.44091 -4.469079) (xy 86.500539 -4.422264)
			(xy 86.564807 -4.382052) (xy 86.632984 -4.3489) (xy 86.7043 -4.323182) (xy 86.777945 -4.30519) (xy 86.853085 -4.295128)
			(xy 86.928869 -4.293109) (xy 87.004439 -4.299158) (xy 87.078937 -4.313205) (xy 87.15152 -4.335091)
			(xy 87.221366 -4.364568) (xy 87.287683 -4.401303) (xy 87.349719 -4.444878) (xy 87.406772 -4.4948)
			(xy 87.458196 -4.550504) (xy 87.503407 -4.611359) (xy 87.541894 -4.676674) (xy 87.57322 -4.74571)
			(xy 87.59703 -4.817685) (xy 87.613055 -4.891783) (xy 87.621114 -4.967164) (xy 87.621618 -5.00507)
			(xy 88.737697 -5.00507) (xy 88.741732 -4.929366) (xy 88.753791 -4.854521) (xy 88.773737 -4.78138)
			(xy 88.801344 -4.710775) (xy 88.8363 -4.643504) (xy 88.878208 -4.580329) (xy 88.926594 -4.521967)
			(xy 88.98091 -4.469079) (xy 89.040539 -4.422264) (xy 89.104807 -4.382052) (xy 89.172984 -4.3489)
			(xy 89.2443 -4.323182) (xy 89.317945 -4.30519) (xy 89.393085 -4.295128) (xy 89.468869 -4.293109)
			(xy 89.544439 -4.299158) (xy 89.618937 -4.313205) (xy 89.69152 -4.335091) (xy 89.761366 -4.364568)
			(xy 89.827683 -4.401303) (xy 89.889719 -4.444878) (xy 89.946772 -4.4948) (xy 89.998196 -4.550504)
			(xy 90.043407 -4.611359) (xy 90.081894 -4.676674) (xy 90.11322 -4.74571) (xy 90.13703 -4.817685)
			(xy 90.153055 -4.891783) (xy 90.161114 -4.967164) (xy 90.161618 -5.00507) (xy 91.277697 -5.00507)
			(xy 91.281732 -4.929366) (xy 91.293791 -4.854521) (xy 91.313737 -4.78138) (xy 91.341344 -4.710775)
			(xy 91.3763 -4.643504) (xy 91.418208 -4.580329) (xy 91.466594 -4.521967) (xy 91.52091 -4.469079)
			(xy 91.580539 -4.422264) (xy 91.644807 -4.382052) (xy 91.712984 -4.3489) (xy 91.7843 -4.323182) (xy 91.857945 -4.30519)
			(xy 91.933085 -4.295128) (xy 92.008869 -4.293109) (xy 92.084439 -4.299158) (xy 92.158937 -4.313205)
			(xy 92.23152 -4.335091) (xy 92.301366 -4.364568) (xy 92.367683 -4.401303) (xy 92.429719 -4.444878)
			(xy 92.486772 -4.4948) (xy 92.538196 -4.550504) (xy 92.583407 -4.611359) (xy 92.621894 -4.676674)
			(xy 92.65322 -4.74571) (xy 92.67703 -4.817685) (xy 92.693055 -4.891783) (xy 92.701114 -4.967164)
			(xy 92.701618 -5.00507) (xy 92.701114 -5.042976) (xy 92.693055 -5.118357) (xy 92.67703 -5.192455)
			(xy 92.65322 -5.26443) (xy 92.621894 -5.333466) (xy 92.583407 -5.398781) (xy 92.538196 -5.459636)
			(xy 92.486772 -5.51534) (xy 92.429719 -5.565262) (xy 92.367683 -5.608837) (xy 92.301366 -5.645572)
			(xy 92.23152 -5.675049) (xy 92.158937 -5.696935) (xy 92.084439 -5.710982) (xy 92.008869 -5.717031)
			(xy 91.933085 -5.715012) (xy 91.857945 -5.70495) (xy 91.7843 -5.686958) (xy 91.712984 -5.66124) (xy 91.644807 -5.628088)
			(xy 91.580539 -5.587876) (xy 91.52091 -5.541061) (xy 91.466594 -5.488173) (xy 91.418208 -5.429811)
			(xy 91.3763 -5.366636) (xy 91.341344 -5.299365) (xy 91.313737 -5.22876) (xy 91.293791 -5.155619)
			(xy 91.281732 -5.080774) (xy 91.277697 -5.00507) (xy 90.161618 -5.00507) (xy 90.161114 -5.042976)
			(xy 90.153055 -5.118357) (xy 90.13703 -5.192455) (xy 90.11322 -5.26443) (xy 90.081894 -5.333466)
			(xy 90.043407 -5.398781) (xy 89.998196 -5.459636) (xy 89.946772 -5.51534) (xy 89.889719 -5.565262)
			(xy 89.827683 -5.608837) (xy 89.761366 -5.645572) (xy 89.69152 -5.675049) (xy 89.618937 -5.696935)
			(xy 89.544439 -5.710982) (xy 89.468869 -5.717031) (xy 89.393085 -5.715012) (xy 89.317945 -5.70495)
			(xy 89.2443 -5.686958) (xy 89.172984 -5.66124) (xy 89.104807 -5.628088) (xy 89.040539 -5.587876)
			(xy 88.98091 -5.541061) (xy 88.926594 -5.488173) (xy 88.878208 -5.429811) (xy 88.8363 -5.366636)
			(xy 88.801344 -5.299365) (xy 88.773737 -5.22876) (xy 88.753791 -5.155619) (xy 88.741732 -5.080774)
			(xy 88.737697 -5.00507) (xy 87.621618 -5.00507) (xy 87.621114 -5.042976) (xy 87.613055 -5.118357)
			(xy 87.59703 -5.192455) (xy 87.57322 -5.26443) (xy 87.541894 -5.333466) (xy 87.503407 -5.398781)
			(xy 87.458196 -5.459636) (xy 87.406772 -5.51534) (xy 87.349719 -5.565262) (xy 87.287683 -5.608837)
			(xy 87.221366 -5.645572) (xy 87.15152 -5.675049) (xy 87.078937 -5.696935) (xy 87.004439 -5.710982)
			(xy 86.928869 -5.717031) (xy 86.853085 -5.715012) (xy 86.777945 -5.70495) (xy 86.7043 -5.686958)
			(xy 86.632984 -5.66124) (xy 86.564807 -5.628088) (xy 86.500539 -5.587876) (xy 86.44091 -5.541061)
			(xy 86.386594 -5.488173) (xy 86.338208 -5.429811) (xy 86.2963 -5.366636) (xy 86.261344 -5.299365)
			(xy 86.233737 -5.22876) (xy 86.213791 -5.155619) (xy 86.201732 -5.080774) (xy 86.197697 -5.00507)
			(xy 62.265544 -5.00507) (xy 62.316652 -5.04979) (xy 62.368076 -5.105494) (xy 62.413287 -5.166349)
			(xy 62.451774 -5.231664) (xy 62.4831 -5.3007) (xy 62.50691 -5.372675) (xy 62.522935 -5.446773) (xy 62.530994 -5.522154)
			(xy 62.531498 -5.56006) (xy 62.530994 -5.597966) (xy 62.522935 -5.673347) (xy 62.50691 -5.747445)
			(xy 62.4831 -5.81942) (xy 62.451774 -5.888456) (xy 62.413287 -5.953771) (xy 62.368076 -6.014626)
			(xy 62.316652 -6.07033) (xy 62.259599 -6.120252) (xy 62.197563 -6.163827) (xy 62.131246 -6.200562)
			(xy 62.0614 -6.230039) (xy 61.988817 -6.251925) (xy 61.914319 -6.265972) (xy 61.838749 -6.272021)
			(xy 61.762965 -6.270002) (xy 61.687825 -6.25994) (xy 61.61418 -6.241948) (xy 61.542864 -6.21623)
			(xy 61.474687 -6.183078) (xy 61.410419 -6.142866) (xy 61.35079 -6.096051) (xy 61.296474 -6.043163)
			(xy 61.248088 -5.984801) (xy 61.20618 -5.921626) (xy 61.171224 -5.854355) (xy 61.143617 -5.78375)
			(xy 61.123671 -5.710609) (xy 61.111612 -5.635764) (xy 61.107577 -5.56006) (xy 59.991498 -5.56006)
			(xy 59.990994 -5.597966) (xy 59.982935 -5.673347) (xy 59.96691 -5.747445) (xy 59.9431 -5.81942) (xy 59.911774 -5.888456)
			(xy 59.873287 -5.953771) (xy 59.828076 -6.014626) (xy 59.776652 -6.07033) (xy 59.719599 -6.120252)
			(xy 59.657563 -6.163827) (xy 59.591246 -6.200562) (xy 59.5214 -6.230039) (xy 59.448817 -6.251925)
			(xy 59.374319 -6.265972) (xy 59.298749 -6.272021) (xy 59.222965 -6.270002) (xy 59.147825 -6.25994)
			(xy 59.07418 -6.241948) (xy 59.002864 -6.21623) (xy 58.934687 -6.183078) (xy 58.870419 -6.142866)
			(xy 58.81079 -6.096051) (xy 58.756474 -6.043163) (xy 58.708088 -5.984801) (xy 58.66618 -5.921626)
			(xy 58.631224 -5.854355) (xy 58.603617 -5.78375) (xy 58.583671 -5.710609) (xy 58.571612 -5.635764)
			(xy 58.567577 -5.56006) (xy 57.451498 -5.56006) (xy 57.450994 -5.597966) (xy 57.442935 -5.673347)
			(xy 57.42691 -5.747445) (xy 57.4031 -5.81942) (xy 57.371774 -5.888456) (xy 57.333287 -5.953771) (xy 57.288076 -6.014626)
			(xy 57.236652 -6.07033) (xy 57.179599 -6.120252) (xy 57.117563 -6.163827) (xy 57.051246 -6.200562)
			(xy 56.9814 -6.230039) (xy 56.908817 -6.251925) (xy 56.834319 -6.265972) (xy 56.758749 -6.272021)
			(xy 56.682965 -6.270002) (xy 56.607825 -6.25994) (xy 56.53418 -6.241948) (xy 56.462864 -6.21623)
			(xy 56.394687 -6.183078) (xy 56.330419 -6.142866) (xy 56.27079 -6.096051) (xy 56.216474 -6.043163)
			(xy 56.168088 -5.984801) (xy 56.12618 -5.921626) (xy 56.091224 -5.854355) (xy 56.063617 -5.78375)
			(xy 56.043671 -5.710609) (xy 56.031612 -5.635764) (xy 56.027577 -5.56006) (xy 54.911498 -5.56006)
			(xy 54.910994 -5.597966) (xy 54.902935 -5.673347) (xy 54.88691 -5.747445) (xy 54.8631 -5.81942) (xy 54.831774 -5.888456)
			(xy 54.793287 -5.953771) (xy 54.748076 -6.014626) (xy 54.696652 -6.07033) (xy 54.639599 -6.120252)
			(xy 54.577563 -6.163827) (xy 54.511246 -6.200562) (xy 54.4414 -6.230039) (xy 54.368817 -6.251925)
			(xy 54.294319 -6.265972) (xy 54.218749 -6.272021) (xy 54.142965 -6.270002) (xy 54.067825 -6.25994)
			(xy 53.99418 -6.241948) (xy 53.922864 -6.21623) (xy 53.854687 -6.183078) (xy 53.790419 -6.142866)
			(xy 53.73079 -6.096051) (xy 53.676474 -6.043163) (xy 53.628088 -5.984801) (xy 53.58618 -5.921626)
			(xy 53.551224 -5.854355) (xy 53.523617 -5.78375) (xy 53.503671 -5.710609) (xy 53.491612 -5.635764)
			(xy 53.487577 -5.56006) (xy 52.371498 -5.56006) (xy 52.370994 -5.597966) (xy 52.362935 -5.673347)
			(xy 52.34691 -5.747445) (xy 52.3231 -5.81942) (xy 52.291774 -5.888456) (xy 52.253287 -5.953771) (xy 52.208076 -6.014626)
			(xy 52.156652 -6.07033) (xy 52.099599 -6.120252) (xy 52.037563 -6.163827) (xy 51.971246 -6.200562)
			(xy 51.9014 -6.230039) (xy 51.828817 -6.251925) (xy 51.754319 -6.265972) (xy 51.678749 -6.272021)
			(xy 51.602965 -6.270002) (xy 51.527825 -6.25994) (xy 51.45418 -6.241948) (xy 51.382864 -6.21623)
			(xy 51.314687 -6.183078) (xy 51.250419 -6.142866) (xy 51.19079 -6.096051) (xy 51.136474 -6.043163)
			(xy 51.088088 -5.984801) (xy 51.04618 -5.921626) (xy 51.011224 -5.854355) (xy 50.983617 -5.78375)
			(xy 50.963671 -5.710609) (xy 50.951612 -5.635764) (xy 50.947577 -5.56006) (xy 49.831498 -5.56006)
			(xy 49.830994 -5.597966) (xy 49.822935 -5.673347) (xy 49.80691 -5.747445) (xy 49.7831 -5.81942) (xy 49.751774 -5.888456)
			(xy 49.713287 -5.953771) (xy 49.668076 -6.014626) (xy 49.616652 -6.07033) (xy 49.559599 -6.120252)
			(xy 49.497563 -6.163827) (xy 49.431246 -6.200562) (xy 49.3614 -6.230039) (xy 49.288817 -6.251925)
			(xy 49.214319 -6.265972) (xy 49.138749 -6.272021) (xy 49.062965 -6.270002) (xy 48.987825 -6.25994)
			(xy 48.91418 -6.241948) (xy 48.842864 -6.21623) (xy 48.774687 -6.183078) (xy 48.710419 -6.142866)
			(xy 48.65079 -6.096051) (xy 48.596474 -6.043163) (xy 48.548088 -5.984801) (xy 48.50618 -5.921626)
			(xy 48.471224 -5.854355) (xy 48.443617 -5.78375) (xy 48.423671 -5.710609) (xy 48.411612 -5.635764)
			(xy 48.407577 -5.56006) (xy 47.291498 -5.56006) (xy 47.290994 -5.597966) (xy 47.282935 -5.673347)
			(xy 47.26691 -5.747445) (xy 47.2431 -5.81942) (xy 47.211774 -5.888456) (xy 47.173287 -5.953771) (xy 47.128076 -6.014626)
			(xy 47.076652 -6.07033) (xy 47.019599 -6.120252) (xy 46.957563 -6.163827) (xy 46.891246 -6.200562)
			(xy 46.8214 -6.230039) (xy 46.748817 -6.251925) (xy 46.674319 -6.265972) (xy 46.598749 -6.272021)
			(xy 46.522965 -6.270002) (xy 46.447825 -6.25994) (xy 46.37418 -6.241948) (xy 46.302864 -6.21623)
			(xy 46.234687 -6.183078) (xy 46.170419 -6.142866) (xy 46.11079 -6.096051) (xy 46.056474 -6.043163)
			(xy 46.008088 -5.984801) (xy 45.96618 -5.921626) (xy 45.931224 -5.854355) (xy 45.903617 -5.78375)
			(xy 45.883671 -5.710609) (xy 45.871612 -5.635764) (xy 45.867577 -5.56006) (xy 44.751498 -5.56006)
			(xy 44.750994 -5.597966) (xy 44.742935 -5.673347) (xy 44.72691 -5.747445) (xy 44.7031 -5.81942) (xy 44.671774 -5.888456)
			(xy 44.633287 -5.953771) (xy 44.588076 -6.014626) (xy 44.536652 -6.07033) (xy 44.479599 -6.120252)
			(xy 44.417563 -6.163827) (xy 44.351246 -6.200562) (xy 44.2814 -6.230039) (xy 44.208817 -6.251925)
			(xy 44.134319 -6.265972) (xy 44.058749 -6.272021) (xy 43.982965 -6.270002) (xy 43.907825 -6.25994)
			(xy 43.83418 -6.241948) (xy 43.762864 -6.21623) (xy 43.694687 -6.183078) (xy 43.630419 -6.142866)
			(xy 43.57079 -6.096051) (xy 43.516474 -6.043163) (xy 43.468088 -5.984801) (xy 43.42618 -5.921626)
			(xy 43.391224 -5.854355) (xy 43.363617 -5.78375) (xy 43.343671 -5.710609) (xy 43.331612 -5.635764)
			(xy 43.327577 -5.56006) (xy 42.50107 -5.56006) (xy 42.515537 -5.570272) (xy 42.604599 -5.64273) (xy 42.68851 -5.721096)
			(xy 42.766876 -5.805007) (xy 42.839334 -5.894069) (xy 42.905545 -5.987869) (xy 42.9652 -6.085968)
			(xy 43.018022 -6.18791) (xy 43.055881 -6.27507) (xy 84.927697 -6.27507) (xy 84.931732 -6.199366)
			(xy 84.943791 -6.124521) (xy 84.963737 -6.05138) (xy 84.991344 -5.980775) (xy 85.0263 -5.913504)
			(xy 85.068208 -5.850329) (xy 85.116594 -5.791967) (xy 85.17091 -5.739079) (xy 85.230539 -5.692264)
			(xy 85.294807 -5.652052) (xy 85.362984 -5.6189) (xy 85.4343 -5.593182) (xy 85.507945 -5.57519) (xy 85.583085 -5.565128)
			(xy 85.658869 -5.563109) (xy 85.734439 -5.569158) (xy 85.808937 -5.583205) (xy 85.88152 -5.605091)
			(xy 85.951366 -5.634568) (xy 86.017683 -5.671303) (xy 86.079719 -5.714878) (xy 86.136772 -5.7648)
			(xy 86.188196 -5.820504) (xy 86.233407 -5.881359) (xy 86.271894 -5.946674) (xy 86.30322 -6.01571)
			(xy 86.32703 -6.087685) (xy 86.343055 -6.161783) (xy 86.351114 -6.237164) (xy 86.351618 -6.27507)
			(xy 87.467697 -6.27507) (xy 87.471732 -6.199366) (xy 87.483791 -6.124521) (xy 87.503737 -6.05138)
			(xy 87.531344 -5.980775) (xy 87.5663 -5.913504) (xy 87.608208 -5.850329) (xy 87.656594 -5.791967)
			(xy 87.71091 -5.739079) (xy 87.770539 -5.692264) (xy 87.834807 -5.652052) (xy 87.902984 -5.6189)
			(xy 87.9743 -5.593182) (xy 88.047945 -5.57519) (xy 88.123085 -5.565128) (xy 88.198869 -5.563109)
			(xy 88.274439 -5.569158) (xy 88.348937 -5.583205) (xy 88.42152 -5.605091) (xy 88.491366 -5.634568)
			(xy 88.557683 -5.671303) (xy 88.619719 -5.714878) (xy 88.676772 -5.7648) (xy 88.728196 -5.820504)
			(xy 88.773407 -5.881359) (xy 88.811894 -5.946674) (xy 88.84322 -6.01571) (xy 88.86703 -6.087685)
			(xy 88.883055 -6.161783) (xy 88.891114 -6.237164) (xy 88.891618 -6.27507) (xy 90.007697 -6.27507)
			(xy 90.011732 -6.199366) (xy 90.023791 -6.124521) (xy 90.043737 -6.05138) (xy 90.071344 -5.980775)
			(xy 90.1063 -5.913504) (xy 90.148208 -5.850329) (xy 90.196594 -5.791967) (xy 90.25091 -5.739079)
			(xy 90.310539 -5.692264) (xy 90.374807 -5.652052) (xy 90.442984 -5.6189) (xy 90.5143 -5.593182) (xy 90.587945 -5.57519)
			(xy 90.663085 -5.565128) (xy 90.738869 -5.563109) (xy 90.814439 -5.569158) (xy 90.888937 -5.583205)
			(xy 90.96152 -5.605091) (xy 91.031366 -5.634568) (xy 91.097683 -5.671303) (xy 91.159719 -5.714878)
			(xy 91.216772 -5.7648) (xy 91.268196 -5.820504) (xy 91.313407 -5.881359) (xy 91.351894 -5.946674)
			(xy 91.38322 -6.01571) (xy 91.40703 -6.087685) (xy 91.423055 -6.161783) (xy 91.431114 -6.237164)
			(xy 91.431618 -6.27507) (xy 91.431114 -6.312976) (xy 91.423055 -6.388357) (xy 91.40703 -6.462455)
			(xy 91.38322 -6.53443) (xy 91.351894 -6.603466) (xy 91.313407 -6.668781) (xy 91.268196 -6.729636)
			(xy 91.216772 -6.78534) (xy 91.159719 -6.835262) (xy 91.097683 -6.878837) (xy 91.031366 -6.915572)
			(xy 90.96152 -6.945049) (xy 90.888937 -6.966935) (xy 90.814439 -6.980982) (xy 90.738869 -6.987031)
			(xy 90.663085 -6.985012) (xy 90.587945 -6.97495) (xy 90.5143 -6.956958) (xy 90.442984 -6.93124) (xy 90.374807 -6.898088)
			(xy 90.310539 -6.857876) (xy 90.25091 -6.811061) (xy 90.196594 -6.758173) (xy 90.148208 -6.699811)
			(xy 90.1063 -6.636636) (xy 90.071344 -6.569365) (xy 90.043737 -6.49876) (xy 90.023791 -6.425619)
			(xy 90.011732 -6.350774) (xy 90.007697 -6.27507) (xy 88.891618 -6.27507) (xy 88.891114 -6.312976)
			(xy 88.883055 -6.388357) (xy 88.86703 -6.462455) (xy 88.84322 -6.53443) (xy 88.811894 -6.603466)
			(xy 88.773407 -6.668781) (xy 88.728196 -6.729636) (xy 88.676772 -6.78534) (xy 88.619719 -6.835262)
			(xy 88.557683 -6.878837) (xy 88.491366 -6.915572) (xy 88.42152 -6.945049) (xy 88.348937 -6.966935)
			(xy 88.274439 -6.980982) (xy 88.198869 -6.987031) (xy 88.123085 -6.985012) (xy 88.047945 -6.97495)
			(xy 87.9743 -6.956958) (xy 87.902984 -6.93124) (xy 87.834807 -6.898088) (xy 87.770539 -6.857876)
			(xy 87.71091 -6.811061) (xy 87.656594 -6.758173) (xy 87.608208 -6.699811) (xy 87.5663 -6.636636)
			(xy 87.531344 -6.569365) (xy 87.503737 -6.49876) (xy 87.483791 -6.425619) (xy 87.471732 -6.350774)
			(xy 87.467697 -6.27507) (xy 86.351618 -6.27507) (xy 86.351114 -6.312976) (xy 86.343055 -6.388357)
			(xy 86.32703 -6.462455) (xy 86.30322 -6.53443) (xy 86.271894 -6.603466) (xy 86.233407 -6.668781)
			(xy 86.188196 -6.729636) (xy 86.136772 -6.78534) (xy 86.079719 -6.835262) (xy 86.017683 -6.878837)
			(xy 85.951366 -6.915572) (xy 85.88152 -6.945049) (xy 85.808937 -6.966935) (xy 85.734439 -6.980982)
			(xy 85.658869 -6.987031) (xy 85.583085 -6.985012) (xy 85.507945 -6.97495) (xy 85.4343 -6.956958)
			(xy 85.362984 -6.93124) (xy 85.294807 -6.898088) (xy 85.230539 -6.857876) (xy 85.17091 -6.811061)
			(xy 85.116594 -6.758173) (xy 85.068208 -6.699811) (xy 85.0263 -6.636636) (xy 84.991344 -6.569365)
			(xy 84.963737 -6.49876) (xy 84.943791 -6.425619) (xy 84.931732 -6.350774) (xy 84.927697 -6.27507)
			(xy 43.055881 -6.27507) (xy 43.063764 -6.293218) (xy 43.102213 -6.401403) (xy 43.13319 -6.51196)
			(xy 43.156549 -6.624372) (xy 43.172183 -6.738117) (xy 43.180018 -6.852663) (xy 43.180508 -6.91007)
			(xy 43.180381 -6.943251) (xy 43.177842 -7.009565) (xy 43.175428 -7.042658) (xy 43.170272 -7.100942)
			(xy 43.152948 -7.216671) (xy 43.127616 -7.330914) (xy 43.094401 -7.443119) (xy 43.056327 -7.54507)
			(xy 86.197697 -7.54507) (xy 86.201732 -7.469366) (xy 86.213791 -7.394521) (xy 86.233737 -7.32138)
			(xy 86.261344 -7.250775) (xy 86.2963 -7.183504) (xy 86.338208 -7.120329) (xy 86.386594 -7.061967)
			(xy 86.44091 -7.009079) (xy 86.500539 -6.962264) (xy 86.564807 -6.922052) (xy 86.632984 -6.8889)
			(xy 86.7043 -6.863182) (xy 86.777945 -6.84519) (xy 86.853085 -6.835128) (xy 86.928869 -6.833109)
			(xy 87.004439 -6.839158) (xy 87.078937 -6.853205) (xy 87.15152 -6.875091) (xy 87.221366 -6.904568)
			(xy 87.287683 -6.941303) (xy 87.349719 -6.984878) (xy 87.406772 -7.0348) (xy 87.458196 -7.090504)
			(xy 87.503407 -7.151359) (xy 87.541894 -7.216674) (xy 87.57322 -7.28571) (xy 87.59703 -7.357685)
			(xy 87.613055 -7.431783) (xy 87.621114 -7.507164) (xy 87.621618 -7.54507) (xy 88.737697 -7.54507)
			(xy 88.741732 -7.469366) (xy 88.753791 -7.394521) (xy 88.773737 -7.32138) (xy 88.801344 -7.250775)
			(xy 88.8363 -7.183504) (xy 88.878208 -7.120329) (xy 88.926594 -7.061967) (xy 88.98091 -7.009079)
			(xy 89.040539 -6.962264) (xy 89.104807 -6.922052) (xy 89.172984 -6.8889) (xy 89.2443 -6.863182) (xy 89.317945 -6.84519)
			(xy 89.393085 -6.835128) (xy 89.468869 -6.833109) (xy 89.544439 -6.839158) (xy 89.618937 -6.853205)
			(xy 89.69152 -6.875091) (xy 89.761366 -6.904568) (xy 89.827683 -6.941303) (xy 89.889719 -6.984878)
			(xy 89.946772 -7.0348) (xy 89.998196 -7.090504) (xy 90.043407 -7.151359) (xy 90.081894 -7.216674)
			(xy 90.11322 -7.28571) (xy 90.13703 -7.357685) (xy 90.153055 -7.431783) (xy 90.161114 -7.507164)
			(xy 90.161618 -7.54507) (xy 91.277697 -7.54507) (xy 91.281732 -7.469366) (xy 91.293791 -7.394521)
			(xy 91.313737 -7.32138) (xy 91.341344 -7.250775) (xy 91.3763 -7.183504) (xy 91.418208 -7.120329)
			(xy 91.466594 -7.061967) (xy 91.52091 -7.009079) (xy 91.580539 -6.962264) (xy 91.644807 -6.922052)
			(xy 91.712984 -6.8889) (xy 91.7843 -6.863182) (xy 91.857945 -6.84519) (xy 91.933085 -6.835128) (xy 92.008869 -6.833109)
			(xy 92.084439 -6.839158) (xy 92.158937 -6.853205) (xy 92.23152 -6.875091) (xy 92.301366 -6.904568)
			(xy 92.367683 -6.941303) (xy 92.429719 -6.984878) (xy 92.486772 -7.0348) (xy 92.538196 -7.090504)
			(xy 92.583407 -7.151359) (xy 92.621894 -7.216674) (xy 92.65322 -7.28571) (xy 92.67703 -7.357685)
			(xy 92.693055 -7.431783) (xy 92.701114 -7.507164) (xy 92.701618 -7.54507) (xy 92.701114 -7.582976)
			(xy 92.693055 -7.658357) (xy 92.67703 -7.732455) (xy 92.65322 -7.80443) (xy 92.621894 -7.873466)
			(xy 92.583407 -7.938781) (xy 92.538196 -7.999636) (xy 92.486772 -8.05534) (xy 92.429719 -8.105262)
			(xy 92.367683 -8.148837) (xy 92.301366 -8.185572) (xy 92.23152 -8.215049) (xy 92.158937 -8.236935)
			(xy 92.084439 -8.250982) (xy 92.008869 -8.257031) (xy 91.933085 -8.255012) (xy 91.857945 -8.24495)
			(xy 91.7843 -8.226958) (xy 91.712984 -8.20124) (xy 91.644807 -8.168088) (xy 91.580539 -8.127876)
			(xy 91.52091 -8.081061) (xy 91.466594 -8.028173) (xy 91.418208 -7.969811) (xy 91.3763 -7.906636)
			(xy 91.341344 -7.839365) (xy 91.313737 -7.76876) (xy 91.293791 -7.695619) (xy 91.281732 -7.620774)
			(xy 91.277697 -7.54507) (xy 90.161618 -7.54507) (xy 90.161114 -7.582976) (xy 90.153055 -7.658357)
			(xy 90.13703 -7.732455) (xy 90.11322 -7.80443) (xy 90.081894 -7.873466) (xy 90.043407 -7.938781)
			(xy 89.998196 -7.999636) (xy 89.946772 -8.05534) (xy 89.889719 -8.105262) (xy 89.827683 -8.148837)
			(xy 89.761366 -8.185572) (xy 89.69152 -8.215049) (xy 89.618937 -8.236935) (xy 89.544439 -8.250982)
			(xy 89.468869 -8.257031) (xy 89.393085 -8.255012) (xy 89.317945 -8.24495) (xy 89.2443 -8.226958)
			(xy 89.172984 -8.20124) (xy 89.104807 -8.168088) (xy 89.040539 -8.127876) (xy 88.98091 -8.081061)
			(xy 88.926594 -8.028173) (xy 88.878208 -7.969811) (xy 88.8363 -7.906636) (xy 88.801344 -7.839365)
			(xy 88.773737 -7.76876) (xy 88.753791 -7.695619) (xy 88.741732 -7.620774) (xy 88.737697 -7.54507)
			(xy 87.621618 -7.54507) (xy 87.621114 -7.582976) (xy 87.613055 -7.658357) (xy 87.59703 -7.732455)
			(xy 87.57322 -7.80443) (xy 87.541894 -7.873466) (xy 87.503407 -7.938781) (xy 87.458196 -7.999636)
			(xy 87.406772 -8.05534) (xy 87.349719 -8.105262) (xy 87.287683 -8.148837) (xy 87.221366 -8.185572)
			(xy 87.15152 -8.215049) (xy 87.078937 -8.236935) (xy 87.004439 -8.250982) (xy 86.928869 -8.257031)
			(xy 86.853085 -8.255012) (xy 86.777945 -8.24495) (xy 86.7043 -8.226958) (xy 86.632984 -8.20124) (xy 86.564807 -8.168088)
			(xy 86.500539 -8.127876) (xy 86.44091 -8.081061) (xy 86.386594 -8.028173) (xy 86.338208 -7.969811)
			(xy 86.2963 -7.906636) (xy 86.261344 -7.839365) (xy 86.233737 -7.76876) (xy 86.213791 -7.695619)
			(xy 86.201732 -7.620774) (xy 86.197697 -7.54507) (xy 43.056327 -7.54507) (xy 43.055094 -7.548372)
			(xy 43.328336 -7.548372) (xy 44.751244 -7.548372) (xy 44.751244 -8.26008) (xy 45.867577 -8.26008)
			(xy 45.871612 -8.184376) (xy 45.883671 -8.109531) (xy 45.903617 -8.03639) (xy 45.931224 -7.965785)
			(xy 45.96618 -7.898514) (xy 46.008088 -7.835339) (xy 46.056474 -7.776977) (xy 46.11079 -7.724089)
			(xy 46.170419 -7.677274) (xy 46.234687 -7.637062) (xy 46.302864 -7.60391) (xy 46.37418 -7.578192)
			(xy 46.447825 -7.5602) (xy 46.522965 -7.550138) (xy 46.598749 -7.548119) (xy 46.674319 -7.554168)
			(xy 46.748817 -7.568215) (xy 46.8214 -7.590101) (xy 46.891246 -7.619578) (xy 46.957563 -7.656313)
			(xy 47.019599 -7.699888) (xy 47.076652 -7.74981) (xy 47.128076 -7.805514) (xy 47.173287 -7.866369)
			(xy 47.211774 -7.931684) (xy 47.2431 -8.00072) (xy 47.26691 -8.072695) (xy 47.282935 -8.146793) (xy 47.290994 -8.222174)
			(xy 47.291498 -8.26008) (xy 48.407577 -8.26008) (xy 48.411612 -8.184376) (xy 48.423671 -8.109531)
			(xy 48.443617 -8.03639) (xy 48.471224 -7.965785) (xy 48.50618 -7.898514) (xy 48.548088 -7.835339)
			(xy 48.596474 -7.776977) (xy 48.65079 -7.724089) (xy 48.710419 -7.677274) (xy 48.774687 -7.637062)
			(xy 48.842864 -7.60391) (xy 48.91418 -7.578192) (xy 48.987825 -7.5602) (xy 49.062965 -7.550138) (xy 49.138749 -7.548119)
			(xy 49.214319 -7.554168) (xy 49.288817 -7.568215) (xy 49.3614 -7.590101) (xy 49.431246 -7.619578)
			(xy 49.497563 -7.656313) (xy 49.559599 -7.699888) (xy 49.616652 -7.74981) (xy 49.668076 -7.805514)
			(xy 49.713287 -7.866369) (xy 49.751774 -7.931684) (xy 49.7831 -8.00072) (xy 49.80691 -8.072695) (xy 49.822935 -8.146793)
			(xy 49.830994 -8.222174) (xy 49.831498 -8.26008) (xy 50.947577 -8.26008) (xy 50.951612 -8.184376)
			(xy 50.963671 -8.109531) (xy 50.983617 -8.03639) (xy 51.011224 -7.965785) (xy 51.04618 -7.898514)
			(xy 51.088088 -7.835339) (xy 51.136474 -7.776977) (xy 51.19079 -7.724089) (xy 51.250419 -7.677274)
			(xy 51.314687 -7.637062) (xy 51.382864 -7.60391) (xy 51.45418 -7.578192) (xy 51.527825 -7.5602) (xy 51.602965 -7.550138)
			(xy 51.678749 -7.548119) (xy 51.754319 -7.554168) (xy 51.828817 -7.568215) (xy 51.9014 -7.590101)
			(xy 51.971246 -7.619578) (xy 52.037563 -7.656313) (xy 52.099599 -7.699888) (xy 52.156652 -7.74981)
			(xy 52.208076 -7.805514) (xy 52.253287 -7.866369) (xy 52.291774 -7.931684) (xy 52.3231 -8.00072)
			(xy 52.34691 -8.072695) (xy 52.362935 -8.146793) (xy 52.370994 -8.222174) (xy 52.371498 -8.26008)
			(xy 53.487577 -8.26008) (xy 53.491612 -8.184376) (xy 53.503671 -8.109531) (xy 53.523617 -8.03639)
			(xy 53.551224 -7.965785) (xy 53.58618 -7.898514) (xy 53.628088 -7.835339) (xy 53.676474 -7.776977)
			(xy 53.73079 -7.724089) (xy 53.790419 -7.677274) (xy 53.854687 -7.637062) (xy 53.922864 -7.60391)
			(xy 53.99418 -7.578192) (xy 54.067825 -7.5602) (xy 54.142965 -7.550138) (xy 54.218749 -7.548119)
			(xy 54.294319 -7.554168) (xy 54.368817 -7.568215) (xy 54.4414 -7.590101) (xy 54.511246 -7.619578)
			(xy 54.577563 -7.656313) (xy 54.639599 -7.699888) (xy 54.696652 -7.74981) (xy 54.748076 -7.805514)
			(xy 54.793287 -7.866369) (xy 54.831774 -7.931684) (xy 54.8631 -8.00072) (xy 54.88691 -8.072695) (xy 54.902935 -8.146793)
			(xy 54.910994 -8.222174) (xy 54.911498 -8.26008) (xy 56.027577 -8.26008) (xy 56.031612 -8.184376)
			(xy 56.043671 -8.109531) (xy 56.063617 -8.03639) (xy 56.091224 -7.965785) (xy 56.12618 -7.898514)
			(xy 56.168088 -7.835339) (xy 56.216474 -7.776977) (xy 56.27079 -7.724089) (xy 56.330419 -7.677274)
			(xy 56.394687 -7.637062) (xy 56.462864 -7.60391) (xy 56.53418 -7.578192) (xy 56.607825 -7.5602) (xy 56.682965 -7.550138)
			(xy 56.758749 -7.548119) (xy 56.834319 -7.554168) (xy 56.908817 -7.568215) (xy 56.9814 -7.590101)
			(xy 57.051246 -7.619578) (xy 57.117563 -7.656313) (xy 57.179599 -7.699888) (xy 57.236652 -7.74981)
			(xy 57.288076 -7.805514) (xy 57.333287 -7.866369) (xy 57.371774 -7.931684) (xy 57.4031 -8.00072)
			(xy 57.42691 -8.072695) (xy 57.442935 -8.146793) (xy 57.450994 -8.222174) (xy 57.451498 -8.26008)
			(xy 58.567577 -8.26008) (xy 58.571612 -8.184376) (xy 58.583671 -8.109531) (xy 58.603617 -8.03639)
			(xy 58.631224 -7.965785) (xy 58.66618 -7.898514) (xy 58.708088 -7.835339) (xy 58.756474 -7.776977)
			(xy 58.81079 -7.724089) (xy 58.870419 -7.677274) (xy 58.934687 -7.637062) (xy 59.002864 -7.60391)
			(xy 59.07418 -7.578192) (xy 59.147825 -7.5602) (xy 59.222965 -7.550138) (xy 59.298749 -7.548119)
			(xy 59.374319 -7.554168) (xy 59.448817 -7.568215) (xy 59.5214 -7.590101) (xy 59.591246 -7.619578)
			(xy 59.657563 -7.656313) (xy 59.719599 -7.699888) (xy 59.776652 -7.74981) (xy 59.828076 -7.805514)
			(xy 59.873287 -7.866369) (xy 59.911774 -7.931684) (xy 59.9431 -8.00072) (xy 59.96691 -8.072695) (xy 59.982935 -8.146793)
			(xy 59.990994 -8.222174) (xy 59.991498 -8.26008) (xy 61.107577 -8.26008) (xy 61.111612 -8.184376)
			(xy 61.123671 -8.109531) (xy 61.143617 -8.03639) (xy 61.171224 -7.965785) (xy 61.20618 -7.898514)
			(xy 61.248088 -7.835339) (xy 61.296474 -7.776977) (xy 61.35079 -7.724089) (xy 61.410419 -7.677274)
			(xy 61.474687 -7.637062) (xy 61.542864 -7.60391) (xy 61.61418 -7.578192) (xy 61.687825 -7.5602) (xy 61.762965 -7.550138)
			(xy 61.838749 -7.548119) (xy 61.914319 -7.554168) (xy 61.988817 -7.568215) (xy 62.0614 -7.590101)
			(xy 62.131246 -7.619578) (xy 62.197563 -7.656313) (xy 62.259599 -7.699888) (xy 62.316652 -7.74981)
			(xy 62.368076 -7.805514) (xy 62.413287 -7.866369) (xy 62.451774 -7.931684) (xy 62.4831 -8.00072)
			(xy 62.50691 -8.072695) (xy 62.522935 -8.146793) (xy 62.530994 -8.222174) (xy 62.531498 -8.26008)
			(xy 62.530994 -8.297986) (xy 62.522935 -8.373367) (xy 62.50691 -8.447465) (xy 62.4831 -8.51944) (xy 62.451774 -8.588476)
			(xy 62.413287 -8.653791) (xy 62.368076 -8.714646) (xy 62.316652 -8.77035) (xy 62.265544 -8.81507)
			(xy 84.927697 -8.81507) (xy 84.931732 -8.739366) (xy 84.943791 -8.664521) (xy 84.963737 -8.59138)
			(xy 84.991344 -8.520775) (xy 85.0263 -8.453504) (xy 85.068208 -8.390329) (xy 85.116594 -8.331967)
			(xy 85.17091 -8.279079) (xy 85.230539 -8.232264) (xy 85.294807 -8.192052) (xy 85.362984 -8.1589)
			(xy 85.4343 -8.133182) (xy 85.507945 -8.11519) (xy 85.583085 -8.105128) (xy 85.658869 -8.103109)
			(xy 85.734439 -8.109158) (xy 85.808937 -8.123205) (xy 85.88152 -8.145091) (xy 85.951366 -8.174568)
			(xy 86.017683 -8.211303) (xy 86.079719 -8.254878) (xy 86.136772 -8.3048) (xy 86.188196 -8.360504)
			(xy 86.233407 -8.421359) (xy 86.271894 -8.486674) (xy 86.30322 -8.55571) (xy 86.32703 -8.627685)
			(xy 86.343055 -8.701783) (xy 86.351114 -8.777164) (xy 86.351618 -8.81507) (xy 87.467697 -8.81507)
			(xy 87.471732 -8.739366) (xy 87.483791 -8.664521) (xy 87.503737 -8.59138) (xy 87.531344 -8.520775)
			(xy 87.5663 -8.453504) (xy 87.608208 -8.390329) (xy 87.656594 -8.331967) (xy 87.71091 -8.279079)
			(xy 87.770539 -8.232264) (xy 87.834807 -8.192052) (xy 87.902984 -8.1589) (xy 87.9743 -8.133182) (xy 88.047945 -8.11519)
			(xy 88.123085 -8.105128) (xy 88.198869 -8.103109) (xy 88.274439 -8.109158) (xy 88.348937 -8.123205)
			(xy 88.42152 -8.145091) (xy 88.491366 -8.174568) (xy 88.557683 -8.211303) (xy 88.619719 -8.254878)
			(xy 88.676772 -8.3048) (xy 88.728196 -8.360504) (xy 88.773407 -8.421359) (xy 88.811894 -8.486674)
			(xy 88.84322 -8.55571) (xy 88.86703 -8.627685) (xy 88.883055 -8.701783) (xy 88.891114 -8.777164)
			(xy 88.891618 -8.81507) (xy 90.007697 -8.81507) (xy 90.011732 -8.739366) (xy 90.023791 -8.664521)
			(xy 90.043737 -8.59138) (xy 90.071344 -8.520775) (xy 90.1063 -8.453504) (xy 90.148208 -8.390329)
			(xy 90.196594 -8.331967) (xy 90.25091 -8.279079) (xy 90.310539 -8.232264) (xy 90.374807 -8.192052)
			(xy 90.442984 -8.1589) (xy 90.5143 -8.133182) (xy 90.587945 -8.11519) (xy 90.663085 -8.105128) (xy 90.738869 -8.103109)
			(xy 90.814439 -8.109158) (xy 90.888937 -8.123205) (xy 90.96152 -8.145091) (xy 91.031366 -8.174568)
			(xy 91.097683 -8.211303) (xy 91.159719 -8.254878) (xy 91.165664 -8.26008) (xy 93.154506 -8.26008)
			(xy 93.158522 -8.14381) (xy 93.170549 -8.028095) (xy 93.190531 -7.913485) (xy 93.218373 -7.800526)
			(xy 93.253942 -7.689758) (xy 93.297068 -7.581707) (xy 93.347545 -7.476889) (xy 93.405134 -7.375804)
			(xy 93.46956 -7.278932) (xy 93.540515 -7.186736) (xy 93.617662 -7.099655) (xy 93.700633 -7.018104)
			(xy 93.789033 -6.942472) (xy 93.88244 -6.873118) (xy 93.980409 -6.810375) (xy 94.082473 -6.754539)
			(xy 94.188147 -6.705878) (xy 94.296926 -6.664624) (xy 94.408291 -6.630973) (xy 94.521714 -6.605085)
			(xy 94.636651 -6.587084) (xy 94.752557 -6.577055) (xy 94.868879 -6.575047) (xy 94.985062 -6.581069)
			(xy 95.100553 -6.595092) (xy 95.214801 -6.61705) (xy 95.327262 -6.646837) (xy 95.4374 -6.684312)
			(xy 95.54469 -6.729297) (xy 95.648621 -6.781576) (xy 95.748697 -6.840901) (xy 95.844443 -6.906989)
			(xy 95.9354 -6.979525) (xy 96.021136 -7.058164) (xy 96.101243 -7.14253) (xy 96.175339 -7.232222)
			(xy 96.243069 -7.326812) (xy 96.304113 -7.42585) (xy 96.358178 -7.528863) (xy 96.405008 -7.63536)
			(xy 96.444379 -7.744835) (xy 96.476103 -7.856765) (xy 96.500029 -7.970617) (xy 96.516043 -8.085849)
			(xy 96.52407 -8.201911) (xy 96.524572 -8.26008) (xy 96.52407 -8.318249) (xy 96.516043 -8.434311)
			(xy 96.500029 -8.549543) (xy 96.476103 -8.663395) (xy 96.444379 -8.775325) (xy 96.405008 -8.8848)
			(xy 96.358178 -8.991297) (xy 96.304113 -9.09431) (xy 96.243069 -9.193348) (xy 96.175339 -9.287938)
			(xy 96.101243 -9.37763) (xy 96.021136 -9.461996) (xy 95.9354 -9.540635) (xy 95.844443 -9.613171)
			(xy 95.748697 -9.679259) (xy 95.648621 -9.738584) (xy 95.54469 -9.790863) (xy 95.4374 -9.835848)
			(xy 95.327262 -9.873323) (xy 95.214801 -9.90311) (xy 95.100553 -9.925068) (xy 94.985062 -9.939091)
			(xy 94.868879 -9.945113) (xy 94.752557 -9.943105) (xy 94.636651 -9.933076) (xy 94.521714 -9.915075)
			(xy 94.408291 -9.889187) (xy 94.296926 -9.855536) (xy 94.188147 -9.814282) (xy 94.082473 -9.765621)
			(xy 93.980409 -9.709785) (xy 93.88244 -9.647042) (xy 93.789033 -9.577688) (xy 93.700633 -9.502056)
			(xy 93.617662 -9.420505) (xy 93.540515 -9.333424) (xy 93.46956 -9.241228) (xy 93.405134 -9.144356)
			(xy 93.347545 -9.043271) (xy 93.297068 -8.938453) (xy 93.253942 -8.830402) (xy 93.218373 -8.719634)
			(xy 93.190531 -8.606675) (xy 93.170549 -8.492065) (xy 93.158522 -8.37635) (xy 93.154506 -8.26008)
			(xy 91.165664 -8.26008) (xy 91.216772 -8.3048) (xy 91.268196 -8.360504) (xy 91.313407 -8.421359)
			(xy 91.351894 -8.486674) (xy 91.38322 -8.55571) (xy 91.40703 -8.627685) (xy 91.423055 -8.701783)
			(xy 91.431114 -8.777164) (xy 91.431618 -8.81507) (xy 91.431114 -8.852976) (xy 91.423055 -8.928357)
			(xy 91.40703 -9.002455) (xy 91.38322 -9.07443) (xy 91.351894 -9.143466) (xy 91.313407 -9.208781)
			(xy 91.268196 -9.269636) (xy 91.216772 -9.32534) (xy 91.159719 -9.375262) (xy 91.097683 -9.418837)
			(xy 91.031366 -9.455572) (xy 90.96152 -9.485049) (xy 90.888937 -9.506935) (xy 90.814439 -9.520982)
			(xy 90.738869 -9.527031) (xy 90.663085 -9.525012) (xy 90.587945 -9.51495) (xy 90.5143 -9.496958)
			(xy 90.442984 -9.47124) (xy 90.374807 -9.438088) (xy 90.310539 -9.397876) (xy 90.25091 -9.351061)
			(xy 90.196594 -9.298173) (xy 90.148208 -9.239811) (xy 90.1063 -9.176636) (xy 90.071344 -9.109365)
			(xy 90.043737 -9.03876) (xy 90.023791 -8.965619) (xy 90.011732 -8.890774) (xy 90.007697 -8.81507)
			(xy 88.891618 -8.81507) (xy 88.891114 -8.852976) (xy 88.883055 -8.928357) (xy 88.86703 -9.002455)
			(xy 88.84322 -9.07443) (xy 88.811894 -9.143466) (xy 88.773407 -9.208781) (xy 88.728196 -9.269636)
			(xy 88.676772 -9.32534) (xy 88.619719 -9.375262) (xy 88.557683 -9.418837) (xy 88.491366 -9.455572)
			(xy 88.42152 -9.485049) (xy 88.348937 -9.506935) (xy 88.274439 -9.520982) (xy 88.198869 -9.527031)
			(xy 88.123085 -9.525012) (xy 88.047945 -9.51495) (xy 87.9743 -9.496958) (xy 87.902984 -9.47124) (xy 87.834807 -9.438088)
			(xy 87.770539 -9.397876) (xy 87.71091 -9.351061) (xy 87.656594 -9.298173) (xy 87.608208 -9.239811)
			(xy 87.5663 -9.176636) (xy 87.531344 -9.109365) (xy 87.503737 -9.03876) (xy 87.483791 -8.965619)
			(xy 87.471732 -8.890774) (xy 87.467697 -8.81507) (xy 86.351618 -8.81507) (xy 86.351114 -8.852976)
			(xy 86.343055 -8.928357) (xy 86.32703 -9.002455) (xy 86.30322 -9.07443) (xy 86.271894 -9.143466)
			(xy 86.233407 -9.208781) (xy 86.188196 -9.269636) (xy 86.136772 -9.32534) (xy 86.079719 -9.375262)
			(xy 86.017683 -9.418837) (xy 85.951366 -9.455572) (xy 85.88152 -9.485049) (xy 85.808937 -9.506935)
			(xy 85.734439 -9.520982) (xy 85.658869 -9.527031) (xy 85.583085 -9.525012) (xy 85.507945 -9.51495)
			(xy 85.4343 -9.496958) (xy 85.362984 -9.47124) (xy 85.294807 -9.438088) (xy 85.230539 -9.397876)
			(xy 85.17091 -9.351061) (xy 85.116594 -9.298173) (xy 85.068208 -9.239811) (xy 85.0263 -9.176636)
			(xy 84.991344 -9.109365) (xy 84.963737 -9.03876) (xy 84.943791 -8.965619) (xy 84.931732 -8.890774)
			(xy 84.927697 -8.81507) (xy 62.265544 -8.81507) (xy 62.259599 -8.820272) (xy 62.197563 -8.863847)
			(xy 62.131246 -8.900582) (xy 62.0614 -8.930059) (xy 61.988817 -8.951945) (xy 61.914319 -8.965992)
			(xy 61.838749 -8.972041) (xy 61.762965 -8.970022) (xy 61.687825 -8.95996) (xy 61.61418 -8.941968)
			(xy 61.542864 -8.91625) (xy 61.474687 -8.883098) (xy 61.410419 -8.842886) (xy 61.35079 -8.796071)
			(xy 61.296474 -8.743183) (xy 61.248088 -8.684821) (xy 61.20618 -8.621646) (xy 61.171224 -8.554375)
			(xy 61.143617 -8.48377) (xy 61.123671 -8.410629) (xy 61.111612 -8.335784) (xy 61.107577 -8.26008)
			(xy 59.991498 -8.26008) (xy 59.990994 -8.297986) (xy 59.982935 -8.373367) (xy 59.96691 -8.447465)
			(xy 59.9431 -8.51944) (xy 59.911774 -8.588476) (xy 59.873287 -8.653791) (xy 59.828076 -8.714646)
			(xy 59.776652 -8.77035) (xy 59.719599 -8.820272) (xy 59.657563 -8.863847) (xy 59.591246 -8.900582)
			(xy 59.5214 -8.930059) (xy 59.448817 -8.951945) (xy 59.374319 -8.965992) (xy 59.298749 -8.972041)
			(xy 59.222965 -8.970022) (xy 59.147825 -8.95996) (xy 59.07418 -8.941968) (xy 59.002864 -8.91625)
			(xy 58.934687 -8.883098) (xy 58.870419 -8.842886) (xy 58.81079 -8.796071) (xy 58.756474 -8.743183)
			(xy 58.708088 -8.684821) (xy 58.66618 -8.621646) (xy 58.631224 -8.554375) (xy 58.603617 -8.48377)
			(xy 58.583671 -8.410629) (xy 58.571612 -8.335784) (xy 58.567577 -8.26008) (xy 57.451498 -8.26008)
			(xy 57.450994 -8.297986) (xy 57.442935 -8.373367) (xy 57.42691 -8.447465) (xy 57.4031 -8.51944) (xy 57.371774 -8.588476)
			(xy 57.333287 -8.653791) (xy 57.288076 -8.714646) (xy 57.236652 -8.77035) (xy 57.179599 -8.820272)
			(xy 57.117563 -8.863847) (xy 57.051246 -8.900582) (xy 56.9814 -8.930059) (xy 56.908817 -8.951945)
			(xy 56.834319 -8.965992) (xy 56.758749 -8.972041) (xy 56.682965 -8.970022) (xy 56.607825 -8.95996)
			(xy 56.53418 -8.941968) (xy 56.462864 -8.91625) (xy 56.394687 -8.883098) (xy 56.330419 -8.842886)
			(xy 56.27079 -8.796071) (xy 56.216474 -8.743183) (xy 56.168088 -8.684821) (xy 56.12618 -8.621646)
			(xy 56.091224 -8.554375) (xy 56.063617 -8.48377) (xy 56.043671 -8.410629) (xy 56.031612 -8.335784)
			(xy 56.027577 -8.26008) (xy 54.911498 -8.26008) (xy 54.910994 -8.297986) (xy 54.902935 -8.373367)
			(xy 54.88691 -8.447465) (xy 54.8631 -8.51944) (xy 54.831774 -8.588476) (xy 54.793287 -8.653791) (xy 54.748076 -8.714646)
			(xy 54.696652 -8.77035) (xy 54.639599 -8.820272) (xy 54.577563 -8.863847) (xy 54.511246 -8.900582)
			(xy 54.4414 -8.930059) (xy 54.368817 -8.951945) (xy 54.294319 -8.965992) (xy 54.218749 -8.972041)
			(xy 54.142965 -8.970022) (xy 54.067825 -8.95996) (xy 53.99418 -8.941968) (xy 53.922864 -8.91625)
			(xy 53.854687 -8.883098) (xy 53.790419 -8.842886) (xy 53.73079 -8.796071) (xy 53.676474 -8.743183)
			(xy 53.628088 -8.684821) (xy 53.58618 -8.621646) (xy 53.551224 -8.554375) (xy 53.523617 -8.48377)
			(xy 53.503671 -8.410629) (xy 53.491612 -8.335784) (xy 53.487577 -8.26008) (xy 52.371498 -8.26008)
			(xy 52.370994 -8.297986) (xy 52.362935 -8.373367) (xy 52.34691 -8.447465) (xy 52.3231 -8.51944) (xy 52.291774 -8.588476)
			(xy 52.253287 -8.653791) (xy 52.208076 -8.714646) (xy 52.156652 -8.77035) (xy 52.099599 -8.820272)
			(xy 52.037563 -8.863847) (xy 51.971246 -8.900582) (xy 51.9014 -8.930059) (xy 51.828817 -8.951945)
			(xy 51.754319 -8.965992) (xy 51.678749 -8.972041) (xy 51.602965 -8.970022) (xy 51.527825 -8.95996)
			(xy 51.45418 -8.941968) (xy 51.382864 -8.91625) (xy 51.314687 -8.883098) (xy 51.250419 -8.842886)
			(xy 51.19079 -8.796071) (xy 51.136474 -8.743183) (xy 51.088088 -8.684821) (xy 51.04618 -8.621646)
			(xy 51.011224 -8.554375) (xy 50.983617 -8.48377) (xy 50.963671 -8.410629) (xy 50.951612 -8.335784)
			(xy 50.947577 -8.26008) (xy 49.831498 -8.26008) (xy 49.830994 -8.297986) (xy 49.822935 -8.373367)
			(xy 49.80691 -8.447465) (xy 49.7831 -8.51944) (xy 49.751774 -8.588476) (xy 49.713287 -8.653791) (xy 49.668076 -8.714646)
			(xy 49.616652 -8.77035) (xy 49.559599 -8.820272) (xy 49.497563 -8.863847) (xy 49.431246 -8.900582)
			(xy 49.3614 -8.930059) (xy 49.288817 -8.951945) (xy 49.214319 -8.965992) (xy 49.138749 -8.972041)
			(xy 49.062965 -8.970022) (xy 48.987825 -8.95996) (xy 48.91418 -8.941968) (xy 48.842864 -8.91625)
			(xy 48.774687 -8.883098) (xy 48.710419 -8.842886) (xy 48.65079 -8.796071) (xy 48.596474 -8.743183)
			(xy 48.548088 -8.684821) (xy 48.50618 -8.621646) (xy 48.471224 -8.554375) (xy 48.443617 -8.48377)
			(xy 48.423671 -8.410629) (xy 48.411612 -8.335784) (xy 48.407577 -8.26008) (xy 47.291498 -8.26008)
			(xy 47.290994 -8.297986) (xy 47.282935 -8.373367) (xy 47.26691 -8.447465) (xy 47.2431 -8.51944) (xy 47.211774 -8.588476)
			(xy 47.173287 -8.653791) (xy 47.128076 -8.714646) (xy 47.076652 -8.77035) (xy 47.019599 -8.820272)
			(xy 46.957563 -8.863847) (xy 46.891246 -8.900582) (xy 46.8214 -8.930059) (xy 46.748817 -8.951945)
			(xy 46.674319 -8.965992) (xy 46.598749 -8.972041) (xy 46.522965 -8.970022) (xy 46.447825 -8.95996)
			(xy 46.37418 -8.941968) (xy 46.302864 -8.91625) (xy 46.234687 -8.883098) (xy 46.170419 -8.842886)
			(xy 46.11079 -8.796071) (xy 46.056474 -8.743183) (xy 46.008088 -8.684821) (xy 45.96618 -8.621646)
			(xy 45.931224 -8.554375) (xy 45.903617 -8.48377) (xy 45.883671 -8.410629) (xy 45.871612 -8.335784)
			(xy 45.867577 -8.26008) (xy 44.751244 -8.26008) (xy 44.751244 -8.971788) (xy 43.328336 -8.971788)
			(xy 43.328336 -7.548372) (xy 43.055094 -7.548372) (xy 43.053462 -7.552742) (xy 43.004999 -7.659253)
			(xy 42.949245 -7.762135) (xy 42.886471 -7.860891) (xy 42.816981 -7.955042) (xy 42.741111 -8.044132)
			(xy 42.659229 -8.127729) (xy 42.571732 -8.20543) (xy 42.479042 -8.276857) (xy 42.381609 -8.341665)
			(xy 42.279905 -8.39954) (xy 42.174422 -8.450202) (xy 42.065671 -8.493404) (xy 41.954179 -8.528939)
			(xy 41.840485 -8.556634) (xy 41.725141 -8.576354) (xy 41.608704 -8.588005) (xy 41.491739 -8.59153)
			(xy 41.374812 -8.586912) (xy 41.258489 -8.574173) (xy 41.143334 -8.553375) (xy 41.029905 -8.524618)
			(xy 40.91875 -8.488042) (xy 40.810407 -8.443825) (xy 40.705403 -8.392179) (xy 40.604244 -8.333356)
			(xy 40.507421 -8.26764) (xy 40.415403 -8.195349) (xy 40.328636 -8.116834) (xy 40.247539 -8.032474)
			(xy 40.172506 -7.942679) (xy 40.103899 -7.847883) (xy 40.042051 -7.748544) (xy 39.987262 -7.645145)
			(xy 39.939796 -7.538186) (xy 39.899884 -7.428185) (xy 39.86772 -7.315674) (xy 39.843457 -7.201199)
			(xy 39.827215 -7.085313) (xy 39.819072 -6.968579) (xy 39.818564 -6.91007) (xy 36.454201 -6.91007)
			(xy 36.4555 -6.914635) (xy 36.471468 -7.000055) (xy 36.479486 -7.086584) (xy 36.479988 -7.130034)
			(xy 36.479486 -7.173484) (xy 36.471468 -7.260013) (xy 36.4555 -7.345433) (xy 36.431719 -7.429015)
			(xy 36.400327 -7.510047) (xy 36.361593 -7.587836) (xy 36.315846 -7.66172) (xy 36.263477 -7.731067)
			(xy 36.204933 -7.795287) (xy 36.140713 -7.853831) (xy 36.071366 -7.9062) (xy 35.997482 -7.951947)
			(xy 35.919693 -7.990681) (xy 35.838661 -8.022073) (xy 35.755079 -8.045854) (xy 35.669659 -8.061822)
			(xy 35.58313 -8.06984) (xy 35.49623 -8.06984) (xy 35.409701 -8.061822) (xy 35.324281 -8.045854) (xy 35.240699 -8.022073)
			(xy 35.159667 -7.990681) (xy 35.081878 -7.951947) (xy 35.007994 -7.9062) (xy 34.938647 -7.853831)
			(xy 34.874427 -7.795287) (xy 34.815883 -7.731067) (xy 34.763514 -7.66172) (xy 34.717767 -7.587836)
			(xy 34.679033 -7.510047) (xy 34.647641 -7.429015) (xy 34.62386 -7.345433) (xy 34.607892 -7.260013)
			(xy 34.599874 -7.173484) (xy 31.398767 -7.173484) (xy 31.396983 -7.2139) (xy 31.38536 -7.299118)
			(xy 31.366005 -7.38292) (xy 31.352998 -7.423912) (xy 31.345919 -7.444932) (xy 31.330039 -7.486352)
			(xy 31.321248 -7.506716) (xy 31.311162 -7.529378) (xy 31.288926 -7.573724) (xy 31.276798 -7.595362)
			(xy 31.255462 -7.6327) (xy 31.266892 -7.717536) (xy 31.559246 -8.00989) (xy 31.559246 -9.713484)
			(xy 34.599874 -9.713484) (xy 34.599874 -9.626584) (xy 34.607892 -9.540055) (xy 34.62386 -9.454635)
			(xy 34.647641 -9.371053) (xy 34.679033 -9.290021) (xy 34.717767 -9.212232) (xy 34.763514 -9.138348)
			(xy 34.815883 -9.069001) (xy 34.874427 -9.004781) (xy 34.938647 -8.946237) (xy 35.007994 -8.893868)
			(xy 35.081878 -8.848121) (xy 35.159667 -8.809387) (xy 35.240699 -8.777995) (xy 35.324281 -8.754214)
			(xy 35.409701 -8.738246) (xy 35.49623 -8.730228) (xy 35.58313 -8.730228) (xy 35.669659 -8.738246)
			(xy 35.755079 -8.754214) (xy 35.838661 -8.777995) (xy 35.919693 -8.809387) (xy 35.997482 -8.848121)
			(xy 36.071366 -8.893868) (xy 36.140713 -8.946237) (xy 36.204933 -9.004781) (xy 36.263477 -9.069001)
			(xy 36.315846 -9.138348) (xy 36.361593 -9.212232) (xy 36.400327 -9.290021) (xy 36.431719 -9.371053)
			(xy 36.4555 -9.454635) (xy 36.471468 -9.540055) (xy 36.479486 -9.626584) (xy 36.479988 -9.670034)
			(xy 36.479486 -9.713484) (xy 36.471468 -9.800013) (xy 36.4555 -9.885433) (xy 36.431719 -9.969015)
			(xy 36.400327 -10.050047) (xy 36.361593 -10.127836) (xy 36.315846 -10.20172) (xy 36.263477 -10.271067)
			(xy 36.204933 -10.335287) (xy 36.140713 -10.393831) (xy 36.071366 -10.4462) (xy 35.997482 -10.491947)
			(xy 35.919693 -10.530681) (xy 35.838661 -10.562073) (xy 35.755079 -10.585854) (xy 35.669659 -10.601822)
			(xy 35.58313 -10.60984) (xy 35.49623 -10.60984) (xy 35.409701 -10.601822) (xy 35.324281 -10.585854)
			(xy 35.240699 -10.562073) (xy 35.159667 -10.530681) (xy 35.081878 -10.491947) (xy 35.007994 -10.4462)
			(xy 34.938647 -10.393831) (xy 34.874427 -10.335287) (xy 34.815883 -10.271067) (xy 34.763514 -10.20172)
			(xy 34.717767 -10.127836) (xy 34.679033 -10.050047) (xy 34.647641 -9.969015) (xy 34.62386 -9.885433)
			(xy 34.607892 -9.800013) (xy 34.599874 -9.713484) (xy 31.559246 -9.713484) (xy 31.559246 -12.210253)
			(xy 34.598948 -12.210253) (xy 34.602858 -12.124316) (xy 34.614602 -12.039096) (xy 34.634081 -11.955304)
			(xy 34.661134 -11.873642) (xy 34.695533 -11.794793) (xy 34.736991 -11.719416) (xy 34.785161 -11.648141)
			(xy 34.83964 -11.581564) (xy 34.899974 -11.520242) (xy 34.965656 -11.464688) (xy 35.036139 -11.415367)
			(xy 35.110833 -11.37269) (xy 35.189113 -11.337014) (xy 35.270325 -11.308639) (xy 35.353789 -11.2878)
			(xy 35.438807 -11.274673) (xy 35.524669 -11.269368) (xy 35.610657 -11.271927) (xy 35.696052 -11.282331)
			(xy 35.780139 -11.300492) (xy 35.862216 -11.326259) (xy 35.941596 -11.359415) (xy 36.017615 -11.399684)
			(xy 36.089638 -11.446728) (xy 36.157062 -11.500155) (xy 36.219324 -11.559518) (xy 36.275903 -11.62432)
			(xy 36.326325 -11.69402) (xy 36.37017 -11.768034) (xy 36.389056 -11.806682) (xy 36.397277 -11.8226)
			(xy 36.421027 -11.849403) (xy 36.451301 -11.868532) (xy 36.485704 -11.878474) (xy 36.50361 -11.879072)
			(xy 39.304214 -11.879072) (xy 40.117268 -12.692126) (xy 40.1447 -12.701778) (xy 40.169931 -12.710979)
			(xy 40.217713 -12.735496) (xy 40.261584 -12.766473) (xy 40.300676 -12.803298) (xy 40.334216 -12.845242)
			(xy 40.361542 -12.891476) (xy 40.382111 -12.941085) (xy 40.395519 -12.99309) (xy 40.401499 -13.046461)
			(xy 40.401166 -13.057886) (xy 83.794344 -13.057886) (xy 83.798415 -13.002264) (xy 83.810541 -12.947827)
			(xy 83.830464 -12.895736) (xy 83.85776 -12.847101) (xy 83.891846 -12.802958) (xy 83.931995 -12.764249)
			(xy 83.977353 -12.731798) (xy 84.026953 -12.706297) (xy 84.079737 -12.68829) (xy 84.13458 -12.67816)
			(xy 84.190314 -12.676123) (xy 84.245751 -12.682223) (xy 84.299708 -12.696329) (xy 84.351037 -12.718141)
			(xy 84.398643 -12.747195) (xy 84.441511 -12.78287) (xy 84.478728 -12.824407) (xy 84.509501 -12.87092)
			(xy 84.533173 -12.921417) (xy 84.549241 -12.974824) (xy 84.557361 -13.03) (xy 84.55787 -13.057886)
			(xy 84.557361 -13.085772) (xy 84.55511 -13.101066) (xy 86.072724 -13.101066) (xy 86.076795 -13.045444)
			(xy 86.088921 -12.991007) (xy 86.108844 -12.938916) (xy 86.13614 -12.890281) (xy 86.170226 -12.846138)
			(xy 86.210375 -12.807429) (xy 86.255733 -12.774978) (xy 86.305333 -12.749477) (xy 86.358117 -12.73147)
			(xy 86.41296 -12.72134) (xy 86.468694 -12.719303) (xy 86.524131 -12.725403) (xy 86.578088 -12.739509)
			(xy 86.629417 -12.761321) (xy 86.677023 -12.790375) (xy 86.719891 -12.82605) (xy 86.757108 -12.867587)
			(xy 86.787881 -12.9141) (xy 86.790273 -12.919202) (xy 88.083388 -12.919202) (xy 88.087459 -12.86358)
			(xy 88.099585 -12.809143) (xy 88.119508 -12.757052) (xy 88.146804 -12.708417) (xy 88.18089 -12.664274)
			(xy 88.221039 -12.625565) (xy 88.266397 -12.593114) (xy 88.315997 -12.567613) (xy 88.368781 -12.549606)
			(xy 88.423624 -12.539476) (xy 88.479358 -12.537439) (xy 88.534795 -12.543539) (xy 88.588752 -12.557645)
			(xy 88.640081 -12.579457) (xy 88.687687 -12.608511) (xy 88.730555 -12.644186) (xy 88.767772 -12.685723)
			(xy 88.798545 -12.732236) (xy 88.822217 -12.782733) (xy 88.838285 -12.83614) (xy 88.846405 -12.891316)
			(xy 88.846914 -12.919202) (xy 88.846405 -12.947088) (xy 88.838285 -13.002264) (xy 88.822217 -13.055671)
			(xy 88.798545 -13.106168) (xy 88.767772 -13.152681) (xy 88.730555 -13.194218) (xy 88.687687 -13.229893)
			(xy 88.6449 -13.256006) (xy 91.040456 -13.256006) (xy 91.044527 -13.200384) (xy 91.056653 -13.145947)
			(xy 91.076576 -13.093856) (xy 91.103872 -13.045221) (xy 91.137958 -13.001078) (xy 91.178107 -12.962369)
			(xy 91.223465 -12.929918) (xy 91.273065 -12.904417) (xy 91.325849 -12.88641) (xy 91.380692 -12.87628)
			(xy 91.436426 -12.874243) (xy 91.491863 -12.880343) (xy 91.54582 -12.894449) (xy 91.597149 -12.916261)
			(xy 91.644755 -12.945315) (xy 91.687623 -12.98099) (xy 91.72484 -13.022527) (xy 91.755613 -13.06904)
			(xy 91.779285 -13.119537) (xy 91.795353 -13.172944) (xy 91.803473 -13.22812) (xy 91.803838 -13.248132)
			(xy 95.94926 -13.248132) (xy 95.953331 -13.19251) (xy 95.965457 -13.138073) (xy 95.98538 -13.085982)
			(xy 96.012676 -13.037347) (xy 96.046762 -12.993204) (xy 96.086911 -12.954495) (xy 96.132269 -12.922044)
			(xy 96.181869 -12.896543) (xy 96.234653 -12.878536) (xy 96.289496 -12.868406) (xy 96.34523 -12.866369)
			(xy 96.400667 -12.872469) (xy 96.454624 -12.886575) (xy 96.505953 -12.908387) (xy 96.553559 -12.937441)
			(xy 96.596427 -12.973116) (xy 96.633644 -13.014653) (xy 96.664417 -13.061166) (xy 96.688089 -13.111663)
			(xy 96.704157 -13.16507) (xy 96.712277 -13.220246) (xy 96.712786 -13.248132) (xy 96.712277 -13.276018)
			(xy 96.704157 -13.331194) (xy 96.688089 -13.384601) (xy 96.664417 -13.435098) (xy 96.633644 -13.481611)
			(xy 96.596427 -13.523148) (xy 96.553559 -13.558823) (xy 96.505953 -13.587877) (xy 96.454624 -13.609689)
			(xy 96.400667 -13.623795) (xy 96.34523 -13.629895) (xy 96.289496 -13.627858) (xy 96.234653 -13.617728)
			(xy 96.181869 -13.599721) (xy 96.132269 -13.57422) (xy 96.086911 -13.541769) (xy 96.046762 -13.50306)
			(xy 96.012676 -13.458917) (xy 95.98538 -13.410282) (xy 95.965457 -13.358191) (xy 95.953331 -13.303754)
			(xy 95.94926 -13.248132) (xy 91.803838 -13.248132) (xy 91.803982 -13.256006) (xy 91.803473 -13.283892)
			(xy 91.795353 -13.339068) (xy 91.779285 -13.392475) (xy 91.755613 -13.442972) (xy 91.72484 -13.489485)
			(xy 91.687623 -13.531022) (xy 91.644755 -13.566697) (xy 91.597149 -13.595751) (xy 91.54582 -13.617563)
			(xy 91.491863 -13.631669) (xy 91.436426 -13.637769) (xy 91.380692 -13.635732) (xy 91.325849 -13.625602)
			(xy 91.273065 -13.607595) (xy 91.223465 -13.582094) (xy 91.178107 -13.549643) (xy 91.137958 -13.510934)
			(xy 91.103872 -13.466791) (xy 91.076576 -13.418156) (xy 91.056653 -13.366065) (xy 91.044527 -13.311628)
			(xy 91.040456 -13.256006) (xy 88.6449 -13.256006) (xy 88.640081 -13.258947) (xy 88.588752 -13.280759)
			(xy 88.534795 -13.294865) (xy 88.479358 -13.300965) (xy 88.423624 -13.298928) (xy 88.368781 -13.288798)
			(xy 88.315997 -13.270791) (xy 88.266397 -13.24529) (xy 88.221039 -13.212839) (xy 88.18089 -13.17413)
			(xy 88.146804 -13.129987) (xy 88.119508 -13.081352) (xy 88.099585 -13.029261) (xy 88.087459 -12.974824)
			(xy 88.083388 -12.919202) (xy 86.790273 -12.919202) (xy 86.811553 -12.964597) (xy 86.827621 -13.018004)
			(xy 86.835741 -13.07318) (xy 86.83625 -13.101066) (xy 86.835741 -13.128952) (xy 86.827621 -13.184128)
			(xy 86.811553 -13.237535) (xy 86.787881 -13.288032) (xy 86.757108 -13.334545) (xy 86.719891 -13.376082)
			(xy 86.677023 -13.411757) (xy 86.629417 -13.440811) (xy 86.578088 -13.462623) (xy 86.524131 -13.476729)
			(xy 86.468694 -13.482829) (xy 86.41296 -13.480792) (xy 86.358117 -13.470662) (xy 86.305333 -13.452655)
			(xy 86.255733 -13.427154) (xy 86.210375 -13.394703) (xy 86.170226 -13.355994) (xy 86.13614 -13.311851)
			(xy 86.108844 -13.263216) (xy 86.088921 -13.211125) (xy 86.076795 -13.156688) (xy 86.072724 -13.101066)
			(xy 84.55511 -13.101066) (xy 84.549241 -13.140948) (xy 84.533173 -13.194355) (xy 84.509501 -13.244852)
			(xy 84.478728 -13.291365) (xy 84.441511 -13.332902) (xy 84.398643 -13.368577) (xy 84.351037 -13.397631)
			(xy 84.299708 -13.419443) (xy 84.245751 -13.433549) (xy 84.190314 -13.439649) (xy 84.13458 -13.437612)
			(xy 84.079737 -13.427482) (xy 84.026953 -13.409475) (xy 83.977353 -13.383974) (xy 83.931995 -13.351523)
			(xy 83.891846 -13.312814) (xy 83.85776 -13.268671) (xy 83.830464 -13.220036) (xy 83.810541 -13.167945)
			(xy 83.798415 -13.113508) (xy 83.794344 -13.057886) (xy 40.401166 -13.057886) (xy 40.399934 -13.100143)
			(xy 40.390855 -13.153075) (xy 40.37444 -13.204211) (xy 40.36314 -13.228574) (xy 40.35044 -13.254736)
			(xy 40.35044 -13.65631) (xy 40.295068 -13.711682) (xy 40.283607 -13.723815) (xy 40.266893 -13.752692)
			(xy 40.25824 -13.784916) (xy 40.25824 -13.818281) (xy 40.266892 -13.850505) (xy 40.283605 -13.879383)
			(xy 40.295068 -13.891514) (xy 40.319452 -13.915898) (xy 40.386 -13.93317) (xy 40.419274 -13.923772)
			(xy 40.453172 -13.914767) (xy 40.522636 -13.905075) (xy 40.557704 -13.904468) (xy 41.245536 -13.904468)
			(xy 41.277494 -13.90502) (xy 41.340906 -13.913035) (xy 41.402813 -13.928934) (xy 41.462239 -13.952466)
			(xy 41.518248 -13.983261) (xy 41.569956 -14.020832) (xy 41.616547 -14.064587) (xy 41.657287 -14.113837)
			(xy 41.691534 -14.167804) (xy 41.718747 -14.225638) (xy 41.738497 -14.286426) (xy 41.750473 -14.34921)
			(xy 41.754487 -14.413) (xy 41.750473 -14.47679) (xy 41.750305 -14.477672) (xy 60.058738 -14.477672)
			(xy 60.062629 -14.423327) (xy 60.074215 -14.370089) (xy 60.093259 -14.319041) (xy 60.119375 -14.271223)
			(xy 60.15203 -14.227609) (xy 60.190559 -14.189086) (xy 60.234179 -14.156439) (xy 60.282001 -14.130332)
			(xy 60.333052 -14.111296) (xy 60.386293 -14.09972) (xy 60.440639 -14.095838) (xy 60.494984 -14.099731)
			(xy 60.548222 -14.111318) (xy 60.599269 -14.130364) (xy 60.647086 -14.15648) (xy 60.66917 -14.172438)
			(xy 60.688182 -14.186034) (xy 60.730065 -14.206766) (xy 60.775033 -14.219492) (xy 60.82157 -14.223782)
			(xy 60.868107 -14.219492) (xy 60.913075 -14.206766) (xy 60.954958 -14.186034) (xy 60.97397 -14.172438)
			(xy 60.996016 -14.156413) (xy 61.043846 -14.130282) (xy 61.094909 -14.111224) (xy 61.148164 -14.099628)
			(xy 61.202527 -14.095729) (xy 61.256892 -14.099607) (xy 61.310152 -14.111183) (xy 61.361222 -14.130222)
			(xy 61.409062 -14.156335) (xy 61.452699 -14.188991) (xy 61.491243 -14.227526) (xy 61.523911 -14.271154)
			(xy 61.550037 -14.318987) (xy 61.569089 -14.370052) (xy 61.580679 -14.423308) (xy 61.584571 -14.477672)
			(xy 61.962748 -14.477672) (xy 61.966639 -14.423329) (xy 61.978223 -14.370093) (xy 61.997267 -14.319047)
			(xy 62.023381 -14.271231) (xy 62.056034 -14.227619) (xy 62.094562 -14.189097) (xy 62.138179 -14.15645)
			(xy 62.185999 -14.130343) (xy 62.237048 -14.111307) (xy 62.290286 -14.09973) (xy 62.344629 -14.095848)
			(xy 62.398973 -14.099739) (xy 62.452209 -14.111324) (xy 62.503254 -14.130368) (xy 62.55107 -14.156482)
			(xy 62.573154 -14.172438) (xy 62.592166 -14.186034) (xy 62.634049 -14.206766) (xy 62.679017 -14.219492)
			(xy 62.725554 -14.223782) (xy 62.772091 -14.219492) (xy 62.817059 -14.206766) (xy 62.858942 -14.186034)
			(xy 62.877954 -14.172438) (xy 62.9 -14.156412) (xy 62.947832 -14.130278) (xy 62.998896 -14.111218)
			(xy 63.052153 -14.099619) (xy 63.106518 -14.095719) (xy 63.160885 -14.099596) (xy 63.214147 -14.111172)
			(xy 63.26522 -14.13021) (xy 63.313062 -14.156324) (xy 63.356701 -14.188981) (xy 63.395248 -14.227516)
			(xy 63.396609 -14.229334) (xy 84.425788 -14.229334) (xy 84.429859 -14.173712) (xy 84.441985 -14.119275)
			(xy 84.461908 -14.067184) (xy 84.489204 -14.018549) (xy 84.52329 -13.974406) (xy 84.563439 -13.935697)
			(xy 84.608797 -13.903246) (xy 84.658397 -13.877745) (xy 84.711181 -13.859738) (xy 84.766024 -13.849608)
			(xy 84.821758 -13.847571) (xy 84.877195 -13.853671) (xy 84.931152 -13.867777) (xy 84.982481 -13.889589)
			(xy 85.030087 -13.918643) (xy 85.072955 -13.954318) (xy 85.110172 -13.995855) (xy 85.140945 -14.042368)
			(xy 85.164617 -14.092865) (xy 85.180685 -14.146272) (xy 85.188805 -14.201448) (xy 85.189314 -14.229334)
			(xy 85.188805 -14.25722) (xy 85.186592 -14.27226) (xy 87.270588 -14.27226) (xy 87.274659 -14.216638)
			(xy 87.286785 -14.162201) (xy 87.306708 -14.11011) (xy 87.334004 -14.061475) (xy 87.36809 -14.017332)
			(xy 87.408239 -13.978623) (xy 87.453597 -13.946172) (xy 87.503197 -13.920671) (xy 87.555981 -13.902664)
			(xy 87.610824 -13.892534) (xy 87.666558 -13.890497) (xy 87.721995 -13.896597) (xy 87.775952 -13.910703)
			(xy 87.827281 -13.932515) (xy 87.874887 -13.961569) (xy 87.917755 -13.997244) (xy 87.954972 -14.038781)
			(xy 87.985745 -14.085294) (xy 88.009417 -14.135791) (xy 88.025485 -14.189198) (xy 88.033605 -14.244374)
			(xy 88.033817 -14.256004) (xy 94.157798 -14.256004) (xy 94.161869 -14.200382) (xy 94.173995 -14.145945)
			(xy 94.193918 -14.093854) (xy 94.221214 -14.045219) (xy 94.2553 -14.001076) (xy 94.295449 -13.962367)
			(xy 94.340807 -13.929916) (xy 94.390407 -13.904415) (xy 94.443191 -13.886408) (xy 94.498034 -13.876278)
			(xy 94.553768 -13.874241) (xy 94.609205 -13.880341) (xy 94.663162 -13.894447) (xy 94.714491 -13.916259)
			(xy 94.762097 -13.945313) (xy 94.804965 -13.980988) (xy 94.842182 -14.022525) (xy 94.872955 -14.069038)
			(xy 94.896627 -14.119535) (xy 94.912695 -14.172942) (xy 94.920815 -14.228118) (xy 94.921324 -14.256004)
			(xy 94.920815 -14.28389) (xy 94.912695 -14.339066) (xy 94.896627 -14.392473) (xy 94.872955 -14.44297)
			(xy 94.842182 -14.489483) (xy 94.804965 -14.53102) (xy 94.762097 -14.566695) (xy 94.714491 -14.595749)
			(xy 94.663162 -14.617561) (xy 94.609205 -14.631667) (xy 94.553768 -14.637767) (xy 94.498034 -14.63573)
			(xy 94.443191 -14.6256) (xy 94.390407 -14.607593) (xy 94.340807 -14.582092) (xy 94.295449 -14.549641)
			(xy 94.2553 -14.510932) (xy 94.221214 -14.466789) (xy 94.193918 -14.418154) (xy 94.173995 -14.366063)
			(xy 94.161869 -14.311626) (xy 94.157798 -14.256004) (xy 88.033817 -14.256004) (xy 88.034114 -14.27226)
			(xy 88.033605 -14.300146) (xy 88.025485 -14.355322) (xy 88.009417 -14.408729) (xy 87.985745 -14.459226)
			(xy 87.954972 -14.505739) (xy 87.917755 -14.547276) (xy 87.874887 -14.582951) (xy 87.827281 -14.612005)
			(xy 87.775952 -14.633817) (xy 87.721995 -14.647923) (xy 87.666558 -14.654023) (xy 87.610824 -14.651986)
			(xy 87.555981 -14.641856) (xy 87.503197 -14.623849) (xy 87.453597 -14.598348) (xy 87.408239 -14.565897)
			(xy 87.36809 -14.527188) (xy 87.334004 -14.483045) (xy 87.306708 -14.43441) (xy 87.286785 -14.382319)
			(xy 87.274659 -14.327882) (xy 87.270588 -14.27226) (xy 85.186592 -14.27226) (xy 85.180685 -14.312396)
			(xy 85.164617 -14.365803) (xy 85.140945 -14.4163) (xy 85.110172 -14.462813) (xy 85.072955 -14.50435)
			(xy 85.030087 -14.540025) (xy 84.982481 -14.569079) (xy 84.931152 -14.590891) (xy 84.877195 -14.604997)
			(xy 84.821758 -14.611097) (xy 84.766024 -14.60906) (xy 84.711181 -14.59893) (xy 84.658397 -14.580923)
			(xy 84.608797 -14.555422) (xy 84.563439 -14.522971) (xy 84.52329 -14.484262) (xy 84.489204 -14.440119)
			(xy 84.461908 -14.391484) (xy 84.441985 -14.339393) (xy 84.429859 -14.284956) (xy 84.425788 -14.229334)
			(xy 63.396609 -14.229334) (xy 63.427917 -14.271146) (xy 63.454044 -14.318981) (xy 63.473097 -14.370048)
			(xy 63.484688 -14.423306) (xy 63.488581 -14.477672) (xy 63.484696 -14.532039) (xy 63.473113 -14.585299)
			(xy 63.454067 -14.636369) (xy 63.427947 -14.684208) (xy 63.395284 -14.727842) (xy 63.356743 -14.766383)
			(xy 63.313109 -14.799047) (xy 63.26527 -14.825167) (xy 63.2142 -14.844213) (xy 63.16094 -14.855796)
			(xy 63.106573 -14.859681) (xy 63.052207 -14.855788) (xy 62.998949 -14.844198) (xy 62.947882 -14.825145)
			(xy 62.900047 -14.799018) (xy 62.877954 -14.783054) (xy 62.858942 -14.769458) (xy 62.817059 -14.748726)
			(xy 62.772091 -14.736) (xy 62.725554 -14.73171) (xy 62.679017 -14.736) (xy 62.634049 -14.748726)
			(xy 62.592166 -14.769458) (xy 62.573154 -14.783054) (xy 62.551024 -14.798948) (xy 62.503204 -14.825055)
			(xy 62.452156 -14.844092) (xy 62.398918 -14.855669) (xy 62.344574 -14.859552) (xy 62.290231 -14.855662)
			(xy 62.236995 -14.844077) (xy 62.185949 -14.825034) (xy 62.138133 -14.79892) (xy 62.09452 -14.766267)
			(xy 62.055998 -14.72774) (xy 62.023351 -14.684122) (xy 61.997244 -14.636302) (xy 61.978208 -14.585254)
			(xy 61.966631 -14.532016) (xy 61.962748 -14.477672) (xy 61.584571 -14.477672) (xy 61.580687 -14.532037)
			(xy 61.569104 -14.585295) (xy 61.55006 -14.636363) (xy 61.523941 -14.6842) (xy 61.491279 -14.727833)
			(xy 61.45274 -14.766373) (xy 61.409108 -14.799035) (xy 61.361272 -14.825155) (xy 61.310205 -14.844201)
			(xy 61.256947 -14.855785) (xy 61.202582 -14.859671) (xy 61.148218 -14.85578) (xy 61.094962 -14.844192)
			(xy 61.043896 -14.825141) (xy 60.996062 -14.799016) (xy 60.97397 -14.783054) (xy 60.954958 -14.769458)
			(xy 60.913075 -14.748726) (xy 60.868107 -14.736) (xy 60.82157 -14.73171) (xy 60.775033 -14.736) (xy 60.730065 -14.748726)
			(xy 60.688182 -14.769458) (xy 60.66917 -14.783054) (xy 60.647039 -14.798949) (xy 60.599219 -14.825059)
			(xy 60.548169 -14.844098) (xy 60.494929 -14.855677) (xy 60.440583 -14.859562) (xy 60.386238 -14.855672)
			(xy 60.332999 -14.844088) (xy 60.281951 -14.825045) (xy 60.234133 -14.798931) (xy 60.190517 -14.766278)
			(xy 60.151993 -14.727749) (xy 60.119345 -14.68413) (xy 60.093236 -14.636309) (xy 60.074199 -14.585258)
			(xy 60.062621 -14.532018) (xy 60.058738 -14.477672) (xy 41.750305 -14.477672) (xy 41.738497 -14.539574)
			(xy 41.718747 -14.600362) (xy 41.691534 -14.658196) (xy 41.657287 -14.712163) (xy 41.616547 -14.761413)
			(xy 41.569956 -14.805168) (xy 41.518248 -14.842739) (xy 41.462239 -14.873534) (xy 41.402813 -14.897066)
			(xy 41.340906 -14.912965) (xy 41.277494 -14.92098) (xy 41.245536 -14.921484) (xy 40.557704 -14.921484)
			(xy 40.525002 -14.920958) (xy 40.46014 -14.912565) (xy 40.396891 -14.895919) (xy 40.336301 -14.871293)
			(xy 40.279372 -14.839096) (xy 40.252904 -14.819884) (xy 40.219122 -14.794484) (xy 39.401496 -14.794484)
			(xy 39.401496 -14.031468) (xy 39.426896 -14.031468) (xy 39.426896 -13.644626) (xy 39.689024 -13.382498)
			(xy 39.689024 -13.254736) (xy 39.676324 -13.228574) (xy 39.671551 -13.218444) (xy 39.663034 -13.197731)
			(xy 39.659306 -13.187172) (xy 39.649654 -13.15974) (xy 39.030402 -12.540488) (xy 36.467034 -12.540488)
			(xy 36.405058 -12.579858) (xy 36.38931 -12.612878) (xy 36.370408 -12.651519) (xy 36.326603 -12.725557)
			(xy 36.276218 -12.795283) (xy 36.219674 -12.860116) (xy 36.157444 -12.919512) (xy 36.090049 -12.972976)
			(xy 36.018051 -13.020059) (xy 35.942054 -13.060369) (xy 35.862692 -13.093568) (xy 35.780629 -13.119378)
			(xy 35.696552 -13.137584) (xy 35.611163 -13.148034) (xy 35.525176 -13.15064) (xy 35.439311 -13.145381)
			(xy 35.354285 -13.1323) (xy 35.27081 -13.111506) (xy 35.189583 -13.083174) (xy 35.111284 -13.047541)
			(xy 35.036568 -13.004904) (xy 34.966058 -12.955621) (xy 34.900345 -12.900102) (xy 34.839979 -12.838813)
			(xy 34.785463 -12.772265) (xy 34.737255 -12.701016) (xy 34.695756 -12.625662) (xy 34.661315 -12.546831)
			(xy 34.634219 -12.465184) (xy 34.614694 -12.381403) (xy 34.602904 -12.296188) (xy 34.598948 -12.210253)
			(xy 31.559246 -12.210253) (xy 31.559246 -14.418056) (xy 31.934674 -14.793484) (xy 34.599874 -14.793484)
			(xy 34.599874 -14.706584) (xy 34.607892 -14.620055) (xy 34.62386 -14.534635) (xy 34.647641 -14.451053)
			(xy 34.679033 -14.370021) (xy 34.717767 -14.292232) (xy 34.763514 -14.218348) (xy 34.815883 -14.149001)
			(xy 34.874427 -14.084781) (xy 34.938647 -14.026237) (xy 35.007994 -13.973868) (xy 35.081878 -13.928121)
			(xy 35.159667 -13.889387) (xy 35.240699 -13.857995) (xy 35.324281 -13.834214) (xy 35.409701 -13.818246)
			(xy 35.49623 -13.810228) (xy 35.58313 -13.810228) (xy 35.669659 -13.818246) (xy 35.755079 -13.834214)
			(xy 35.838661 -13.857995) (xy 35.919693 -13.889387) (xy 35.997482 -13.928121) (xy 36.071366 -13.973868)
			(xy 36.140713 -14.026237) (xy 36.204933 -14.084781) (xy 36.263477 -14.149001) (xy 36.315846 -14.218348)
			(xy 36.361593 -14.292232) (xy 36.400327 -14.370021) (xy 36.431719 -14.451053) (xy 36.4555 -14.534635)
			(xy 36.471468 -14.620055) (xy 36.479486 -14.706584) (xy 36.479988 -14.750034) (xy 36.479486 -14.793484)
			(xy 36.471468 -14.880013) (xy 36.4555 -14.965433) (xy 36.431719 -15.049015) (xy 36.400327 -15.130047)
			(xy 36.361593 -15.207836) (xy 36.315846 -15.28172) (xy 36.263477 -15.351067) (xy 36.204933 -15.415287)
			(xy 36.140713 -15.473831) (xy 36.071366 -15.5262) (xy 35.997482 -15.571947) (xy 35.919693 -15.610681)
			(xy 35.854373 -15.635986) (xy 85.52764 -15.635986) (xy 85.531711 -15.580364) (xy 85.543837 -15.525927)
			(xy 85.56376 -15.473836) (xy 85.591056 -15.425201) (xy 85.625142 -15.381058) (xy 85.665291 -15.342349)
			(xy 85.710649 -15.309898) (xy 85.760249 -15.284397) (xy 85.813033 -15.26639) (xy 85.867876 -15.25626)
			(xy 85.92361 -15.254223) (xy 85.979047 -15.260323) (xy 86.033004 -15.274429) (xy 86.084333 -15.296241)
			(xy 86.131939 -15.325295) (xy 86.174807 -15.36097) (xy 86.212024 -15.402507) (xy 86.242797 -15.44902)
			(xy 86.266469 -15.499517) (xy 86.282537 -15.552924) (xy 86.290657 -15.6081) (xy 86.291166 -15.635986)
			(xy 86.290657 -15.663872) (xy 86.282537 -15.719048) (xy 86.266469 -15.772455) (xy 86.242797 -15.822952)
			(xy 86.212024 -15.869465) (xy 86.174807 -15.911002) (xy 86.131939 -15.946677) (xy 86.084333 -15.975731)
			(xy 86.033004 -15.997543) (xy 85.979047 -16.011649) (xy 85.92361 -16.017749) (xy 85.867876 -16.015712)
			(xy 85.813033 -16.005582) (xy 85.760249 -15.987575) (xy 85.710649 -15.962074) (xy 85.665291 -15.929623)
			(xy 85.625142 -15.890914) (xy 85.591056 -15.846771) (xy 85.56376 -15.798136) (xy 85.543837 -15.746045)
			(xy 85.531711 -15.691608) (xy 85.52764 -15.635986) (xy 35.854373 -15.635986) (xy 35.838661 -15.642073)
			(xy 35.755079 -15.665854) (xy 35.669659 -15.681822) (xy 35.58313 -15.68984) (xy 35.49623 -15.68984)
			(xy 35.409701 -15.681822) (xy 35.324281 -15.665854) (xy 35.240699 -15.642073) (xy 35.159667 -15.610681)
			(xy 35.081878 -15.571947) (xy 35.007994 -15.5262) (xy 34.938647 -15.473831) (xy 34.874427 -15.415287)
			(xy 34.815883 -15.351067) (xy 34.763514 -15.28172) (xy 34.717767 -15.207836) (xy 34.679033 -15.130047)
			(xy 34.647641 -15.049015) (xy 34.62386 -14.965433) (xy 34.607892 -14.880013) (xy 34.599874 -14.793484)
			(xy 31.934674 -14.793484) (xy 33.527492 -16.386302) (xy 35.27933 -16.386302) (xy 35.295586 -16.381984)
			(xy 35.323018 -16.375126) (xy 35.348432 -16.369248) (xy 35.39977 -16.359971) (xy 35.425634 -16.356584)
			(xy 35.425888 -16.356584) (xy 35.433 -16.355822) (xy 35.476466 -16.351349) (xy 35.563831 -16.349512)
			(xy 35.650989 -16.35579) (xy 35.73719 -16.370127) (xy 35.769755 -16.378711) (xy 60.058687 -16.378711)
			(xy 60.062573 -16.324358) (xy 60.074155 -16.271111) (xy 60.093197 -16.220055) (xy 60.119311 -16.172228)
			(xy 60.151966 -16.128605) (xy 60.190497 -16.090073) (xy 60.234119 -16.057416) (xy 60.281945 -16.031301)
			(xy 60.333001 -16.012258) (xy 60.386247 -16.000674) (xy 60.4406 -15.996787) (xy 60.494953 -16.000675)
			(xy 60.548199 -16.012258) (xy 60.599255 -16.031301) (xy 60.647081 -16.057417) (xy 60.66917 -16.073374)
			(xy 60.688182 -16.08697) (xy 60.730065 -16.107702) (xy 60.775033 -16.120428) (xy 60.82157 -16.124718)
			(xy 60.868107 -16.120428) (xy 60.913075 -16.107702) (xy 60.954958 -16.08697) (xy 60.97397 -16.073374)
			(xy 60.996076 -16.057436) (xy 61.043902 -16.031313) (xy 61.09496 -16.012262) (xy 61.148209 -16.000673)
			(xy 61.202566 -15.99678) (xy 61.256923 -16.000663) (xy 61.310174 -16.012243) (xy 61.361235 -16.031284)
			(xy 61.409067 -16.057399) (xy 61.452694 -16.090055) (xy 61.49123 -16.128588) (xy 61.523889 -16.172214)
			(xy 61.550006 -16.220043) (xy 61.56905 -16.271103) (xy 61.580634 -16.324354) (xy 61.58452 -16.378711)
			(xy 61.962697 -16.378711) (xy 61.966582 -16.32436) (xy 61.978163 -16.271115) (xy 61.997204 -16.220061)
			(xy 62.023317 -16.172236) (xy 62.05597 -16.128614) (xy 62.094499 -16.090083) (xy 62.138119 -16.057428)
			(xy 62.185943 -16.031312) (xy 62.236996 -16.012269) (xy 62.29024 -16.000685) (xy 62.344591 -15.996797)
			(xy 62.398942 -16.000683) (xy 62.452186 -16.012264) (xy 62.503241 -16.031305) (xy 62.551066 -16.057418)
			(xy 62.573154 -16.073374) (xy 62.592166 -16.08697) (xy 62.634049 -16.107702) (xy 62.679017 -16.120428)
			(xy 62.725554 -16.124718) (xy 62.772091 -16.120428) (xy 62.817059 -16.107702) (xy 62.858942 -16.08697)
			(xy 62.877954 -16.073374) (xy 62.90006 -16.057434) (xy 62.947888 -16.031309) (xy 62.998947 -16.012256)
			(xy 63.052198 -16.000665) (xy 63.106557 -15.99677) (xy 63.160916 -16.000652) (xy 63.21417 -16.012232)
			(xy 63.265233 -16.031273) (xy 63.313067 -16.057387) (xy 63.356697 -16.090045) (xy 63.395234 -16.128579)
			(xy 63.427895 -16.172206) (xy 63.454014 -16.220037) (xy 63.473059 -16.271099) (xy 63.484643 -16.324352)
			(xy 63.48853 -16.378711) (xy 63.48464 -16.43307) (xy 63.473053 -16.486322) (xy 63.454005 -16.537383)
			(xy 63.427883 -16.585212) (xy 63.39522 -16.628838) (xy 63.35668 -16.66737) (xy 63.313049 -16.700024)
			(xy 63.265214 -16.726136) (xy 63.214149 -16.745174) (xy 63.160895 -16.756751) (xy 63.106535 -16.76063)
			(xy 63.052177 -16.756732) (xy 62.998926 -16.745138) (xy 62.947868 -16.726082) (xy 62.900042 -16.699954)
			(xy 62.877954 -16.68399) (xy 62.858942 -16.670394) (xy 62.817059 -16.649662) (xy 62.772091 -16.636936)
			(xy 62.725554 -16.632646) (xy 62.679017 -16.636936) (xy 62.634049 -16.649662) (xy 62.592166 -16.670394)
			(xy 62.573154 -16.68399) (xy 62.551084 -16.69997) (xy 62.50326 -16.726086) (xy 62.452207 -16.74513)
			(xy 62.398963 -16.756714) (xy 62.344613 -16.760603) (xy 62.290262 -16.756718) (xy 62.237017 -16.745137)
			(xy 62.185963 -16.726097) (xy 62.138138 -16.699984) (xy 62.094515 -16.667331) (xy 62.055984 -16.628802)
			(xy 62.023329 -16.585182) (xy 61.997213 -16.537359) (xy 61.97817 -16.486305) (xy 61.966585 -16.433061)
			(xy 61.962697 -16.378711) (xy 61.58452 -16.378711) (xy 61.580631 -16.433068) (xy 61.569044 -16.486318)
			(xy 61.549997 -16.537376) (xy 61.523877 -16.585204) (xy 61.491215 -16.628828) (xy 61.452678 -16.667359)
			(xy 61.409048 -16.700013) (xy 61.361216 -16.726125) (xy 61.310154 -16.745163) (xy 61.256902 -16.75674)
			(xy 61.202544 -16.76062) (xy 61.148188 -16.756724) (xy 61.094939 -16.745132) (xy 61.043883 -16.726078)
			(xy 60.996058 -16.699953) (xy 60.97397 -16.68399) (xy 60.954958 -16.670394) (xy 60.913075 -16.649662)
			(xy 60.868107 -16.636936) (xy 60.82157 -16.632646) (xy 60.775033 -16.636936) (xy 60.730065 -16.649662)
			(xy 60.688182 -16.670394) (xy 60.66917 -16.68399) (xy 60.647099 -16.699972) (xy 60.599275 -16.72609)
			(xy 60.54822 -16.745136) (xy 60.494974 -16.756722) (xy 60.440622 -16.760613) (xy 60.386269 -16.756729)
			(xy 60.333022 -16.745148) (xy 60.281965 -16.726108) (xy 60.234137 -16.699995) (xy 60.190513 -16.667342)
			(xy 60.15198 -16.628812) (xy 60.119322 -16.58519) (xy 60.093205 -16.537365) (xy 60.074161 -16.48631)
			(xy 60.062576 -16.433064) (xy 60.058687 -16.378711) (xy 35.769755 -16.378711) (xy 35.821688 -16.3924)
			(xy 35.903755 -16.422418) (xy 35.982683 -16.45992) (xy 36.020502 -16.481806) (xy 41.125648 -16.481806)
			(xy 41.15689 -16.513048) (xy 41.547034 -16.513048) (xy 41.858946 -16.82496) (xy 41.858946 -17.742916)
			(xy 50.87366 -17.742916) (xy 52.525676 -17.742916) (xy 52.525676 -18.053793) (xy 60.058711 -18.053793)
			(xy 60.062599 -17.999443) (xy 60.074183 -17.946201) (xy 60.093226 -17.895148) (xy 60.119341 -17.847326)
			(xy 60.151996 -17.803707) (xy 60.190526 -17.765179) (xy 60.234147 -17.732527) (xy 60.281971 -17.706415)
			(xy 60.333025 -17.687376) (xy 60.386269 -17.675796) (xy 60.440618 -17.671911) (xy 60.494967 -17.675801)
			(xy 60.54821 -17.687386) (xy 60.599262 -17.70643) (xy 60.647083 -17.732547) (xy 60.66917 -17.748504)
			(xy 60.688182 -17.7621) (xy 60.730065 -17.782832) (xy 60.775033 -17.795558) (xy 60.82157 -17.799848)
			(xy 60.868107 -17.795558) (xy 60.913075 -17.782832) (xy 60.954958 -17.7621) (xy 60.97397 -17.748504)
			(xy 60.996048 -17.732525) (xy 61.043876 -17.706398) (xy 61.094936 -17.687344) (xy 61.148188 -17.675752)
			(xy 61.202548 -17.671856) (xy 61.256909 -17.675737) (xy 61.310164 -17.687315) (xy 61.361229 -17.706355)
			(xy 61.409064 -17.732469) (xy 61.452696 -17.765125) (xy 61.491236 -17.803659) (xy 61.523899 -17.847286)
			(xy 61.55002 -17.895117) (xy 61.569068 -17.946179) (xy 61.580655 -17.999432) (xy 61.584544 -18.053793)
			(xy 61.962721 -18.053793) (xy 61.966609 -17.999446) (xy 61.978192 -17.946205) (xy 61.997234 -17.895155)
			(xy 62.023347 -17.847334) (xy 62.056 -17.803716) (xy 62.094528 -17.765189) (xy 62.138147 -17.732538)
			(xy 62.185969 -17.706427) (xy 62.237021 -17.687387) (xy 62.290262 -17.675806) (xy 62.344609 -17.671921)
			(xy 62.398956 -17.675809) (xy 62.452197 -17.687392) (xy 62.503247 -17.706434) (xy 62.551068 -17.732548)
			(xy 62.573154 -17.748504) (xy 62.592166 -17.7621) (xy 62.634049 -17.782832) (xy 62.679017 -17.795558)
			(xy 62.725554 -17.799848) (xy 62.772091 -17.795558) (xy 62.817059 -17.782832) (xy 62.858942 -17.7621)
			(xy 62.877954 -17.748504) (xy 62.900032 -17.732524) (xy 62.947861 -17.706394) (xy 62.998923 -17.687338)
			(xy 63.052177 -17.675743) (xy 63.106539 -17.671846) (xy 63.160902 -17.675726) (xy 63.214159 -17.687304)
			(xy 63.265227 -17.706343) (xy 63.313065 -17.732458) (xy 63.356699 -17.765115) (xy 63.39524 -17.803649)
			(xy 63.427905 -17.847278) (xy 63.454028 -17.895111) (xy 63.473077 -17.946175) (xy 63.484664 -17.99943)
			(xy 63.488554 -18.053793) (xy 63.484666 -18.108155) (xy 63.473081 -18.161411) (xy 63.454034 -18.212476)
			(xy 63.427913 -18.26031) (xy 63.39525 -18.30394) (xy 63.35671 -18.342476) (xy 63.313077 -18.375135)
			(xy 63.26524 -18.401251) (xy 63.214173 -18.420292) (xy 63.160916 -18.431872) (xy 63.106553 -18.435754)
			(xy 63.052191 -18.431859) (xy 62.998937 -18.420266) (xy 62.947874 -18.401212) (xy 62.900044 -18.375084)
			(xy 62.877954 -18.35912) (xy 62.858942 -18.345524) (xy 62.817059 -18.324792) (xy 62.772091 -18.312066)
			(xy 62.725554 -18.307776) (xy 62.679017 -18.312066) (xy 62.634049 -18.324792) (xy 62.592166 -18.345524)
			(xy 62.573154 -18.35912) (xy 62.551056 -18.37506) (xy 62.503234 -18.401172) (xy 62.452183 -18.420212)
			(xy 62.398942 -18.431793) (xy 62.344595 -18.435679) (xy 62.290247 -18.431792) (xy 62.237007 -18.420209)
			(xy 62.185956 -18.401167) (xy 62.138135 -18.375054) (xy 62.094518 -18.342401) (xy 62.055991 -18.303873)
			(xy 62.023339 -18.260254) (xy 61.997228 -18.212432) (xy 61.978188 -18.161381) (xy 61.966607 -18.10814)
			(xy 61.962721 -18.053793) (xy 61.584544 -18.053793) (xy 61.580657 -18.108153) (xy 61.569072 -18.161407)
			(xy 61.550026 -18.21247) (xy 61.523907 -18.260302) (xy 61.491245 -18.30393) (xy 61.452707 -18.342465)
			(xy 61.409076 -18.375123) (xy 61.361242 -18.401239) (xy 61.310178 -18.420281) (xy 61.256923 -18.431861)
			(xy 61.202562 -18.435744) (xy 61.148202 -18.43185) (xy 61.09495 -18.42026) (xy 61.043889 -18.401208)
			(xy 60.99606 -18.375082) (xy 60.97397 -18.35912) (xy 60.954958 -18.345524) (xy 60.913075 -18.324792)
			(xy 60.868107 -18.312066) (xy 60.82157 -18.307776) (xy 60.775033 -18.312066) (xy 60.730065 -18.324792)
			(xy 60.688182 -18.345524) (xy 60.66917 -18.35912) (xy 60.647071 -18.375061) (xy 60.599249 -18.401176)
			(xy 60.548196 -18.420218) (xy 60.494953 -18.431801) (xy 60.440604 -18.435689) (xy 60.386254 -18.431802)
			(xy 60.333011 -18.42022) (xy 60.281958 -18.401179) (xy 60.234135 -18.375065) (xy 60.190515 -18.342412)
			(xy 60.151986 -18.303882) (xy 60.119333 -18.260262) (xy 60.09322 -18.212439) (xy 60.074179 -18.161386)
			(xy 60.062597 -18.108142) (xy 60.058711 -18.053793) (xy 52.525676 -18.053793) (xy 52.525676 -19.394424)
			(xy 50.87366 -19.394424) (xy 50.87366 -17.742916) (xy 41.858946 -17.742916) (xy 41.858946 -18.532602)
			(xy 41.782323 -18.609225) (xy 47.374038 -18.609225) (xy 47.374038 -18.528115) (xy 47.381988 -18.447396)
			(xy 47.397811 -18.367845) (xy 47.421356 -18.290229) (xy 47.452395 -18.215293) (xy 47.49063 -18.143761)
			(xy 47.535692 -18.076321) (xy 47.587147 -18.013622) (xy 47.6445 -17.956269) (xy 47.707199 -17.904814)
			(xy 47.774639 -17.859752) (xy 47.846171 -17.821517) (xy 47.921107 -17.790478) (xy 47.998723 -17.766933)
			(xy 48.078274 -17.75111) (xy 48.158993 -17.74316) (xy 48.240103 -17.74316) (xy 48.320822 -17.75111)
			(xy 48.400373 -17.766933) (xy 48.477989 -17.790478) (xy 48.552925 -17.821517) (xy 48.624457 -17.859752)
			(xy 48.691897 -17.904814) (xy 48.754596 -17.956269) (xy 48.811949 -18.013622) (xy 48.863404 -18.076321)
			(xy 48.908466 -18.143761) (xy 48.946701 -18.215293) (xy 48.97774 -18.290229) (xy 49.001285 -18.367845)
			(xy 49.017108 -18.447396) (xy 49.025058 -18.528115) (xy 49.025556 -18.56867) (xy 49.025058 -18.609225)
			(xy 49.017108 -18.689944) (xy 49.001285 -18.769495) (xy 48.97774 -18.847111) (xy 48.946701 -18.922047)
			(xy 48.908466 -18.993579) (xy 48.863404 -19.061019) (xy 48.811949 -19.123718) (xy 48.754596 -19.181071)
			(xy 48.691897 -19.232526) (xy 48.624457 -19.277588) (xy 48.552925 -19.315823) (xy 48.477989 -19.346862)
			(xy 48.400373 -19.370407) (xy 48.320822 -19.38623) (xy 48.240103 -19.39418) (xy 48.158993 -19.39418)
			(xy 48.078274 -19.38623) (xy 47.998723 -19.370407) (xy 47.921107 -19.346862) (xy 47.846171 -19.315823)
			(xy 47.774639 -19.277588) (xy 47.707199 -19.232526) (xy 47.6445 -19.181071) (xy 47.587147 -19.123718)
			(xy 47.535692 -19.061019) (xy 47.49063 -18.993579) (xy 47.452395 -18.922047) (xy 47.421356 -18.847111)
			(xy 47.397811 -18.769495) (xy 47.381988 -18.689944) (xy 47.374038 -18.609225) (xy 41.782323 -18.609225)
			(xy 40.671496 -19.720052) (xy 40.671496 -20.06501) (xy 60.015149 -20.06501) (xy 60.019036 -20.010648)
			(xy 60.030621 -19.957393) (xy 60.049667 -19.906329) (xy 60.075787 -19.858495) (xy 60.108449 -19.814866)
			(xy 60.146988 -19.77633) (xy 60.19062 -19.743671) (xy 60.238455 -19.717555) (xy 60.289521 -19.698512)
			(xy 60.342777 -19.686932) (xy 60.397139 -19.683049) (xy 60.4515 -19.686943) (xy 60.504754 -19.698534)
			(xy 60.555816 -19.717587) (xy 60.603646 -19.743713) (xy 60.625736 -19.759676) (xy 60.644748 -19.773272)
			(xy 60.686631 -19.794004) (xy 60.731599 -19.80673) (xy 60.778136 -19.81102) (xy 60.824673 -19.80673)
			(xy 60.869641 -19.794004) (xy 60.911524 -19.773272) (xy 60.930536 -19.759676) (xy 60.952638 -19.743741)
			(xy 61.00046 -19.717628) (xy 61.051512 -19.698587) (xy 61.104754 -19.687005) (xy 61.159102 -19.683118)
			(xy 61.21345 -19.687005) (xy 61.266692 -19.698588) (xy 61.317743 -19.717629) (xy 61.365565 -19.743743)
			(xy 61.409184 -19.776396) (xy 61.447711 -19.814925) (xy 61.480363 -19.858545) (xy 61.506475 -19.906367)
			(xy 61.525516 -19.957419) (xy 61.537096 -20.010661) (xy 61.540982 -20.06501) (xy 61.919159 -20.06501)
			(xy 61.923045 -20.01065) (xy 61.934629 -19.957397) (xy 61.953674 -19.906335) (xy 61.979793 -19.858503)
			(xy 62.012453 -19.814875) (xy 62.050991 -19.77634) (xy 62.09462 -19.743682) (xy 62.142453 -19.717566)
			(xy 62.193516 -19.698524) (xy 62.24677 -19.686943) (xy 62.30113 -19.683059) (xy 62.355489 -19.686951)
			(xy 62.408741 -19.69854) (xy 62.459801 -19.717591) (xy 62.50763 -19.743714) (xy 62.52972 -19.759676)
			(xy 62.548732 -19.773272) (xy 62.590615 -19.794004) (xy 62.635583 -19.80673) (xy 62.68212 -19.81102)
			(xy 62.728657 -19.80673) (xy 62.773625 -19.794004) (xy 62.815508 -19.773272) (xy 62.83452 -19.759676)
			(xy 62.856623 -19.743739) (xy 62.904446 -19.717624) (xy 62.955499 -19.69858) (xy 63.008743 -19.686997)
			(xy 63.063093 -19.683108) (xy 63.117443 -19.686995) (xy 63.170687 -19.698576) (xy 63.221741 -19.717618)
			(xy 63.269565 -19.743732) (xy 63.313186 -19.776386) (xy 63.351716 -19.814916) (xy 63.38437 -19.858537)
			(xy 63.410483 -19.906361) (xy 63.429524 -19.957415) (xy 63.441106 -20.010659) (xy 63.444992 -20.06501)
			(xy 63.441103 -20.11936) (xy 63.429519 -20.172603) (xy 63.410475 -20.223656) (xy 63.384359 -20.271479)
			(xy 63.351703 -20.315099) (xy 63.313172 -20.353627) (xy 63.269549 -20.386279) (xy 63.221724 -20.41239)
			(xy 63.170669 -20.431429) (xy 63.117424 -20.443008) (xy 63.063074 -20.446892) (xy 63.008724 -20.443001)
			(xy 62.955481 -20.431414) (xy 62.904428 -20.412368) (xy 62.856607 -20.38625) (xy 62.83452 -20.370292)
			(xy 62.815508 -20.356696) (xy 62.773625 -20.335964) (xy 62.728657 -20.323238) (xy 62.68212 -20.318948)
			(xy 62.635583 -20.323238) (xy 62.590615 -20.335964) (xy 62.548732 -20.356696) (xy 62.52972 -20.370292)
			(xy 62.507646 -20.386275) (xy 62.459819 -20.412401) (xy 62.408759 -20.431454) (xy 62.355508 -20.443046)
			(xy 62.301149 -20.446941) (xy 62.246789 -20.44306) (xy 62.193535 -20.431482) (xy 62.142471 -20.412442)
			(xy 62.094636 -20.386328) (xy 62.051005 -20.353672) (xy 62.012466 -20.315139) (xy 61.979803 -20.271513)
			(xy 61.953682 -20.223683) (xy 61.934635 -20.172621) (xy 61.923048 -20.119369) (xy 61.919159 -20.06501)
			(xy 61.540982 -20.06501) (xy 61.537094 -20.119358) (xy 61.52551 -20.172599) (xy 61.506467 -20.22365)
			(xy 61.480353 -20.271471) (xy 61.447699 -20.315089) (xy 61.409169 -20.353616) (xy 61.365549 -20.386267)
			(xy 61.317726 -20.412378) (xy 61.266673 -20.431418) (xy 61.213431 -20.442997) (xy 61.159083 -20.446882)
			(xy 61.104735 -20.442993) (xy 61.051494 -20.431408) (xy 61.000443 -20.412364) (xy 60.952622 -20.386249)
			(xy 60.930536 -20.370292) (xy 60.911524 -20.356696) (xy 60.869641 -20.335964) (xy 60.824673 -20.323238)
			(xy 60.778136 -20.318948) (xy 60.731599 -20.323238) (xy 60.686631 -20.335964) (xy 60.644748 -20.356696)
			(xy 60.625736 -20.370292) (xy 60.603662 -20.386277) (xy 60.555833 -20.412405) (xy 60.504772 -20.43146)
			(xy 60.451519 -20.443054) (xy 60.397158 -20.446951) (xy 60.342796 -20.443071) (xy 60.289539 -20.431493)
			(xy 60.238473 -20.412453) (xy 60.190636 -20.386339) (xy 60.147003 -20.353683) (xy 60.108461 -20.315149)
			(xy 60.075797 -20.271521) (xy 60.049675 -20.223689) (xy 60.030626 -20.172626) (xy 60.019039 -20.119371)
			(xy 60.015149 -20.06501) (xy 40.671496 -20.06501) (xy 40.671496 -21.013928) (xy 74.290428 -21.013928)
			(xy 74.290428 -19.994372) (xy 74.291055 -19.958314) (xy 74.301257 -19.886924) (xy 74.310748 -19.852132)
			(xy 74.315828 -19.834606) (xy 74.315828 -19.460464) (xy 75.281536 -19.460464) (xy 75.281536 -19.834606)
			(xy 75.286616 -19.852132) (xy 75.296102 -19.886925) (xy 75.306303 -19.958315) (xy 75.306936 -19.994372)
			(xy 75.306936 -20.009612) (xy 75.612244 -20.009612) (xy 75.612244 -19.149822) (xy 75.612742 -19.117095)
			(xy 75.621135 -19.052183) (xy 75.637785 -18.988883) (xy 75.662417 -18.928242) (xy 75.694625 -18.871261)
			(xy 75.713844 -18.844768) (xy 75.739244 -18.810986) (xy 75.739244 -18.793968) (xy 75.754484 -18.793968)
			(xy 75.790298 -18.763488) (xy 75.815475 -18.742635) (xy 75.870207 -18.706884) (xy 75.929072 -18.678445)
			(xy 75.991097 -18.65779) (xy 76.055259 -18.645259) (xy 76.120498 -18.641059) (xy 76.185737 -18.645259)
			(xy 76.249899 -18.65779) (xy 76.311924 -18.678445) (xy 76.370789 -18.706884) (xy 76.425521 -18.742635)
			(xy 76.450698 -18.763488) (xy 76.486512 -18.793968) (xy 76.501752 -18.793968) (xy 76.501752 -18.810986)
			(xy 76.527152 -18.844768) (xy 76.540326 -18.862701) (xy 76.563857 -18.900473) (xy 76.574142 -18.920206)
			(xy 76.581564 -18.933913) (xy 76.601935 -18.957495) (xy 76.627421 -18.975425) (xy 76.656498 -18.986631)
			(xy 76.687426 -18.990443) (xy 76.718354 -18.986631) (xy 76.747431 -18.975425) (xy 76.772917 -18.957495)
			(xy 76.793288 -18.933913) (xy 76.80071 -18.920206) (xy 76.810986 -18.900468) (xy 76.834517 -18.862695)
			(xy 76.8477 -18.844768) (xy 76.8731 -18.810986) (xy 76.8731 -18.793968) (xy 76.88834 -18.793968)
			(xy 76.924154 -18.763488) (xy 76.949331 -18.742635) (xy 77.004063 -18.706884) (xy 77.062928 -18.678445)
			(xy 77.124953 -18.65779) (xy 77.189115 -18.645259) (xy 77.254354 -18.641059) (xy 77.319593 -18.645259)
			(xy 77.383755 -18.65779) (xy 77.44578 -18.678445) (xy 77.504645 -18.706884) (xy 77.559377 -18.742635)
			(xy 77.584554 -18.763488) (xy 77.620368 -18.793968) (xy 77.635608 -18.793968) (xy 77.635608 -18.810986)
			(xy 77.661008 -18.844768) (xy 77.675361 -18.864372) (xy 77.700677 -18.905846) (xy 77.711554 -18.927572)
			(xy 77.718885 -18.941602) (xy 77.73927 -18.965806) (xy 77.764987 -18.984246) (xy 77.794454 -18.995784)
			(xy 77.825854 -18.999711) (xy 77.857254 -18.995784) (xy 77.886721 -18.984246) (xy 77.912438 -18.965806)
			(xy 77.932823 -18.941602) (xy 77.940154 -18.927572) (xy 77.951033 -18.905847) (xy 77.976348 -18.864373)
			(xy 77.9907 -18.844768) (xy 78.0161 -18.810986) (xy 78.0161 -18.793968) (xy 78.03134 -18.793968)
			(xy 78.067154 -18.763488) (xy 78.092331 -18.742635) (xy 78.147063 -18.706884) (xy 78.205928 -18.678445)
			(xy 78.267953 -18.65779) (xy 78.332115 -18.645259) (xy 78.397354 -18.641059) (xy 78.462593 -18.645259)
			(xy 78.526755 -18.65779) (xy 78.58878 -18.678445) (xy 78.647645 -18.706884) (xy 78.702377 -18.742635)
			(xy 78.727554 -18.763488) (xy 78.763368 -18.793968) (xy 78.778608 -18.793968) (xy 78.778608 -18.810986)
			(xy 78.804008 -18.844768) (xy 78.816312 -18.861538) (xy 78.838437 -18.896762) (xy 78.848204 -18.915126)
			(xy 78.855711 -18.928619) (xy 78.876116 -18.951782) (xy 78.901487 -18.969369) (xy 78.930337 -18.98035)
			(xy 78.96098 -18.984083) (xy 78.991623 -18.98035) (xy 79.020473 -18.969369) (xy 79.045844 -18.951782)
			(xy 79.066249 -18.928619) (xy 79.073756 -18.915126) (xy 79.083532 -18.896768) (xy 79.105661 -18.861547)
			(xy 79.117952 -18.844768) (xy 79.143352 -18.810986) (xy 79.143352 -18.793968) (xy 79.158592 -18.793968)
			(xy 79.194406 -18.763488) (xy 79.219583 -18.742635) (xy 79.274315 -18.706884) (xy 79.33318 -18.678445)
			(xy 79.395205 -18.65779) (xy 79.459367 -18.645259) (xy 79.524606 -18.641059) (xy 79.589845 -18.645259)
			(xy 79.654007 -18.65779) (xy 79.716032 -18.678445) (xy 79.774897 -18.706884) (xy 79.829629 -18.742635)
			(xy 79.854806 -18.763488) (xy 79.89062 -18.793968) (xy 79.90586 -18.793968) (xy 79.90586 -18.810986)
			(xy 79.93126 -18.844768) (xy 79.944863 -18.863335) (xy 79.96903 -18.902512) (xy 79.97952 -18.923)
			(xy 79.986923 -18.936835) (xy 80.00733 -18.960659) (xy 80.032931 -18.978785) (xy 80.062181 -18.990118)
			(xy 80.093312 -18.993973) (xy 80.124443 -18.990118) (xy 80.153693 -18.978785) (xy 80.179294 -18.960659)
			(xy 80.199701 -18.936835) (xy 80.207104 -18.923) (xy 80.217603 -18.902517) (xy 80.241768 -18.86334)
			(xy 80.255364 -18.844768) (xy 80.280764 -18.810986) (xy 80.280764 -18.793968) (xy 80.296004 -18.793968)
			(xy 80.331818 -18.763488) (xy 80.356995 -18.742635) (xy 80.411727 -18.706884) (xy 80.470592 -18.678445)
			(xy 80.532617 -18.65779) (xy 80.596779 -18.645259) (xy 80.662018 -18.641059) (xy 80.727257 -18.645259)
			(xy 80.791419 -18.65779) (xy 80.853444 -18.678445) (xy 80.912309 -18.706884) (xy 80.967041 -18.742635)
			(xy 80.992218 -18.763488) (xy 81.028032 -18.793968) (xy 81.043272 -18.793968) (xy 81.043272 -18.810986)
			(xy 81.068672 -18.844768) (xy 81.080974 -18.861539) (xy 81.103101 -18.896763) (xy 81.112868 -18.915126)
			(xy 81.120375 -18.928619) (xy 81.14078 -18.951782) (xy 81.166151 -18.969369) (xy 81.195001 -18.98035)
			(xy 81.225644 -18.984083) (xy 81.256287 -18.98035) (xy 81.285137 -18.969369) (xy 81.310508 -18.951782)
			(xy 81.330913 -18.928619) (xy 81.33842 -18.915126) (xy 81.348198 -18.896769) (xy 81.370325 -18.861547)
			(xy 81.382616 -18.844768) (xy 81.408016 -18.810986) (xy 81.408016 -18.793968) (xy 81.423256 -18.793968)
			(xy 81.45907 -18.763488) (xy 81.484247 -18.742635) (xy 81.538979 -18.706884) (xy 81.597844 -18.678445)
			(xy 81.659869 -18.65779) (xy 81.724031 -18.645259) (xy 81.78927 -18.641059) (xy 81.854509 -18.645259)
			(xy 81.918671 -18.65779) (xy 81.980696 -18.678445) (xy 82.039561 -18.706884) (xy 82.094293 -18.742635)
			(xy 82.11947 -18.763488) (xy 82.155284 -18.793968) (xy 82.170524 -18.793968) (xy 82.170524 -18.810986)
			(xy 82.195924 -18.844768) (xy 82.215147 -18.871261) (xy 82.247377 -18.928231) (xy 82.272019 -18.988871)
			(xy 82.288664 -19.052176) (xy 82.297034 -19.117094) (xy 82.297524 -19.149822) (xy 82.297524 -20.009612)
			(xy 82.297517 -20.01012) (xy 86.39887 -20.01012) (xy 86.402874 -19.810022) (xy 86.414881 -19.610244)
			(xy 86.434872 -19.411107) (xy 86.462814 -19.212929) (xy 86.498662 -19.016027) (xy 86.54236 -18.820718)
			(xy 86.593837 -18.627313) (xy 86.653011 -18.436123) (xy 86.719787 -18.247453) (xy 86.794059 -18.061606)
			(xy 86.875706 -17.878879) (xy 86.964599 -17.699566) (xy 87.060595 -17.523952) (xy 87.16354 -17.35232)
			(xy 87.27327 -17.184944) (xy 87.389608 -17.022093) (xy 87.512369 -16.864026) (xy 87.641356 -16.710998)
			(xy 87.776363 -16.563253) (xy 87.917172 -16.421027) (xy 88.063559 -16.28455) (xy 88.215289 -16.154038)
			(xy 88.37212 -16.029702) (xy 88.533799 -15.91174) (xy 88.700069 -15.800341) (xy 88.870662 -15.695684)
			(xy 89.045306 -15.597936) (xy 89.223722 -15.507253) (xy 89.405622 -15.423782) (xy 89.590717 -15.347655)
			(xy 89.778709 -15.278995) (xy 89.969298 -15.217911) (xy 90.162178 -15.164501) (xy 90.35704 -15.118852)
			(xy 90.553573 -15.081035) (xy 90.751462 -15.051111) (xy 90.950389 -15.029129) (xy 91.150037 -15.015124)
			(xy 91.350085 -15.009118) (xy 91.550213 -15.01112) (xy 91.750101 -15.021128) (xy 91.949428 -15.039125)
			(xy 92.147876 -15.065083) (xy 92.345126 -15.09896) (xy 92.540863 -15.140702) (xy 92.734773 -15.190241)
			(xy 92.926546 -15.247499) (xy 93.115875 -15.312384) (xy 93.302455 -15.384792) (xy 93.48599 -15.464608)
			(xy 93.666184 -15.551702) (xy 93.842749 -15.645936) (xy 94.015402 -15.747159) (xy 94.147215 -15.831701)
			(xy 97.076248 -15.831701) (xy 97.076248 -15.718147) (xy 97.084169 -15.604871) (xy 97.099972 -15.492423)
			(xy 97.123581 -15.381352) (xy 97.154881 -15.272197) (xy 97.193718 -15.165492) (xy 97.239904 -15.061757)
			(xy 97.293214 -14.961495) (xy 97.353388 -14.865197) (xy 97.420133 -14.773331) (xy 97.493123 -14.686344)
			(xy 97.572004 -14.604661) (xy 97.65639 -14.528679) (xy 97.745871 -14.458769) (xy 97.840011 -14.395271)
			(xy 97.938351 -14.338494) (xy 98.040411 -14.288716) (xy 98.145696 -14.246178) (xy 98.253691 -14.211088)
			(xy 98.363871 -14.183617) (xy 98.475699 -14.163899) (xy 98.58863 -14.152029) (xy 98.702114 -14.148067)
			(xy 98.815598 -14.152029) (xy 98.928529 -14.163899) (xy 99.040357 -14.183617) (xy 99.150537 -14.211088)
			(xy 99.258532 -14.246178) (xy 99.363817 -14.288716) (xy 99.465877 -14.338494) (xy 99.564217 -14.395271)
			(xy 99.658357 -14.458769) (xy 99.747838 -14.528679) (xy 99.832224 -14.604661) (xy 99.911105 -14.686344)
			(xy 99.984095 -14.773331) (xy 100.05084 -14.865197) (xy 100.111014 -14.961495) (xy 100.164324 -15.061757)
			(xy 100.21051 -15.165492) (xy 100.249347 -15.272197) (xy 100.280647 -15.381352) (xy 100.304256 -15.492423)
			(xy 100.320059 -15.604871) (xy 100.32798 -15.718147) (xy 100.328476 -15.774924) (xy 100.32798 -15.831701)
			(xy 100.320059 -15.944977) (xy 100.304256 -16.057425) (xy 100.280647 -16.168496) (xy 100.249347 -16.277651)
			(xy 100.21051 -16.384356) (xy 100.164324 -16.488091) (xy 100.111014 -16.588353) (xy 100.05084 -16.684651)
			(xy 99.984095 -16.776517) (xy 99.911105 -16.863504) (xy 99.832224 -16.945187) (xy 99.747838 -17.021169)
			(xy 99.658357 -17.091079) (xy 99.564217 -17.154577) (xy 99.465877 -17.211354) (xy 99.363817 -17.261132)
			(xy 99.258532 -17.30367) (xy 99.150537 -17.33876) (xy 99.040357 -17.366231) (xy 98.928529 -17.385949)
			(xy 98.815598 -17.397819) (xy 98.702114 -17.401782) (xy 98.58863 -17.397819) (xy 98.475699 -17.385949)
			(xy 98.363871 -17.366231) (xy 98.253691 -17.33876) (xy 98.145696 -17.30367) (xy 98.040411 -17.261132)
			(xy 97.938351 -17.211354) (xy 97.840011 -17.154577) (xy 97.745871 -17.091079) (xy 97.65639 -17.021169)
			(xy 97.572004 -16.945187) (xy 97.493123 -16.863504) (xy 97.420133 -16.776517) (xy 97.353388 -16.684651)
			(xy 97.293214 -16.588353) (xy 97.239904 -16.488091) (xy 97.193718 -16.384356) (xy 97.154881 -16.277651)
			(xy 97.123581 -16.168496) (xy 97.099972 -16.057425) (xy 97.084169 -15.944977) (xy 97.076248 -15.831701)
			(xy 94.147215 -15.831701) (xy 94.183867 -15.855209) (xy 94.347875 -15.969912) (xy 94.507162 -16.091086)
			(xy 94.661473 -16.218535) (xy 94.810561 -16.352056) (xy 94.954188 -16.491436) (xy 95.092124 -16.63645)
			(xy 95.224147 -16.786867) (xy 95.350046 -16.942445) (xy 95.46962 -17.102937) (xy 95.582676 -17.268083)
			(xy 95.689035 -17.437621) (xy 95.788526 -17.611279) (xy 95.880989 -17.788778) (xy 95.966276 -17.969834)
			(xy 96.044251 -18.154158) (xy 96.114788 -18.341454) (xy 96.177776 -18.531422) (xy 96.233113 -18.723758)
			(xy 96.28071 -18.918154) (xy 96.320491 -19.114299) (xy 96.352393 -19.311878) (xy 96.376364 -19.510575)
			(xy 96.377051 -19.519138) (xy 98.049078 -19.519138) (xy 98.053149 -19.463516) (xy 98.065275 -19.409079)
			(xy 98.085198 -19.356988) (xy 98.112494 -19.308353) (xy 98.14658 -19.26421) (xy 98.186729 -19.225501)
			(xy 98.232087 -19.19305) (xy 98.281687 -19.167549) (xy 98.334471 -19.149542) (xy 98.389314 -19.139412)
			(xy 98.445048 -19.137375) (xy 98.500485 -19.143475) (xy 98.554442 -19.157581) (xy 98.605771 -19.179393)
			(xy 98.653377 -19.208447) (xy 98.696245 -19.244122) (xy 98.733462 -19.285659) (xy 98.764235 -19.332172)
			(xy 98.787907 -19.382669) (xy 98.803975 -19.436076) (xy 98.812095 -19.491252) (xy 98.812604 -19.519138)
			(xy 98.812095 -19.547024) (xy 98.803975 -19.6022) (xy 98.787907 -19.655607) (xy 98.764235 -19.706104)
			(xy 98.733462 -19.752617) (xy 98.696245 -19.794154) (xy 98.653377 -19.829829) (xy 98.605771 -19.858883)
			(xy 98.554442 -19.880695) (xy 98.500485 -19.894801) (xy 98.445048 -19.900901) (xy 98.389314 -19.898864)
			(xy 98.334471 -19.888734) (xy 98.281687 -19.870727) (xy 98.232087 -19.845226) (xy 98.186729 -19.812775)
			(xy 98.14658 -19.774066) (xy 98.112494 -19.729923) (xy 98.085198 -19.681288) (xy 98.065275 -19.629197)
			(xy 98.053149 -19.57476) (xy 98.049078 -19.519138) (xy 96.377051 -19.519138) (xy 96.392366 -19.710073)
			(xy 96.400373 -19.910051) (xy 96.400874 -20.01012) (xy 96.400373 -20.110189) (xy 96.392366 -20.310167)
			(xy 96.376364 -20.509665) (xy 96.352393 -20.708362) (xy 96.320491 -20.905941) (xy 96.28071 -21.102086)
			(xy 96.233113 -21.296482) (xy 96.177776 -21.488818) (xy 96.114788 -21.678786) (xy 96.044251 -21.866082)
			(xy 95.966276 -22.050406) (xy 95.880989 -22.231462) (xy 95.788526 -22.408961) (xy 95.689035 -22.582619)
			(xy 95.582676 -22.752157) (xy 95.46962 -22.917303) (xy 95.350046 -23.077795) (xy 95.224147 -23.233373)
			(xy 95.092124 -23.38379) (xy 94.954188 -23.528804) (xy 94.810561 -23.668184) (xy 94.661473 -23.801705)
			(xy 94.507162 -23.929154) (xy 94.347875 -24.050328) (xy 94.183867 -24.165031) (xy 94.015402 -24.273081)
			(xy 93.842749 -24.374304) (xy 93.666184 -24.468538) (xy 93.48599 -24.555632) (xy 93.302455 -24.635448)
			(xy 93.115875 -24.707856) (xy 92.926546 -24.772741) (xy 92.734773 -24.829999) (xy 92.540863 -24.879538)
			(xy 92.345126 -24.92128) (xy 92.147876 -24.955157) (xy 91.949428 -24.981115) (xy 91.750101 -24.999112)
			(xy 91.550213 -25.00912) (xy 91.350085 -25.011122) (xy 91.150037 -25.005116) (xy 90.950389 -24.991111)
			(xy 90.751462 -24.969129) (xy 90.553573 -24.939205) (xy 90.35704 -24.901388) (xy 90.162178 -24.855739)
			(xy 89.969298 -24.802329) (xy 89.778709 -24.741245) (xy 89.590717 -24.672585) (xy 89.405622 -24.596458)
			(xy 89.223722 -24.512987) (xy 89.045306 -24.422304) (xy 88.870662 -24.324556) (xy 88.700069 -24.219899)
			(xy 88.533799 -24.1085) (xy 88.37212 -23.990538) (xy 88.215289 -23.866202) (xy 88.063559 -23.73569)
			(xy 87.917172 -23.599213) (xy 87.776363 -23.456987) (xy 87.641356 -23.309242) (xy 87.512369 -23.156214)
			(xy 87.389608 -22.998147) (xy 87.27327 -22.835296) (xy 87.16354 -22.66792) (xy 87.060595 -22.496288)
			(xy 86.964599 -22.320674) (xy 86.875706 -22.141361) (xy 86.794059 -21.958634) (xy 86.719787 -21.772787)
			(xy 86.653011 -21.584117) (xy 86.593837 -21.392927) (xy 86.54236 -21.199522) (xy 86.498662 -21.004213)
			(xy 86.462814 -20.807311) (xy 86.434872 -20.609133) (xy 86.414881 -20.409996) (xy 86.402874 -20.210218)
			(xy 86.39887 -20.01012) (xy 82.297517 -20.01012) (xy 82.297087 -20.041764) (xy 82.288953 -20.105552)
			(xy 82.272842 -20.167806) (xy 82.24901 -20.227531) (xy 82.217838 -20.283775) (xy 82.179824 -20.335641)
			(xy 82.135574 -20.382299) (xy 82.085795 -20.423007) (xy 82.03128 -20.457113) (xy 81.972901 -20.484074)
			(xy 81.911588 -20.50346) (xy 81.84832 -20.51496) (xy 81.784107 -20.518392) (xy 81.719974 -20.513701)
			(xy 81.656944 -20.500962) (xy 81.596023 -20.480377) (xy 81.538184 -20.452276) (xy 81.484349 -20.417107)
			(xy 81.435377 -20.375431) (xy 81.41335 -20.352004) (xy 81.397155 -20.334978) (xy 81.359671 -20.306648)
			(xy 81.317618 -20.285693) (xy 81.272429 -20.272827) (xy 81.225644 -20.26849) (xy 81.178859 -20.272827)
			(xy 81.13367 -20.285693) (xy 81.091617 -20.306648) (xy 81.054133 -20.334978) (xy 81.037938 -20.352004)
			(xy 81.015521 -20.375879) (xy 80.965557 -20.418222) (xy 80.910571 -20.4538) (xy 80.851471 -20.482024)
			(xy 80.789238 -20.502426) (xy 80.724899 -20.51467) (xy 80.659522 -20.518552) (xy 80.594187 -20.514008)
			(xy 80.529976 -20.501113) (xy 80.467952 -20.480081) (xy 80.409142 -20.451261) (xy 80.354518 -20.415128)
			(xy 80.304986 -20.372281) (xy 80.282796 -20.348194) (xy 80.266557 -20.330809) (xy 80.228832 -20.301838)
			(xy 80.186375 -20.280391) (xy 80.14067 -20.267215) (xy 80.093312 -20.262771) (xy 80.045954 -20.267215)
			(xy 80.000249 -20.280391) (xy 79.957792 -20.301838) (xy 79.920067 -20.330809) (xy 79.903828 -20.348194)
			(xy 79.881603 -20.372253) (xy 79.832086 -20.415121) (xy 79.777472 -20.451274) (xy 79.718667 -20.480113)
			(xy 79.656644 -20.501158) (xy 79.592432 -20.514062) (xy 79.527094 -20.51861) (xy 79.461713 -20.514728)
			(xy 79.397373 -20.50248) (xy 79.335139 -20.482068) (xy 79.276042 -20.453831) (xy 79.221063 -20.418237)
			(xy 79.171111 -20.375875) (xy 79.148686 -20.352004) (xy 79.132491 -20.334978) (xy 79.095007 -20.306648)
			(xy 79.052954 -20.285693) (xy 79.007765 -20.272827) (xy 78.96098 -20.26849) (xy 78.914195 -20.272827)
			(xy 78.869006 -20.285693) (xy 78.826953 -20.306648) (xy 78.789469 -20.334978) (xy 78.773274 -20.352004)
			(xy 78.750728 -20.375896) (xy 78.700592 -20.418343) (xy 78.645408 -20.453981) (xy 78.586094 -20.482215)
			(xy 78.523638 -20.502577) (xy 78.45908 -20.514727) (xy 78.393495 -20.518462) (xy 78.327975 -20.513721)
			(xy 78.263611 -20.500583) (xy 78.201475 -20.479265) (xy 78.142601 -20.450124) (xy 78.08797 -20.413643)
			(xy 78.038491 -20.370432) (xy 78.016354 -20.346162) (xy 78.001752 -20.330305) (xy 77.968185 -20.303266)
			(xy 77.930538 -20.282278) (xy 77.88989 -20.267942) (xy 77.847405 -20.26067) (xy 77.804303 -20.26067)
			(xy 77.761818 -20.267942) (xy 77.72117 -20.282278) (xy 77.683523 -20.303266) (xy 77.649956 -20.330305)
			(xy 77.635354 -20.346162) (xy 77.613124 -20.370512) (xy 77.563442 -20.413859) (xy 77.508573 -20.450419)
			(xy 77.449438 -20.479578) (xy 77.387029 -20.500848) (xy 77.322394 -20.513871) (xy 77.256618 -20.518428)
			(xy 77.190805 -20.514444) (xy 77.126059 -20.501985) (xy 77.063468 -20.48126) (xy 77.00408 -20.452617)
			(xy 76.948895 -20.416537) (xy 76.898836 -20.373626) (xy 76.876402 -20.349464) (xy 76.860167 -20.332197)
			(xy 76.822502 -20.303438) (xy 76.780161 -20.282154) (xy 76.73461 -20.269081) (xy 76.687426 -20.264673)
			(xy 76.640242 -20.269081) (xy 76.594691 -20.282154) (xy 76.55235 -20.303438) (xy 76.514685 -20.332197)
			(xy 76.49845 -20.349464) (xy 76.476504 -20.37308) (xy 76.42768 -20.415182) (xy 76.373924 -20.450771)
			(xy 76.316099 -20.479277) (xy 76.255134 -20.500242) (xy 76.192007 -20.513329) (xy 76.127731 -20.518328)
			(xy 76.06334 -20.515158) (xy 75.999866 -20.503871) (xy 75.93833 -20.484647) (xy 75.879718 -20.457796)
			(xy 75.824972 -20.423749) (xy 75.774972 -20.383052) (xy 75.730519 -20.336358) (xy 75.692328 -20.284418)
			(xy 75.661013 -20.228066) (xy 75.637074 -20.168205) (xy 75.620898 -20.105798) (xy 75.612744 -20.041847)
			(xy 75.612244 -20.009612) (xy 75.306936 -20.009612) (xy 75.306936 -21.013928) (xy 75.306435 -21.045873)
			(xy 75.298427 -21.109259) (xy 75.282538 -21.171142) (xy 75.259019 -21.230546) (xy 75.228239 -21.286533)
			(xy 75.190686 -21.338222) (xy 75.14695 -21.384796) (xy 75.097722 -21.425521) (xy 75.043777 -21.459755)
			(xy 74.985968 -21.486958) (xy 74.925205 -21.506701) (xy 74.862446 -21.518673) (xy 74.798682 -21.522685)
			(xy 74.734918 -21.518673) (xy 74.672159 -21.506701) (xy 74.611396 -21.486958) (xy 74.553587 -21.459755)
			(xy 74.499642 -21.425521) (xy 74.450414 -21.384796) (xy 74.406678 -21.338222) (xy 74.369125 -21.286533)
			(xy 74.338345 -21.230546) (xy 74.314826 -21.171142) (xy 74.298937 -21.109259) (xy 74.290929 -21.045873)
			(xy 74.290428 -21.013928) (xy 40.671496 -21.013928) (xy 40.671496 -21.169376) (xy 40.706802 -21.256498)
			(xy 40.721534 -21.273008) (xy 40.745156 -21.30171) (xy 40.75792 -21.318892) (xy 40.780689 -21.35514)
			(xy 40.790622 -21.3741) (xy 40.80426 -21.401787) (xy 40.825177 -21.459853) (xy 40.838525 -21.520112)
			(xy 40.844085 -21.58158) (xy 40.841766 -21.643256) (xy 40.831608 -21.704133) (xy 40.813774 -21.76322)
			(xy 40.788557 -21.819552) (xy 40.756367 -21.872212) (xy 40.717729 -21.920341) (xy 40.681224 -21.955496)
			(xy 60.015167 -21.955496) (xy 60.019055 -21.901137) (xy 60.030641 -21.847885) (xy 60.049688 -21.796824)
			(xy 60.075809 -21.748993) (xy 60.108471 -21.705367) (xy 60.14701 -21.666834) (xy 60.19064 -21.634179)
			(xy 60.238475 -21.608065) (xy 60.289539 -21.589025) (xy 60.342792 -21.577447) (xy 60.397152 -21.573567)
			(xy 60.451511 -21.577462) (xy 60.504762 -21.589055) (xy 60.55582 -21.608108) (xy 60.603647 -21.634235)
			(xy 60.625736 -21.650198) (xy 60.644748 -21.663794) (xy 60.686631 -21.684526) (xy 60.731599 -21.697252)
			(xy 60.778136 -21.701542) (xy 60.824673 -21.697252) (xy 60.869641 -21.684526) (xy 60.911524 -21.663794)
			(xy 60.930536 -21.650198) (xy 60.952618 -21.634233) (xy 61.000441 -21.608117) (xy 61.051494 -21.589073)
			(xy 61.104738 -21.577489) (xy 61.159089 -21.5736) (xy 61.21344 -21.577486) (xy 61.266684 -21.589067)
			(xy 61.317739 -21.608108) (xy 61.365564 -21.634221) (xy 61.409185 -21.666874) (xy 61.447716 -21.705404)
			(xy 61.480371 -21.749024) (xy 61.506486 -21.796848) (xy 61.525529 -21.847902) (xy 61.537112 -21.901146)
			(xy 61.541 -21.955496) (xy 61.919176 -21.955496) (xy 61.923065 -21.901139) (xy 61.93465 -21.847889)
			(xy 61.953696 -21.79683) (xy 61.979815 -21.749001) (xy 62.012475 -21.705377) (xy 62.051012 -21.666845)
			(xy 62.094641 -21.63419) (xy 62.142473 -21.608077) (xy 62.193534 -21.589037) (xy 62.246786 -21.577458)
			(xy 62.301143 -21.573576) (xy 62.3555 -21.57747) (xy 62.408748 -21.589061) (xy 62.459806 -21.608112)
			(xy 62.507632 -21.634236) (xy 62.52972 -21.650198) (xy 62.548732 -21.663794) (xy 62.590615 -21.684526)
			(xy 62.635583 -21.697252) (xy 62.68212 -21.701542) (xy 62.728657 -21.697252) (xy 62.773625 -21.684526)
			(xy 62.815508 -21.663794) (xy 62.83452 -21.650198) (xy 62.856602 -21.634232) (xy 62.904427 -21.608113)
			(xy 62.955481 -21.589067) (xy 63.008727 -21.577481) (xy 63.06308 -21.573591) (xy 63.117433 -21.577475)
			(xy 63.17068 -21.589056) (xy 63.221737 -21.608097) (xy 63.269564 -21.63421) (xy 63.313188 -21.666864)
			(xy 63.351721 -21.705394) (xy 63.384377 -21.749016) (xy 63.410494 -21.796842) (xy 63.429537 -21.847897)
			(xy 63.441121 -21.901144) (xy 63.445009 -21.955496) (xy 63.441122 -22.009849) (xy 63.429539 -22.063096)
			(xy 63.410497 -22.114152) (xy 63.384381 -22.161978) (xy 63.351725 -22.2056) (xy 63.313193 -22.244131)
			(xy 63.26957 -22.276786) (xy 63.221743 -22.3029) (xy 63.170687 -22.321942) (xy 63.11744 -22.333524)
			(xy 63.063087 -22.337409) (xy 63.008734 -22.33352) (xy 62.955488 -22.321935) (xy 62.904433 -22.30289)
			(xy 62.856608 -22.276772) (xy 62.83452 -22.260814) (xy 62.815508 -22.247218) (xy 62.773625 -22.226486)
			(xy 62.728657 -22.21376) (xy 62.68212 -22.20947) (xy 62.635583 -22.21376) (xy 62.590615 -22.226486)
			(xy 62.548732 -22.247218) (xy 62.52972 -22.260814) (xy 62.507626 -22.276768) (xy 62.459799 -22.302891)
			(xy 62.408742 -22.321941) (xy 62.355492 -22.333531) (xy 62.301136 -22.337424) (xy 62.246778 -22.333541)
			(xy 62.193527 -22.321961) (xy 62.142466 -22.30292) (xy 62.094635 -22.276806) (xy 62.051007 -22.24415)
			(xy 62.012471 -22.205618) (xy 61.979811 -22.161993) (xy 61.953693 -22.114163) (xy 61.934648 -22.063104)
			(xy 61.923064 -22.009853) (xy 61.919176 -21.955496) (xy 61.541 -21.955496) (xy 61.537113 -22.009847)
			(xy 61.525531 -22.063091) (xy 61.506489 -22.114145) (xy 61.480375 -22.16197) (xy 61.447721 -22.205591)
			(xy 61.409191 -22.244121) (xy 61.36557 -22.276775) (xy 61.317745 -22.302889) (xy 61.266691 -22.321931)
			(xy 61.213447 -22.333513) (xy 61.159096 -22.3374) (xy 61.104745 -22.333512) (xy 61.051501 -22.321929)
			(xy 61.000448 -22.302886) (xy 60.952624 -22.276771) (xy 60.930536 -22.260814) (xy 60.911524 -22.247218)
			(xy 60.869641 -22.226486) (xy 60.824673 -22.21376) (xy 60.778136 -22.20947) (xy 60.731599 -22.21376)
			(xy 60.686631 -22.226486) (xy 60.644748 -22.247218) (xy 60.625736 -22.260814) (xy 60.603641 -22.276769)
			(xy 60.555814 -22.302895) (xy 60.504755 -22.321947) (xy 60.451504 -22.333539) (xy 60.397145 -22.337433)
			(xy 60.342785 -22.333552) (xy 60.289532 -22.321972) (xy 60.238468 -22.302932) (xy 60.190634 -22.276817)
			(xy 60.147004 -22.244161) (xy 60.108466 -22.205627) (xy 60.075805 -22.162001) (xy 60.049685 -22.11417)
			(xy 60.030639 -22.063108) (xy 60.019054 -22.009856) (xy 60.015167 -21.955496) (xy 40.681224 -21.955496)
			(xy 40.673273 -21.963153) (xy 40.623723 -21.999952) (xy 40.569889 -22.030136) (xy 40.512647 -22.053214)
			(xy 40.45293 -22.06881) (xy 40.391714 -22.076669) (xy 40.360854 -22.077172) (xy 40.203374 -22.077172)
			(xy 40.179616 -22.079691) (xy 40.133588 -22.092476) (xy 40.111934 -22.102572) (xy 40.111934 -22.676866)
			(xy 40.133704 -22.687045) (xy 40.179987 -22.699961) (xy 40.203882 -22.70252) (xy 40.491918 -22.70252)
			(xy 40.523533 -22.703038) (xy 40.586222 -22.711293) (xy 40.647297 -22.72766) (xy 40.705713 -22.751859)
			(xy 40.760471 -22.783476) (xy 40.810634 -22.821969) (xy 40.855343 -22.86668) (xy 40.893835 -22.916844)
			(xy 40.925449 -22.971603) (xy 40.949645 -23.03002) (xy 40.96601 -23.091096) (xy 40.974263 -23.153785)
			(xy 40.974263 -23.217015) (xy 40.96601 -23.279704) (xy 40.949645 -23.34078) (xy 40.925449 -23.399197)
			(xy 40.893835 -23.453956) (xy 40.855343 -23.50412) (xy 40.810634 -23.548831) (xy 40.760471 -23.587324)
			(xy 40.705713 -23.618941) (xy 40.647297 -23.64314) (xy 40.586222 -23.659507) (xy 40.523533 -23.667762)
			(xy 40.491918 -23.668228) (xy 39.46398 -23.668228) (xy 39.446585 -23.668117) (xy 39.411881 -23.6657)
			(xy 39.394638 -23.663402) (xy 39.38016 -23.661116) (xy 39.356538 -23.65629) (xy 39.355268 -23.656036)
			(xy 39.341298 -23.652734) (xy 38.937946 -23.652734) (xy 38.1635 -22.878288) (xy 36.397184 -22.878288)
			(xy 36.382355 -22.87873) (xy 36.3535 -22.885584) (xy 36.326999 -22.898899) (xy 36.304274 -22.917957)
			(xy 36.295076 -22.929596) (xy 36.269185 -22.963763) (xy 36.212105 -23.02773) (xy 36.149439 -23.086235)
			(xy 36.081706 -23.138792) (xy 36.00947 -23.184964) (xy 35.93333 -23.224367) (xy 35.853919 -23.256675)
			(xy 35.771896 -23.281619) (xy 35.687943 -23.298992) (xy 35.602757 -23.308649) (xy 35.517046 -23.31051)
			(xy 35.431521 -23.30456) (xy 35.346893 -23.290848) (xy 35.263864 -23.269489) (xy 35.183126 -23.240659)
			(xy 35.105347 -23.204598) (xy 35.031174 -23.161605) (xy 34.961224 -23.112038) (xy 34.896077 -23.056308)
			(xy 34.836274 -22.994879) (xy 34.782313 -22.92826) (xy 34.734641 -22.857005) (xy 34.713672 -22.819614)
			(xy 34.705213 -22.803941) (xy 34.689334 -22.772055) (xy 34.681922 -22.75586) (xy 34.666682 -22.722078)
			(xy 34.603944 -22.681184) (xy 31.395416 -22.681184) (xy 31.332424 -22.722078) (xy 31.317184 -22.756114)
			(xy 31.29901 -22.795288) (xy 31.256483 -22.870456) (xy 31.207242 -22.941407) (xy 31.151703 -23.007545)
			(xy 31.090335 -23.068311) (xy 31.023652 -23.123195) (xy 30.952219 -23.171733) (xy 30.876636 -23.213517)
			(xy 30.79754 -23.248195) (xy 30.715597 -23.275475) (xy 30.631499 -23.295126) (xy 30.545953 -23.306983)
			(xy 30.45968 -23.310946) (xy 30.373407 -23.306983) (xy 30.287861 -23.295126) (xy 30.203763 -23.275475)
			(xy 30.12182 -23.248195) (xy 30.042724 -23.213517) (xy 29.967141 -23.171733) (xy 29.895708 -23.123195)
			(xy 29.829025 -23.068311) (xy 29.767657 -23.007545) (xy 29.712118 -22.941407) (xy 29.662877 -22.870456)
			(xy 29.62035 -22.795288) (xy 29.602176 -22.756114) (xy 29.586936 -22.722078) (xy 29.523944 -22.681184)
			(xy 29.36748 -22.681184) (xy 29.351288 -22.681658) (xy 29.319942 -22.689792) (xy 29.291655 -22.705558)
			(xy 29.26825 -22.727939) (xy 29.251234 -22.755492) (xy 29.241705 -22.786442) (xy 29.24048 -22.802596)
			(xy 29.24048 -24.953484) (xy 29.519874 -24.953484) (xy 29.519874 -24.866584) (xy 29.527892 -24.780055)
			(xy 29.54386 -24.694635) (xy 29.567641 -24.611053) (xy 29.599033 -24.530021) (xy 29.637767 -24.452232)
			(xy 29.683514 -24.378348) (xy 29.735883 -24.309001) (xy 29.794427 -24.244781) (xy 29.858647 -24.186237)
			(xy 29.927994 -24.133868) (xy 30.001878 -24.088121) (xy 30.079667 -24.049387) (xy 30.160699 -24.017995)
			(xy 30.244281 -23.994214) (xy 30.329701 -23.978246) (xy 30.41623 -23.970228) (xy 30.50313 -23.970228)
			(xy 30.589659 -23.978246) (xy 30.675079 -23.994214) (xy 30.758661 -24.017995) (xy 30.839693 -24.049387)
			(xy 30.917482 -24.088121) (xy 30.991366 -24.133868) (xy 31.060713 -24.186237) (xy 31.124933 -24.244781)
			(xy 31.183477 -24.309001) (xy 31.235846 -24.378348) (xy 31.281593 -24.452232) (xy 31.320327 -24.530021)
			(xy 31.351719 -24.611053) (xy 31.3755 -24.694635) (xy 31.391468 -24.780055) (xy 31.399486 -24.866584)
			(xy 31.399988 -24.910034) (xy 31.399486 -24.953484) (xy 34.599874 -24.953484) (xy 34.599874 -24.866584)
			(xy 34.607892 -24.780055) (xy 34.62386 -24.694635) (xy 34.647641 -24.611053) (xy 34.679033 -24.530021)
			(xy 34.717767 -24.452232) (xy 34.763514 -24.378348) (xy 34.815883 -24.309001) (xy 34.874427 -24.244781)
			(xy 34.938647 -24.186237) (xy 35.007994 -24.133868) (xy 35.081878 -24.088121) (xy 35.159667 -24.049387)
			(xy 35.240699 -24.017995) (xy 35.324281 -23.994214) (xy 35.409701 -23.978246) (xy 35.49623 -23.970228)
			(xy 35.58313 -23.970228) (xy 35.669659 -23.978246) (xy 35.755079 -23.994214) (xy 35.763922 -23.99673)
			(xy 60.015122 -23.99673) (xy 60.019006 -23.942364) (xy 60.030589 -23.889105) (xy 60.049634 -23.838036)
			(xy 60.075753 -23.790197) (xy 60.108415 -23.746564) (xy 60.146955 -23.708023) (xy 60.190588 -23.675359)
			(xy 60.238425 -23.649238) (xy 60.289494 -23.630192) (xy 60.342753 -23.618608) (xy 60.397119 -23.614722)
			(xy 60.451484 -23.618613) (xy 60.504742 -23.630202) (xy 60.555808 -23.649254) (xy 60.603643 -23.675379)
			(xy 60.625736 -23.691342) (xy 60.644748 -23.704938) (xy 60.686631 -23.72567) (xy 60.731599 -23.738396)
			(xy 60.778136 -23.742686) (xy 60.824673 -23.738396) (xy 60.869641 -23.72567) (xy 60.911524 -23.704938)
			(xy 60.930536 -23.691342) (xy 60.952576 -23.675318) (xy 61.000402 -23.649196) (xy 61.051459 -23.630147)
			(xy 61.104707 -23.618558) (xy 61.159062 -23.614665) (xy 61.213419 -23.618547) (xy 61.266669 -23.630126)
			(xy 61.317729 -23.649165) (xy 61.36556 -23.675277) (xy 61.409188 -23.70793) (xy 61.447725 -23.746461)
			(xy 61.480386 -23.790083) (xy 61.506507 -23.837909) (xy 61.525555 -23.888966) (xy 61.537143 -23.942215)
			(xy 61.541035 -23.99657) (xy 61.541024 -23.99673) (xy 61.919131 -23.99673) (xy 61.923016 -23.942366)
			(xy 61.934597 -23.889109) (xy 61.953641 -23.838042) (xy 61.979759 -23.790205) (xy 62.01242 -23.746573)
			(xy 62.050957 -23.708033) (xy 62.094588 -23.67537) (xy 62.142423 -23.64925) (xy 62.193489 -23.630203)
			(xy 62.246746 -23.618619) (xy 62.301109 -23.614731) (xy 62.355473 -23.618621) (xy 62.408729 -23.630209)
			(xy 62.459794 -23.649258) (xy 62.507628 -23.67538) (xy 62.52972 -23.691342) (xy 62.548732 -23.704938)
			(xy 62.590615 -23.72567) (xy 62.635583 -23.738396) (xy 62.68212 -23.742686) (xy 62.728657 -23.738396)
			(xy 62.773625 -23.72567) (xy 62.815508 -23.704938) (xy 62.83452 -23.691342) (xy 62.856561 -23.675316)
			(xy 62.904388 -23.649192) (xy 62.955446 -23.630141) (xy 63.008696 -23.61855) (xy 63.063053 -23.614655)
			(xy 63.117412 -23.618537) (xy 63.170664 -23.630115) (xy 63.221727 -23.649154) (xy 63.269561 -23.675266)
			(xy 63.313191 -23.70792) (xy 63.35173 -23.746451) (xy 63.384393 -23.790075) (xy 63.410515 -23.837903)
			(xy 63.429564 -23.888962) (xy 63.441152 -23.942212) (xy 63.445045 -23.99657) (xy 63.441161 -24.050928)
			(xy 63.429581 -24.10418) (xy 63.41054 -24.155242) (xy 63.384425 -24.203075) (xy 63.351769 -24.246704)
			(xy 63.313236 -24.285241) (xy 63.269611 -24.317902) (xy 63.221782 -24.344022) (xy 63.170722 -24.363069)
			(xy 63.117471 -24.374655) (xy 63.063113 -24.378545) (xy 63.008755 -24.374659) (xy 62.955504 -24.363076)
			(xy 62.904442 -24.344033) (xy 62.856611 -24.317916) (xy 62.83452 -24.301958) (xy 62.815508 -24.288362)
			(xy 62.773625 -24.26763) (xy 62.728657 -24.254904) (xy 62.68212 -24.250614) (xy 62.635583 -24.254904)
			(xy 62.590615 -24.26763) (xy 62.548732 -24.288362) (xy 62.52972 -24.301958) (xy 62.507678 -24.317987)
			(xy 62.459848 -24.344117) (xy 62.408786 -24.363175) (xy 62.355532 -24.37477) (xy 62.301169 -24.378669)
			(xy 62.246805 -24.37479) (xy 62.193547 -24.363214) (xy 62.142478 -24.344175) (xy 62.094639 -24.318062)
			(xy 62.051003 -24.285406) (xy 62.012459 -24.246872) (xy 61.979792 -24.203245) (xy 61.953666 -24.155413)
			(xy 61.934614 -24.104349) (xy 61.923024 -24.051093) (xy 61.919131 -23.99673) (xy 61.541024 -23.99673)
			(xy 61.537152 -24.050926) (xy 61.525572 -24.104176) (xy 61.506532 -24.155236) (xy 61.480419 -24.203067)
			(xy 61.447765 -24.246694) (xy 61.409234 -24.28523) (xy 61.365611 -24.317891) (xy 61.317784 -24.34401)
			(xy 61.266726 -24.363057) (xy 61.213478 -24.374644) (xy 61.159122 -24.378535) (xy 61.104767 -24.374651)
			(xy 61.051517 -24.36307) (xy 61.000457 -24.344029) (xy 60.952627 -24.317915) (xy 60.930536 -24.301958)
			(xy 60.911524 -24.288362) (xy 60.869641 -24.26763) (xy 60.824673 -24.254904) (xy 60.778136 -24.250614)
			(xy 60.731599 -24.254904) (xy 60.686631 -24.26763) (xy 60.644748 -24.288362) (xy 60.625736 -24.301958)
			(xy 60.603694 -24.317988) (xy 60.555863 -24.344121) (xy 60.504799 -24.363181) (xy 60.451543 -24.374778)
			(xy 60.397179 -24.378678) (xy 60.342812 -24.374801) (xy 60.289551 -24.363225) (xy 60.23848 -24.344187)
			(xy 60.190638 -24.318073) (xy 60.147 -24.285417) (xy 60.108454 -24.246882) (xy 60.075785 -24.203253)
			(xy 60.049658 -24.155419) (xy 60.030606 -24.104353) (xy 60.019015 -24.051095) (xy 60.015122 -23.99673)
			(xy 35.763922 -23.99673) (xy 35.838661 -24.017995) (xy 35.919693 -24.049387) (xy 35.997482 -24.088121)
			(xy 36.071366 -24.133868) (xy 36.140713 -24.186237) (xy 36.204933 -24.244781) (xy 36.263477 -24.309001)
			(xy 36.315846 -24.378348) (xy 36.361593 -24.452232) (xy 36.400327 -24.530021) (xy 36.431719 -24.611053)
			(xy 36.4555 -24.694635) (xy 36.471468 -24.780055) (xy 36.479486 -24.866584) (xy 36.479988 -24.910034)
			(xy 36.479486 -24.953484) (xy 36.471468 -25.040013) (xy 36.4555 -25.125433) (xy 36.431719 -25.209015)
			(xy 36.400327 -25.290047) (xy 36.361593 -25.367836) (xy 36.315846 -25.44172) (xy 36.263477 -25.511067)
			(xy 36.204933 -25.575287) (xy 36.140713 -25.633831) (xy 36.071366 -25.6862) (xy 35.997482 -25.731947)
			(xy 35.919693 -25.770681) (xy 35.838661 -25.802073) (xy 35.755079 -25.825854) (xy 35.669659 -25.841822)
			(xy 35.58313 -25.84984) (xy 35.49623 -25.84984) (xy 35.409701 -25.841822) (xy 35.324281 -25.825854)
			(xy 35.240699 -25.802073) (xy 35.159667 -25.770681) (xy 35.081878 -25.731947) (xy 35.007994 -25.6862)
			(xy 34.938647 -25.633831) (xy 34.874427 -25.575287) (xy 34.815883 -25.511067) (xy 34.763514 -25.44172)
			(xy 34.717767 -25.367836) (xy 34.679033 -25.290047) (xy 34.647641 -25.209015) (xy 34.62386 -25.125433)
			(xy 34.607892 -25.040013) (xy 34.599874 -24.953484) (xy 31.399486 -24.953484) (xy 31.391468 -25.040013)
			(xy 31.3755 -25.125433) (xy 31.351719 -25.209015) (xy 31.320327 -25.290047) (xy 31.281593 -25.367836)
			(xy 31.235846 -25.44172) (xy 31.183477 -25.511067) (xy 31.124933 -25.575287) (xy 31.060713 -25.633831)
			(xy 30.991366 -25.6862) (xy 30.917482 -25.731947) (xy 30.839693 -25.770681) (xy 30.758661 -25.802073)
			(xy 30.675079 -25.825854) (xy 30.589659 -25.841822) (xy 30.50313 -25.84984) (xy 30.41623 -25.84984)
			(xy 30.329701 -25.841822) (xy 30.244281 -25.825854) (xy 30.160699 -25.802073) (xy 30.079667 -25.770681)
			(xy 30.001878 -25.731947) (xy 29.927994 -25.6862) (xy 29.858647 -25.633831) (xy 29.794427 -25.575287)
			(xy 29.735883 -25.511067) (xy 29.683514 -25.44172) (xy 29.637767 -25.367836) (xy 29.599033 -25.290047)
			(xy 29.567641 -25.209015) (xy 29.54386 -25.125433) (xy 29.527892 -25.040013) (xy 29.519874 -24.953484)
			(xy 29.24048 -24.953484) (xy 29.24048 -25.906514) (xy 60.015143 -25.906514) (xy 60.019029 -25.852152)
			(xy 60.030613 -25.798896) (xy 60.049659 -25.74783) (xy 60.075779 -25.699996) (xy 60.108441 -25.656365)
			(xy 60.14698 -25.617828) (xy 60.190612 -25.585168) (xy 60.238448 -25.559051) (xy 60.289514 -25.540008)
			(xy 60.342771 -25.528426) (xy 60.397134 -25.524543) (xy 60.451496 -25.528436) (xy 60.504751 -25.540027)
			(xy 60.555814 -25.559079) (xy 60.603645 -25.585205) (xy 60.625736 -25.601168) (xy 60.644748 -25.614764)
			(xy 60.686631 -25.635496) (xy 60.731599 -25.648222) (xy 60.778136 -25.652512) (xy 60.824673 -25.648222)
			(xy 60.869641 -25.635496) (xy 60.911524 -25.614764) (xy 60.930536 -25.601168) (xy 60.952646 -25.585243)
			(xy 61.000467 -25.559132) (xy 61.051518 -25.540091) (xy 61.10476 -25.52851) (xy 61.159107 -25.524624)
			(xy 61.213454 -25.528512) (xy 61.266695 -25.540095) (xy 61.317745 -25.559137) (xy 61.365566 -25.585251)
			(xy 61.409183 -25.617904) (xy 61.44771 -25.656433) (xy 61.480361 -25.700052) (xy 61.506472 -25.747874)
			(xy 61.525511 -25.798926) (xy 61.537091 -25.852167) (xy 61.540976 -25.906514) (xy 61.919152 -25.906514)
			(xy 61.923038 -25.852154) (xy 61.934622 -25.7989) (xy 61.953667 -25.747837) (xy 61.979785 -25.700004)
			(xy 62.012445 -25.656375) (xy 62.050983 -25.617839) (xy 62.094612 -25.585179) (xy 62.142446 -25.559062)
			(xy 62.19351 -25.540019) (xy 62.246764 -25.528437) (xy 62.301125 -25.524552) (xy 62.355485 -25.528444)
			(xy 62.408738 -25.540033) (xy 62.459799 -25.559083) (xy 62.50763 -25.585206) (xy 62.52972 -25.601168)
			(xy 62.548732 -25.614764) (xy 62.590615 -25.635496) (xy 62.635583 -25.648222) (xy 62.68212 -25.652512)
			(xy 62.728657 -25.648222) (xy 62.773625 -25.635496) (xy 62.815508 -25.614764) (xy 62.83452 -25.601168)
			(xy 62.85663 -25.585242) (xy 62.904453 -25.559128) (xy 62.955505 -25.540085) (xy 63.008748 -25.528502)
			(xy 63.063098 -25.524615) (xy 63.117447 -25.528502) (xy 63.17069 -25.540084) (xy 63.221743 -25.559126)
			(xy 63.269566 -25.58524) (xy 63.313186 -25.617894) (xy 63.351714 -25.656423) (xy 63.384367 -25.700044)
			(xy 63.410479 -25.747868) (xy 63.429519 -25.798921) (xy 63.4411 -25.852165) (xy 63.444985 -25.906514)
			(xy 63.441096 -25.960864) (xy 63.429511 -26.014106) (xy 63.410467 -26.065158) (xy 63.384351 -26.11298)
			(xy 63.351695 -26.156598) (xy 63.313164 -26.195125) (xy 63.269542 -26.227776) (xy 63.221717 -26.253886)
			(xy 63.170663 -26.272924) (xy 63.117419 -26.284502) (xy 63.063069 -26.288385) (xy 63.00872 -26.284494)
			(xy 62.955478 -26.272907) (xy 62.904427 -26.25386) (xy 62.856606 -26.227742) (xy 62.83452 -26.211784)
			(xy 62.815508 -26.198188) (xy 62.773625 -26.177456) (xy 62.728657 -26.16473) (xy 62.68212 -26.16044)
			(xy 62.635583 -26.16473) (xy 62.590615 -26.177456) (xy 62.548732 -26.198188) (xy 62.52972 -26.211784)
			(xy 62.507654 -26.227778) (xy 62.459826 -26.253905) (xy 62.408766 -26.272959) (xy 62.355514 -26.284552)
			(xy 62.301154 -26.288448) (xy 62.246793 -26.284567) (xy 62.193538 -26.272989) (xy 62.142472 -26.25395)
			(xy 62.094637 -26.227836) (xy 62.051005 -26.19518) (xy 62.012464 -26.156647) (xy 61.979801 -26.113021)
			(xy 61.953679 -26.06519) (xy 61.93463 -26.014128) (xy 61.923043 -25.960875) (xy 61.919152 -25.906514)
			(xy 61.540976 -25.906514) (xy 61.537087 -25.960862) (xy 61.525503 -26.014102) (xy 61.50646 -26.065152)
			(xy 61.480345 -26.112972) (xy 61.447691 -26.156589) (xy 61.409161 -26.195115) (xy 61.365541 -26.227765)
			(xy 61.317719 -26.253875) (xy 61.266667 -26.272913) (xy 61.213426 -26.284492) (xy 61.159078 -26.288376)
			(xy 61.104731 -26.284486) (xy 61.051491 -26.272901) (xy 61.000441 -26.253856) (xy 60.952622 -26.227741)
			(xy 60.930536 -26.211784) (xy 60.911524 -26.198188) (xy 60.869641 -26.177456) (xy 60.824673 -26.16473)
			(xy 60.778136 -26.16044) (xy 60.731599 -26.16473) (xy 60.686631 -26.177456) (xy 60.644748 -26.198188)
			(xy 60.625736 -26.211784) (xy 60.603669 -26.227779) (xy 60.55584 -26.253909) (xy 60.504779 -26.272965)
			(xy 60.451525 -26.28456) (xy 60.397163 -26.288457) (xy 60.3428 -26.284578) (xy 60.289542 -26.273001)
			(xy 60.238474 -26.253961) (xy 60.190636 -26.227847) (xy 60.147002 -26.195191) (xy 60.10846 -26.156656)
			(xy 60.075794 -26.113029) (xy 60.049671 -26.065196) (xy 60.030621 -26.014132) (xy 60.019033 -25.960877)
			(xy 60.015143 -25.906514) (xy 29.24048 -25.906514) (xy 29.24048 -27.493484) (xy 29.519874 -27.493484)
			(xy 29.519874 -27.406584) (xy 29.527892 -27.320055) (xy 29.54386 -27.234635) (xy 29.567641 -27.151053)
			(xy 29.599033 -27.070021) (xy 29.637767 -26.992232) (xy 29.683514 -26.918348) (xy 29.735883 -26.849001)
			(xy 29.794427 -26.784781) (xy 29.858647 -26.726237) (xy 29.927994 -26.673868) (xy 30.001878 -26.628121)
			(xy 30.079667 -26.589387) (xy 30.160699 -26.557995) (xy 30.244281 -26.534214) (xy 30.329701 -26.518246)
			(xy 30.41623 -26.510228) (xy 30.50313 -26.510228) (xy 30.589659 -26.518246) (xy 30.675079 -26.534214)
			(xy 30.758661 -26.557995) (xy 30.839693 -26.589387) (xy 30.917482 -26.628121) (xy 30.991366 -26.673868)
			(xy 31.060713 -26.726237) (xy 31.124933 -26.784781) (xy 31.183477 -26.849001) (xy 31.235846 -26.918348)
			(xy 31.281593 -26.992232) (xy 31.320327 -27.070021) (xy 31.351719 -27.151053) (xy 31.3755 -27.234635)
			(xy 31.391468 -27.320055) (xy 31.399486 -27.406584) (xy 31.399988 -27.450034) (xy 31.399486 -27.493484)
			(xy 34.599874 -27.493484) (xy 34.599874 -27.406584) (xy 34.607892 -27.320055) (xy 34.62386 -27.234635)
			(xy 34.647641 -27.151053) (xy 34.679033 -27.070021) (xy 34.717767 -26.992232) (xy 34.763514 -26.918348)
			(xy 34.815883 -26.849001) (xy 34.874427 -26.784781) (xy 34.938647 -26.726237) (xy 35.007994 -26.673868)
			(xy 35.081878 -26.628121) (xy 35.159667 -26.589387) (xy 35.240699 -26.557995) (xy 35.324281 -26.534214)
			(xy 35.409701 -26.518246) (xy 35.49623 -26.510228) (xy 35.58313 -26.510228) (xy 35.669659 -26.518246)
			(xy 35.755079 -26.534214) (xy 35.838661 -26.557995) (xy 35.919693 -26.589387) (xy 35.997482 -26.628121)
			(xy 36.071366 -26.673868) (xy 36.140713 -26.726237) (xy 36.204933 -26.784781) (xy 36.263477 -26.849001)
			(xy 36.315846 -26.918348) (xy 36.361593 -26.992232) (xy 36.400327 -27.070021) (xy 36.431719 -27.151053)
			(xy 36.4555 -27.234635) (xy 36.471468 -27.320055) (xy 36.479486 -27.406584) (xy 36.479988 -27.450034)
			(xy 36.479486 -27.493484) (xy 36.471468 -27.580013) (xy 36.4555 -27.665433) (xy 36.431719 -27.749015)
			(xy 36.400327 -27.830047) (xy 36.361593 -27.907836) (xy 36.315846 -27.98172) (xy 36.263477 -28.051067)
			(xy 36.204933 -28.115287) (xy 36.140713 -28.173831) (xy 36.071366 -28.2262) (xy 35.997482 -28.271947)
			(xy 35.946339 -28.297413) (xy 41.909066 -28.297413) (xy 41.912952 -28.243056) (xy 41.924535 -28.189804)
			(xy 41.943578 -28.138744) (xy 41.969695 -28.090913) (xy 42.002353 -28.047287) (xy 42.040888 -28.008752)
			(xy 42.084515 -27.976094) (xy 42.132345 -27.949978) (xy 42.183406 -27.930934) (xy 42.236657 -27.919352)
			(xy 42.291015 -27.915466) (xy 42.345372 -27.919356) (xy 42.398622 -27.930943) (xy 42.449682 -27.94999)
			(xy 42.49751 -27.97611) (xy 42.5196 -27.99207) (xy 42.538612 -28.005666) (xy 42.580495 -28.026398)
			(xy 42.625463 -28.039124) (xy 42.672 -28.043414) (xy 42.718537 -28.039124) (xy 42.763505 -28.026398)
			(xy 42.805388 -28.005666) (xy 42.8244 -27.99207) (xy 42.846509 -27.97614) (xy 42.894333 -27.950022)
			(xy 42.945388 -27.930976) (xy 42.998633 -27.919391) (xy 43.052985 -27.915501) (xy 43.107338 -27.919387)
			(xy 43.160584 -27.930968) (xy 43.21164 -27.95001) (xy 43.259466 -27.976124) (xy 43.303089 -28.008779)
			(xy 43.34162 -28.04731) (xy 43.374275 -28.090932) (xy 43.40039 -28.138759) (xy 43.419432 -28.189814)
			(xy 43.431013 -28.243061) (xy 43.434899 -28.297413) (xy 43.795759 -28.297413) (xy 43.799645 -28.243054)
			(xy 43.811228 -28.189801) (xy 43.830272 -28.138739) (xy 43.85639 -28.090907) (xy 43.88905 -28.04728)
			(xy 43.927586 -28.008744) (xy 43.971214 -27.976086) (xy 44.019047 -27.949969) (xy 44.070109 -27.930926)
			(xy 44.123362 -27.919344) (xy 44.177722 -27.915459) (xy 44.232081 -27.91935) (xy 44.285332 -27.930938)
			(xy 44.336393 -27.949987) (xy 44.384222 -27.976109) (xy 44.406312 -27.99207) (xy 44.425324 -28.005666)
			(xy 44.467207 -28.026398) (xy 44.512175 -28.039124) (xy 44.558712 -28.043414) (xy 44.605249 -28.039124)
			(xy 44.650217 -28.026398) (xy 44.6921 -28.005666) (xy 44.711112 -27.99207) (xy 44.733221 -27.976141)
			(xy 44.781044 -27.950025) (xy 44.832097 -27.930981) (xy 44.885341 -27.919397) (xy 44.939692 -27.915508)
			(xy 44.994043 -27.919395) (xy 45.047287 -27.930976) (xy 45.098342 -27.950018) (xy 45.146166 -27.976132)
			(xy 45.189787 -28.008787) (xy 45.228317 -28.047317) (xy 45.260971 -28.090938) (xy 45.287084 -28.138763)
			(xy 45.306125 -28.189818) (xy 45.317706 -28.243062) (xy 45.321592 -28.297413) (xy 45.317702 -28.351764)
			(xy 45.306118 -28.405008) (xy 45.287073 -28.456061) (xy 45.260956 -28.503884) (xy 45.2283 -28.547503)
			(xy 45.189767 -28.586031) (xy 45.146144 -28.618682) (xy 45.098318 -28.644793) (xy 45.047262 -28.663831)
			(xy 44.994017 -28.675409) (xy 44.939666 -28.679292) (xy 44.885315 -28.675399) (xy 44.832072 -28.663812)
			(xy 44.78102 -28.644764) (xy 44.733198 -28.618645) (xy 44.711112 -28.602686) (xy 44.6921 -28.58909)
			(xy 44.650217 -28.568358) (xy 44.605249 -28.555632) (xy 44.558712 -28.551342) (xy 44.512175 -28.555632)
			(xy 44.467207 -28.568358) (xy 44.425324 -28.58909) (xy 44.406312 -28.602686) (xy 44.384244 -28.618677)
			(xy 44.336417 -28.644802) (xy 44.285358 -28.663855) (xy 44.232107 -28.675446) (xy 44.177748 -28.679341)
			(xy 44.123389 -28.67546) (xy 44.070135 -28.663882) (xy 44.019071 -28.644842) (xy 43.971237 -28.618729)
			(xy 43.927606 -28.586073) (xy 43.889067 -28.54754) (xy 43.856405 -28.503915) (xy 43.830283 -28.456085)
			(xy 43.811235 -28.405024) (xy 43.799649 -28.351772) (xy 43.795759 -28.297413) (xy 43.434899 -28.297413)
			(xy 43.431009 -28.351765) (xy 43.419424 -28.405011) (xy 43.400379 -28.456066) (xy 43.374261 -28.50389)
			(xy 43.341603 -28.54751) (xy 43.303069 -28.586039) (xy 43.259444 -28.618691) (xy 43.211616 -28.644801)
			(xy 43.160559 -28.66384) (xy 43.107312 -28.675417) (xy 43.052959 -28.679299) (xy 42.998607 -28.675405)
			(xy 42.945362 -28.663816) (xy 42.894309 -28.644767) (xy 42.846487 -28.618646) (xy 42.8244 -28.602686)
			(xy 42.805388 -28.58909) (xy 42.763505 -28.568358) (xy 42.718537 -28.555632) (xy 42.672 -28.551342)
			(xy 42.625463 -28.555632) (xy 42.580495 -28.568358) (xy 42.538612 -28.58909) (xy 42.5196 -28.602686)
			(xy 42.497532 -28.618676) (xy 42.449706 -28.644799) (xy 42.398648 -28.66385) (xy 42.345398 -28.67544)
			(xy 42.291041 -28.679334) (xy 42.236683 -28.675452) (xy 42.183431 -28.663873) (xy 42.132369 -28.644833)
			(xy 42.084537 -28.61872) (xy 42.040908 -28.586065) (xy 42.00237 -28.547533) (xy 41.969709 -28.503909)
			(xy 41.943589 -28.45608) (xy 41.924542 -28.405021) (xy 41.912956 -28.35177) (xy 41.909066 -28.297413)
			(xy 35.946339 -28.297413) (xy 35.919693 -28.310681) (xy 35.838661 -28.342073) (xy 35.755079 -28.365854)
			(xy 35.669659 -28.381822) (xy 35.58313 -28.38984) (xy 35.49623 -28.38984) (xy 35.409701 -28.381822)
			(xy 35.324281 -28.365854) (xy 35.240699 -28.342073) (xy 35.159667 -28.310681) (xy 35.081878 -28.271947)
			(xy 35.007994 -28.2262) (xy 34.938647 -28.173831) (xy 34.874427 -28.115287) (xy 34.815883 -28.051067)
			(xy 34.763514 -27.98172) (xy 34.717767 -27.907836) (xy 34.679033 -27.830047) (xy 34.647641 -27.749015)
			(xy 34.62386 -27.665433) (xy 34.607892 -27.580013) (xy 34.599874 -27.493484) (xy 31.399486 -27.493484)
			(xy 31.391468 -27.580013) (xy 31.3755 -27.665433) (xy 31.351719 -27.749015) (xy 31.320327 -27.830047)
			(xy 31.281593 -27.907836) (xy 31.235846 -27.98172) (xy 31.183477 -28.051067) (xy 31.124933 -28.115287)
			(xy 31.060713 -28.173831) (xy 30.991366 -28.2262) (xy 30.917482 -28.271947) (xy 30.839693 -28.310681)
			(xy 30.758661 -28.342073) (xy 30.675079 -28.365854) (xy 30.589659 -28.381822) (xy 30.50313 -28.38984)
			(xy 30.41623 -28.38984) (xy 30.329701 -28.381822) (xy 30.244281 -28.365854) (xy 30.160699 -28.342073)
			(xy 30.079667 -28.310681) (xy 30.001878 -28.271947) (xy 29.927994 -28.2262) (xy 29.858647 -28.173831)
			(xy 29.794427 -28.115287) (xy 29.735883 -28.051067) (xy 29.683514 -27.98172) (xy 29.637767 -27.907836)
			(xy 29.599033 -27.830047) (xy 29.567641 -27.749015) (xy 29.54386 -27.665433) (xy 29.527892 -27.580013)
			(xy 29.519874 -27.493484) (xy 29.24048 -27.493484) (xy 29.24048 -30.033484) (xy 29.519874 -30.033484)
			(xy 29.519874 -29.946584) (xy 29.527892 -29.860055) (xy 29.54386 -29.774635) (xy 29.567641 -29.691053)
			(xy 29.599033 -29.610021) (xy 29.637767 -29.532232) (xy 29.683514 -29.458348) (xy 29.735883 -29.389001)
			(xy 29.794427 -29.324781) (xy 29.858647 -29.266237) (xy 29.927994 -29.213868) (xy 30.001878 -29.168121)
			(xy 30.079667 -29.129387) (xy 30.160699 -29.097995) (xy 30.244281 -29.074214) (xy 30.329701 -29.058246)
			(xy 30.41623 -29.050228) (xy 30.50313 -29.050228) (xy 30.589659 -29.058246) (xy 30.675079 -29.074214)
			(xy 30.758661 -29.097995) (xy 30.839693 -29.129387) (xy 30.917482 -29.168121) (xy 30.991366 -29.213868)
			(xy 31.060713 -29.266237) (xy 31.124933 -29.324781) (xy 31.183477 -29.389001) (xy 31.235846 -29.458348)
			(xy 31.281593 -29.532232) (xy 31.320327 -29.610021) (xy 31.351719 -29.691053) (xy 31.3755 -29.774635)
			(xy 31.391468 -29.860055) (xy 31.399486 -29.946584) (xy 31.399988 -29.990034) (xy 31.399486 -30.033484)
			(xy 34.599874 -30.033484) (xy 34.599874 -29.946584) (xy 34.607892 -29.860055) (xy 34.62386 -29.774635)
			(xy 34.647641 -29.691053) (xy 34.679033 -29.610021) (xy 34.717767 -29.532232) (xy 34.763514 -29.458348)
			(xy 34.815883 -29.389001) (xy 34.874427 -29.324781) (xy 34.938647 -29.266237) (xy 35.007994 -29.213868)
			(xy 35.081878 -29.168121) (xy 35.159667 -29.129387) (xy 35.240699 -29.097995) (xy 35.324281 -29.074214)
			(xy 35.409701 -29.058246) (xy 35.49623 -29.050228) (xy 35.58313 -29.050228) (xy 35.669659 -29.058246)
			(xy 35.755079 -29.074214) (xy 35.838661 -29.097995) (xy 35.919693 -29.129387) (xy 35.997482 -29.168121)
			(xy 36.071366 -29.213868) (xy 36.140713 -29.266237) (xy 36.204933 -29.324781) (xy 36.258565 -29.383613)
			(xy 64.827449 -29.383613) (xy 64.827449 -29.320387) (xy 64.835701 -29.257702) (xy 64.852064 -29.196631)
			(xy 64.876258 -29.138217) (xy 64.907869 -29.083461) (xy 64.946356 -29.033299) (xy 64.991061 -28.988589)
			(xy 65.041219 -28.950097) (xy 65.095972 -28.91848) (xy 65.154383 -28.89428) (xy 65.215453 -28.877911)
			(xy 65.278137 -28.869652) (xy 65.30975 -28.869132) (xy 66.491866 -28.869132) (xy 66.520129 -28.869525)
			(xy 66.576271 -28.876096) (xy 66.631259 -28.889186) (xy 66.68434 -28.908616) (xy 66.734784 -28.93412)
			(xy 66.758566 -28.949396) (xy 66.79057 -28.970478) (xy 66.993262 -28.970478) (xy 67.025266 -28.949396)
			(xy 67.049065 -28.934151) (xy 67.099516 -28.908672) (xy 67.152593 -28.889248) (xy 67.207573 -28.876145)
			(xy 67.263706 -28.86954) (xy 67.291966 -28.869132) (xy 67.977258 -28.869132) (xy 68.008874 -28.869652)
			(xy 68.071567 -28.8779) (xy 68.132646 -28.894262) (xy 68.191067 -28.918456) (xy 68.24583 -28.950069)
			(xy 68.295998 -28.98856) (xy 68.340712 -29.033271) (xy 68.379207 -29.083435) (xy 68.410825 -29.138195)
			(xy 68.435025 -29.196614) (xy 68.451391 -29.257692) (xy 68.459645 -29.320384) (xy 68.459645 -29.383616)
			(xy 68.451391 -29.446308) (xy 68.435025 -29.507386) (xy 68.410825 -29.565805) (xy 68.379207 -29.620565)
			(xy 68.340712 -29.670729) (xy 68.295998 -29.71544) (xy 68.24583 -29.753931) (xy 68.191067 -29.785544)
			(xy 68.132646 -29.809738) (xy 68.071567 -29.8261) (xy 68.008874 -29.834348) (xy 67.977258 -29.83484)
			(xy 67.291966 -29.83484) (xy 67.263703 -29.834468) (xy 67.20756 -29.827891) (xy 67.152572 -29.814795)
			(xy 67.099492 -29.795361) (xy 67.049047 -29.769854) (xy 67.025266 -29.754576) (xy 66.993262 -29.733494)
			(xy 66.79057 -29.733494) (xy 66.758566 -29.754576) (xy 66.734783 -29.769847) (xy 66.684328 -29.795322)
			(xy 66.631246 -29.814741) (xy 66.576263 -29.827838) (xy 66.520127 -29.834436) (xy 66.491866 -29.83484)
			(xy 65.30975 -29.83484) (xy 65.278137 -29.834348) (xy 65.215453 -29.826089) (xy 65.154383 -29.80972)
			(xy 65.095972 -29.78552) (xy 65.041219 -29.753903) (xy 64.991061 -29.715411) (xy 64.946356 -29.670701)
			(xy 64.907869 -29.620539) (xy 64.876258 -29.565783) (xy 64.852064 -29.507369) (xy 64.835701 -29.446298)
			(xy 64.827449 -29.383613) (xy 36.258565 -29.383613) (xy 36.263477 -29.389001) (xy 36.315846 -29.458348)
			(xy 36.361593 -29.532232) (xy 36.400327 -29.610021) (xy 36.431719 -29.691053) (xy 36.4555 -29.774635)
			(xy 36.471468 -29.860055) (xy 36.479486 -29.946584) (xy 36.479988 -29.990034) (xy 36.479486 -30.033484)
			(xy 36.471468 -30.120013) (xy 36.469415 -30.130998) (xy 41.909087 -30.130998) (xy 41.912975 -30.076643)
			(xy 41.924559 -30.023395) (xy 41.943604 -29.972338) (xy 41.969721 -29.924511) (xy 42.002379 -29.880889)
			(xy 42.040913 -29.842358) (xy 42.084539 -29.809703) (xy 42.132368 -29.78359) (xy 42.183427 -29.76455)
			(xy 42.236676 -29.75297) (xy 42.29103 -29.749087) (xy 42.345385 -29.752979) (xy 42.398632 -29.764567)
			(xy 42.449687 -29.783615) (xy 42.497512 -29.809736) (xy 42.5196 -29.825696) (xy 42.538612 -29.839292)
			(xy 42.580495 -29.860024) (xy 42.625463 -29.87275) (xy 42.672 -29.87704) (xy 42.718537 -29.87275)
			(xy 42.763505 -29.860024) (xy 42.805388 -29.839292) (xy 42.8244 -29.825696) (xy 42.846484 -29.809731)
			(xy 42.89431 -29.783609) (xy 42.945367 -29.764561) (xy 42.998614 -29.752972) (xy 43.05297 -29.74908)
			(xy 43.107325 -29.752964) (xy 43.160575 -29.764544) (xy 43.211634 -29.783584) (xy 43.259464 -29.809698)
			(xy 43.303091 -29.842353) (xy 43.341626 -29.880884) (xy 43.374285 -29.924508) (xy 43.400402 -29.972336)
			(xy 43.419447 -30.023394) (xy 43.431032 -30.076642) (xy 43.43492 -30.130998) (xy 43.795779 -30.130998)
			(xy 43.799668 -30.076642) (xy 43.811252 -30.023392) (xy 43.830298 -29.972334) (xy 43.856416 -29.924505)
			(xy 43.889076 -29.880881) (xy 43.927611 -29.84235) (xy 43.971239 -29.809695) (xy 44.01907 -29.783581)
			(xy 44.07013 -29.764541) (xy 44.123381 -29.752962) (xy 44.177737 -29.749079) (xy 44.232093 -29.752973)
			(xy 44.285341 -29.764562) (xy 44.336398 -29.783612) (xy 44.384224 -29.809735) (xy 44.406312 -29.825696)
			(xy 44.425324 -29.839292) (xy 44.467207 -29.860024) (xy 44.512175 -29.87275) (xy 44.558712 -29.87704)
			(xy 44.605249 -29.87275) (xy 44.650217 -29.860024) (xy 44.6921 -29.839292) (xy 44.711112 -29.825696)
			(xy 44.733196 -29.809732) (xy 44.781021 -29.783612) (xy 44.832076 -29.764565) (xy 44.885323 -29.752978)
			(xy 44.939676 -29.749087) (xy 44.99403 -29.752972) (xy 45.047278 -29.764552) (xy 45.098336 -29.783593)
			(xy 45.146164 -29.809706) (xy 45.189789 -29.842361) (xy 45.228322 -29.880891) (xy 45.26098 -29.924514)
			(xy 45.287096 -29.97234) (xy 45.306141 -30.023397) (xy 45.317725 -30.076644) (xy 45.321613 -30.130998)
			(xy 45.317725 -30.185351) (xy 45.306142 -30.238599) (xy 45.287098 -30.289655) (xy 45.260982 -30.337482)
			(xy 45.228325 -30.381105) (xy 45.189793 -30.419636) (xy 45.146168 -30.452291) (xy 45.09834 -30.478405)
			(xy 45.047283 -30.497447) (xy 44.994035 -30.509028) (xy 44.939681 -30.512913) (xy 44.885328 -30.509022)
			(xy 44.832081 -30.497436) (xy 44.781025 -30.47839) (xy 44.7332 -30.452271) (xy 44.711112 -30.436312)
			(xy 44.6921 -30.422716) (xy 44.650217 -30.401984) (xy 44.605249 -30.389258) (xy 44.558712 -30.384968)
			(xy 44.512175 -30.389258) (xy 44.467207 -30.401984) (xy 44.425324 -30.422716) (xy 44.406312 -30.436312)
			(xy 44.38422 -30.452268) (xy 44.336394 -30.47839) (xy 44.285337 -30.497439) (xy 44.232088 -30.509028)
			(xy 44.177732 -30.512921) (xy 44.123376 -30.509037) (xy 44.070126 -30.497457) (xy 44.019065 -30.478417)
			(xy 43.971235 -30.452303) (xy 43.927608 -30.419647) (xy 43.889073 -30.381115) (xy 43.856414 -30.33749)
			(xy 43.830296 -30.289662) (xy 43.811251 -30.238603) (xy 43.799667 -30.185354) (xy 43.795779 -30.130998)
			(xy 43.43492 -30.130998) (xy 43.431032 -30.185353) (xy 43.419449 -30.238602) (xy 43.400404 -30.28966)
			(xy 43.374287 -30.337488) (xy 43.341629 -30.381112) (xy 43.303094 -30.419644) (xy 43.259468 -30.4523)
			(xy 43.211639 -30.478414) (xy 43.16058 -30.497455) (xy 43.10733 -30.509036) (xy 43.052974 -30.51292)
			(xy 42.998619 -30.509028) (xy 42.945371 -30.497441) (xy 42.894315 -30.478393) (xy 42.846488 -30.452272)
			(xy 42.8244 -30.436312) (xy 42.805388 -30.422716) (xy 42.763505 -30.401984) (xy 42.718537 -30.389258)
			(xy 42.672 -30.384968) (xy 42.625463 -30.389258) (xy 42.580495 -30.401984) (xy 42.538612 -30.422716)
			(xy 42.5196 -30.436312) (xy 42.497508 -30.452267) (xy 42.449683 -30.478387) (xy 42.398627 -30.497434)
			(xy 42.34538 -30.509022) (xy 42.291026 -30.512913) (xy 42.236671 -30.509029) (xy 42.183422 -30.497449)
			(xy 42.132364 -30.478408) (xy 42.084535 -30.452294) (xy 42.04091 -30.419639) (xy 42.002376 -30.381108)
			(xy 41.969718 -30.337484) (xy 41.943602 -30.289657) (xy 41.924558 -30.2386) (xy 41.912974 -30.185352)
			(xy 41.909087 -30.130998) (xy 36.469415 -30.130998) (xy 36.4555 -30.205433) (xy 36.431719 -30.289015)
			(xy 36.400327 -30.370047) (xy 36.361593 -30.447836) (xy 36.315846 -30.52172) (xy 36.263477 -30.591067)
			(xy 36.204933 -30.655287) (xy 36.140713 -30.713831) (xy 36.071366 -30.7662) (xy 35.997482 -30.811947)
			(xy 35.919693 -30.850681) (xy 35.838661 -30.882073) (xy 35.755079 -30.905854) (xy 35.669659 -30.921822)
			(xy 35.58313 -30.92984) (xy 35.49623 -30.92984) (xy 35.409701 -30.921822) (xy 35.324281 -30.905854)
			(xy 35.240699 -30.882073) (xy 35.159667 -30.850681) (xy 35.081878 -30.811947) (xy 35.007994 -30.7662)
			(xy 34.938647 -30.713831) (xy 34.874427 -30.655287) (xy 34.815883 -30.591067) (xy 34.763514 -30.52172)
			(xy 34.717767 -30.447836) (xy 34.679033 -30.370047) (xy 34.647641 -30.289015) (xy 34.62386 -30.205433)
			(xy 34.607892 -30.120013) (xy 34.599874 -30.033484) (xy 31.399486 -30.033484) (xy 31.391468 -30.120013)
			(xy 31.3755 -30.205433) (xy 31.351719 -30.289015) (xy 31.320327 -30.370047) (xy 31.281593 -30.447836)
			(xy 31.235846 -30.52172) (xy 31.183477 -30.591067) (xy 31.124933 -30.655287) (xy 31.060713 -30.713831)
			(xy 30.991366 -30.7662) (xy 30.917482 -30.811947) (xy 30.839693 -30.850681) (xy 30.758661 -30.882073)
			(xy 30.675079 -30.905854) (xy 30.589659 -30.921822) (xy 30.50313 -30.92984) (xy 30.41623 -30.92984)
			(xy 30.329701 -30.921822) (xy 30.244281 -30.905854) (xy 30.160699 -30.882073) (xy 30.079667 -30.850681)
			(xy 30.001878 -30.811947) (xy 29.927994 -30.7662) (xy 29.858647 -30.713831) (xy 29.794427 -30.655287)
			(xy 29.735883 -30.591067) (xy 29.683514 -30.52172) (xy 29.637767 -30.447836) (xy 29.599033 -30.370047)
			(xy 29.567641 -30.289015) (xy 29.54386 -30.205433) (xy 29.527892 -30.120013) (xy 29.519874 -30.033484)
			(xy 29.24048 -30.033484) (xy 29.24048 -32.573484) (xy 29.519874 -32.573484) (xy 29.519874 -32.486584)
			(xy 29.527892 -32.400055) (xy 29.54386 -32.314635) (xy 29.567641 -32.231053) (xy 29.599033 -32.150021)
			(xy 29.637767 -32.072232) (xy 29.683514 -31.998348) (xy 29.735883 -31.929001) (xy 29.794427 -31.864781)
			(xy 29.858647 -31.806237) (xy 29.927994 -31.753868) (xy 30.001878 -31.708121) (xy 30.079667 -31.669387)
			(xy 30.160699 -31.637995) (xy 30.244281 -31.614214) (xy 30.329701 -31.598246) (xy 30.41623 -31.590228)
			(xy 30.50313 -31.590228) (xy 30.589659 -31.598246) (xy 30.675079 -31.614214) (xy 30.758661 -31.637995)
			(xy 30.839693 -31.669387) (xy 30.917482 -31.708121) (xy 30.991366 -31.753868) (xy 31.060713 -31.806237)
			(xy 31.124933 -31.864781) (xy 31.183477 -31.929001) (xy 31.235846 -31.998348) (xy 31.281593 -32.072232)
			(xy 31.320327 -32.150021) (xy 31.351719 -32.231053) (xy 31.3755 -32.314635) (xy 31.391468 -32.400055)
			(xy 31.399486 -32.486584) (xy 31.399988 -32.530034) (xy 31.399486 -32.573484) (xy 34.599874 -32.573484)
			(xy 34.599874 -32.486584) (xy 34.607892 -32.400055) (xy 34.62386 -32.314635) (xy 34.647641 -32.231053)
			(xy 34.679033 -32.150021) (xy 34.717767 -32.072232) (xy 34.763514 -31.998348) (xy 34.815883 -31.929001)
			(xy 34.874427 -31.864781) (xy 34.938647 -31.806237) (xy 35.007994 -31.753868) (xy 35.081878 -31.708121)
			(xy 35.159667 -31.669387) (xy 35.240699 -31.637995) (xy 35.324281 -31.614214) (xy 35.409701 -31.598246)
			(xy 35.49623 -31.590228) (xy 35.58313 -31.590228) (xy 35.669659 -31.598246) (xy 35.755079 -31.614214)
			(xy 35.838661 -31.637995) (xy 35.919693 -31.669387) (xy 35.997482 -31.708121) (xy 36.071366 -31.753868)
			(xy 36.140713 -31.806237) (xy 36.204933 -31.864781) (xy 36.263477 -31.929001) (xy 36.315846 -31.998348)
			(xy 36.336606 -32.031876) (xy 41.909115 -32.031876) (xy 41.913006 -31.977526) (xy 41.924593 -31.924283)
			(xy 41.943639 -31.873231) (xy 41.969757 -31.825409) (xy 42.002415 -31.781791) (xy 42.040949 -31.743265)
			(xy 42.084573 -31.710616) (xy 42.1324 -31.684507) (xy 42.183456 -31.665471) (xy 42.236701 -31.653895)
			(xy 42.291052 -31.650016) (xy 42.345402 -31.65391) (xy 42.398644 -31.665501) (xy 42.449695 -31.68455)
			(xy 42.497515 -31.710672) (xy 42.5196 -31.726632) (xy 42.538612 -31.740228) (xy 42.580495 -31.76096)
			(xy 42.625463 -31.773686) (xy 42.672 -31.777976) (xy 42.718537 -31.773686) (xy 42.763505 -31.76096)
			(xy 42.805388 -31.740228) (xy 42.8244 -31.726632) (xy 42.846451 -31.710618) (xy 42.894279 -31.684492)
			(xy 42.945338 -31.665439) (xy 42.998589 -31.653847) (xy 43.052948 -31.649951) (xy 43.107308 -31.653832)
			(xy 43.160562 -31.66541) (xy 43.211627 -31.684449) (xy 43.259462 -31.710562) (xy 43.303093 -31.743217)
			(xy 43.341633 -31.781749) (xy 43.374297 -31.825374) (xy 43.400419 -31.873204) (xy 43.419469 -31.924265)
			(xy 43.431057 -31.977517) (xy 43.434949 -32.031876) (xy 43.795808 -32.031876) (xy 43.799699 -31.977524)
			(xy 43.811286 -31.92428) (xy 43.830333 -31.873226) (xy 43.856452 -31.825403) (xy 43.889112 -31.781784)
			(xy 43.927647 -31.743257) (xy 43.971273 -31.710607) (xy 44.019101 -31.684499) (xy 44.070159 -31.665463)
			(xy 44.123406 -31.653887) (xy 44.177759 -31.650008) (xy 44.23211 -31.653904) (xy 44.285354 -31.665496)
			(xy 44.336406 -31.684548) (xy 44.384226 -31.710671) (xy 44.406312 -31.726632) (xy 44.425324 -31.740228)
			(xy 44.467207 -31.76096) (xy 44.512175 -31.773686) (xy 44.558712 -31.777976) (xy 44.605249 -31.773686)
			(xy 44.650217 -31.76096) (xy 44.6921 -31.740228) (xy 44.711112 -31.726632) (xy 44.733162 -31.710619)
			(xy 44.780989 -31.684495) (xy 44.832048 -31.665444) (xy 44.885297 -31.653853) (xy 44.939655 -31.649959)
			(xy 44.994013 -31.65384) (xy 45.047266 -31.665418) (xy 45.098328 -31.684458) (xy 45.146162 -31.71057)
			(xy 45.189792 -31.743225) (xy 45.22833 -31.781756) (xy 45.260992 -31.82538) (xy 45.287114 -31.873209)
			(xy 45.306162 -31.924268) (xy 45.31775 -31.977518) (xy 45.321641 -32.031876) (xy 45.317757 -32.086234)
			(xy 45.306176 -32.139486) (xy 45.287134 -32.190548) (xy 45.261018 -32.238379) (xy 45.228361 -32.282008)
			(xy 45.189828 -32.320544) (xy 45.146202 -32.353204) (xy 45.098372 -32.379323) (xy 45.047312 -32.398368)
			(xy 44.994061 -32.409953) (xy 44.939703 -32.413841) (xy 44.885345 -32.409954) (xy 44.832094 -32.39837)
			(xy 44.781033 -32.379325) (xy 44.733203 -32.353207) (xy 44.711112 -32.337248) (xy 44.6921 -32.323652)
			(xy 44.650217 -32.30292) (xy 44.605249 -32.290194) (xy 44.558712 -32.285904) (xy 44.512175 -32.290194)
			(xy 44.467207 -32.30292) (xy 44.425324 -32.323652) (xy 44.406312 -32.337248) (xy 44.384186 -32.353155)
			(xy 44.336362 -32.379272) (xy 44.285308 -32.398318) (xy 44.232063 -32.409903) (xy 44.177711 -32.413792)
			(xy 44.123359 -32.409906) (xy 44.070113 -32.398324) (xy 44.019058 -32.379281) (xy 43.971232 -32.353167)
			(xy 43.92761 -32.320511) (xy 43.88908 -32.28198) (xy 43.856426 -32.238357) (xy 43.830313 -32.19053)
			(xy 43.811273 -32.139474) (xy 43.799692 -32.086228) (xy 43.795808 -32.031876) (xy 43.434949 -32.031876)
			(xy 43.431064 -32.086236) (xy 43.419482 -32.139489) (xy 43.400439 -32.190552) (xy 43.374323 -32.238385)
			(xy 43.341665 -32.282015) (xy 43.30313 -32.320552) (xy 43.259502 -32.353212) (xy 43.21167 -32.379331)
			(xy 43.160608 -32.398377) (xy 43.107355 -32.409961) (xy 43.052996 -32.413849) (xy 42.998637 -32.40996)
			(xy 42.945384 -32.398374) (xy 42.894322 -32.379328) (xy 42.846491 -32.353208) (xy 42.8244 -32.337248)
			(xy 42.805388 -32.323652) (xy 42.763505 -32.30292) (xy 42.718537 -32.290194) (xy 42.672 -32.285904)
			(xy 42.625463 -32.290194) (xy 42.580495 -32.30292) (xy 42.538612 -32.323652) (xy 42.5196 -32.337248)
			(xy 42.497474 -32.353154) (xy 42.449651 -32.37927) (xy 42.398598 -32.398313) (xy 42.345354 -32.409897)
			(xy 42.291004 -32.413785) (xy 42.236654 -32.409898) (xy 42.18341 -32.398315) (xy 42.132356 -32.379273)
			(xy 42.084532 -32.353158) (xy 42.040912 -32.320503) (xy 42.002384 -32.281973) (xy 41.969731 -32.238351)
			(xy 41.943619 -32.190526) (xy 41.924579 -32.139471) (xy 41.912999 -32.086227) (xy 41.909115 -32.031876)
			(xy 36.336606 -32.031876) (xy 36.361593 -32.072232) (xy 36.400327 -32.150021) (xy 36.431719 -32.231053)
			(xy 36.4555 -32.314635) (xy 36.471468 -32.400055) (xy 36.479486 -32.486584) (xy 36.479988 -32.530034)
			(xy 36.479486 -32.573484) (xy 36.475756 -32.613733) (xy 64.781891 -32.613733) (xy 64.781891 -32.550467)
			(xy 64.79015 -32.487741) (xy 64.806525 -32.42663) (xy 64.830737 -32.36818) (xy 64.862372 -32.31339)
			(xy 64.900888 -32.263198) (xy 64.945627 -32.218463) (xy 64.995821 -32.179951) (xy 65.050614 -32.148321)
			(xy 65.109066 -32.124113) (xy 65.170178 -32.107742) (xy 65.232905 -32.099489) (xy 65.264538 -32.098996)
			(xy 66.321178 -32.098996) (xy 66.333878 -32.09671) (xy 66.364976 -32.090889) (xy 66.428091 -32.086473)
			(xy 66.491242 -32.090338) (xy 66.553347 -32.102419) (xy 66.613342 -32.122509) (xy 66.670198 -32.150264)
			(xy 66.696844 -32.167322) (xy 66.728594 -32.188404) (xy 66.785744 -32.188404) (xy 66.785744 -32.243522)
			(xy 66.805622 -32.265832) (xy 66.829875 -32.29991) (xy 69.997584 -32.29991) (xy 70.001572 -32.04729)
			(xy 70.013533 -31.794922) (xy 70.033455 -31.543058) (xy 70.061319 -31.291948) (xy 70.097095 -31.041842)
			(xy 70.140749 -30.792991) (xy 70.192238 -30.545642) (xy 70.251509 -30.300041) (xy 70.318504 -30.056434)
			(xy 70.393155 -29.815064) (xy 70.47539 -29.57617) (xy 70.565124 -29.339992) (xy 70.66227 -29.106764)
			(xy 70.76673 -28.876718) (xy 70.878401 -28.650086) (xy 70.99717 -28.427091) (xy 71.122919 -28.207957)
			(xy 71.255524 -27.992902) (xy 71.394851 -27.78214) (xy 71.540763 -27.575882) (xy 71.693113 -27.374333)
			(xy 71.851749 -27.177693) (xy 72.016514 -26.98616) (xy 72.187244 -26.799923) (xy 72.363768 -26.619169)
			(xy 72.54591 -26.444078) (xy 72.733488 -26.274824) (xy 72.926316 -26.111575) (xy 73.124201 -25.954496)
			(xy 73.326947 -25.803741) (xy 73.534351 -25.659463) (xy 73.746206 -25.521803) (xy 73.962301 -25.3909)
			(xy 74.182421 -25.266884) (xy 74.406346 -25.149879) (xy 74.633853 -25.040001) (xy 74.864715 -24.93736)
			(xy 75.098703 -24.842058) (xy 75.335582 -24.754191) (xy 75.575118 -24.673844) (xy 75.81707 -24.6011)
			(xy 76.061198 -24.53603) (xy 76.307259 -24.4787) (xy 76.555007 -24.429166) (xy 76.804195 -24.387477)
			(xy 77.054575 -24.353676) (xy 77.305897 -24.327795) (xy 77.557911 -24.309862) (xy 77.810365 -24.299893)
			(xy 78.063009 -24.297899) (xy 78.315589 -24.303881) (xy 78.567855 -24.317834) (xy 78.819554 -24.339744)
			(xy 79.070437 -24.369588) (xy 79.320252 -24.407338) (xy 79.568751 -24.452955) (xy 79.815686 -24.506394)
			(xy 80.060811 -24.567602) (xy 80.303881 -24.636517) (xy 80.544655 -24.713072) (xy 80.782892 -24.797189)
			(xy 81.018355 -24.888786) (xy 81.250809 -24.98777) (xy 81.480023 -25.094042) (xy 81.705767 -25.207498)
			(xy 81.927817 -25.328023) (xy 82.145951 -25.455499) (xy 82.359953 -25.589797) (xy 82.569609 -25.730783)
			(xy 82.774709 -25.878318) (xy 82.975049 -26.032254) (xy 83.17043 -26.192438) (xy 83.360657 -26.35871)
			(xy 83.54554 -26.530905) (xy 83.724896 -26.708849) (xy 83.898544 -26.892368) (xy 84.066312 -27.081276)
			(xy 84.228033 -27.275387) (xy 84.383546 -27.474506) (xy 84.532695 -27.678435) (xy 84.675332 -27.886971)
			(xy 84.811315 -28.099906) (xy 84.940508 -28.317028) (xy 85.062783 -28.53812) (xy 85.178017 -28.762961)
			(xy 85.286096 -28.991329) (xy 85.386911 -29.222994) (xy 85.480363 -29.457727) (xy 85.566358 -29.695292)
			(xy 85.644811 -29.935454) (xy 85.715643 -30.177973) (xy 85.778784 -30.422608) (xy 85.834171 -30.669113)
			(xy 85.881748 -30.917244) (xy 85.921468 -31.166754) (xy 85.953292 -31.417393) (xy 85.977188 -31.668911)
			(xy 85.993132 -31.921059) (xy 86.001107 -32.173584) (xy 86.001606 -32.29991) (xy 86.001107 -32.426236)
			(xy 85.993132 -32.678761) (xy 85.977188 -32.930909) (xy 85.953292 -33.182427) (xy 85.921468 -33.433066)
			(xy 85.881748 -33.682576) (xy 85.834171 -33.930707) (xy 85.778784 -34.177212) (xy 85.715643 -34.421847)
			(xy 85.644811 -34.664366) (xy 85.566358 -34.904528) (xy 85.480363 -35.142093) (xy 85.386911 -35.376826)
			(xy 85.286096 -35.608491) (xy 85.178017 -35.836859) (xy 85.062783 -36.0617) (xy 84.940508 -36.282792)
			(xy 84.811315 -36.499914) (xy 84.675332 -36.712849) (xy 84.532695 -36.921385) (xy 84.383546 -37.125314)
			(xy 84.228033 -37.324433) (xy 84.066312 -37.518544) (xy 83.898544 -37.707452) (xy 83.724896 -37.890971)
			(xy 83.54554 -38.068915) (xy 83.360657 -38.24111) (xy 83.17043 -38.407382) (xy 82.975049 -38.567566)
			(xy 82.774709 -38.721502) (xy 82.569609 -38.869037) (xy 82.359953 -39.010023) (xy 82.145951 -39.144321)
			(xy 81.927817 -39.271797) (xy 81.705767 -39.392322) (xy 81.480023 -39.505778) (xy 81.250809 -39.61205)
			(xy 81.018355 -39.711034) (xy 80.782892 -39.802631) (xy 80.544655 -39.886748) (xy 80.303881 -39.963303)
			(xy 80.060811 -40.032218) (xy 79.815686 -40.093426) (xy 79.568751 -40.146865) (xy 79.320252 -40.192482)
			(xy 79.070437 -40.230232) (xy 78.819554 -40.260076) (xy 78.567855 -40.281986) (xy 78.315589 -40.295939)
			(xy 78.063009 -40.301921) (xy 77.810365 -40.299927) (xy 77.557911 -40.289958) (xy 77.305897 -40.272025)
			(xy 77.054575 -40.246144) (xy 76.804195 -40.212343) (xy 76.555007 -40.170654) (xy 76.307259 -40.12112)
			(xy 76.061198 -40.06379) (xy 75.81707 -39.99872) (xy 75.575118 -39.925976) (xy 75.335582 -39.845629)
			(xy 75.098703 -39.757762) (xy 74.864715 -39.66246) (xy 74.633853 -39.559819) (xy 74.406346 -39.449941)
			(xy 74.182421 -39.332936) (xy 73.962301 -39.20892) (xy 73.746206 -39.078017) (xy 73.534351 -38.940357)
			(xy 73.326947 -38.796079) (xy 73.124201 -38.645324) (xy 72.926316 -38.488245) (xy 72.733488 -38.324996)
			(xy 72.54591 -38.155742) (xy 72.363768 -37.980651) (xy 72.187244 -37.799897) (xy 72.016514 -37.61366)
			(xy 71.851749 -37.422127) (xy 71.693113 -37.225487) (xy 71.540763 -37.023938) (xy 71.394851 -36.81768)
			(xy 71.255524 -36.606918) (xy 71.122919 -36.391863) (xy 70.99717 -36.172729) (xy 70.878401 -35.949734)
			(xy 70.76673 -35.723102) (xy 70.66227 -35.493056) (xy 70.565124 -35.259828) (xy 70.47539 -35.02365)
			(xy 70.393155 -34.784756) (xy 70.318504 -34.543386) (xy 70.251509 -34.299779) (xy 70.192238 -34.054178)
			(xy 70.140749 -33.806829) (xy 70.097095 -33.557978) (xy 70.061319 -33.307872) (xy 70.033455 -33.056762)
			(xy 70.013533 -32.804898) (xy 70.001572 -32.55253) (xy 69.997584 -32.29991) (xy 66.829875 -32.29991)
			(xy 66.840271 -32.314517) (xy 66.868647 -32.367106) (xy 66.890318 -32.422794) (xy 66.904951 -32.480731)
			(xy 66.912323 -32.540031) (xy 66.912322 -32.599787) (xy 66.904948 -32.659086) (xy 66.890312 -32.717022)
			(xy 66.86864 -32.77271) (xy 66.840262 -32.825298) (xy 66.805611 -32.873982) (xy 66.785744 -32.896302)
			(xy 66.785744 -32.95142) (xy 66.731642 -32.95142) (xy 66.61785 -33.065212) (xy 65.264538 -33.065212)
			(xy 65.232905 -33.064711) (xy 65.170178 -33.056458) (xy 65.109066 -33.040087) (xy 65.050614 -33.015879)
			(xy 64.995821 -32.984249) (xy 64.945627 -32.945737) (xy 64.900888 -32.901002) (xy 64.862372 -32.85081)
			(xy 64.830737 -32.79602) (xy 64.806525 -32.73757) (xy 64.79015 -32.676459) (xy 64.781891 -32.613733)
			(xy 36.475756 -32.613733) (xy 36.471468 -32.660013) (xy 36.4555 -32.745433) (xy 36.431719 -32.829015)
			(xy 36.400327 -32.910047) (xy 36.361593 -32.987836) (xy 36.315846 -33.06172) (xy 36.263477 -33.131067)
			(xy 36.204933 -33.195287) (xy 36.140713 -33.253831) (xy 36.071366 -33.3062) (xy 35.997482 -33.351947)
			(xy 35.919693 -33.390681) (xy 35.838661 -33.422073) (xy 35.755079 -33.445854) (xy 35.669659 -33.461822)
			(xy 35.58313 -33.46984) (xy 35.49623 -33.46984) (xy 35.409701 -33.461822) (xy 35.324281 -33.445854)
			(xy 35.240699 -33.422073) (xy 35.159667 -33.390681) (xy 35.081878 -33.351947) (xy 35.007994 -33.3062)
			(xy 34.938647 -33.253831) (xy 34.874427 -33.195287) (xy 34.815883 -33.131067) (xy 34.763514 -33.06172)
			(xy 34.717767 -32.987836) (xy 34.679033 -32.910047) (xy 34.647641 -32.829015) (xy 34.62386 -32.745433)
			(xy 34.607892 -32.660013) (xy 34.599874 -32.573484) (xy 31.399486 -32.573484) (xy 31.391468 -32.660013)
			(xy 31.3755 -32.745433) (xy 31.351719 -32.829015) (xy 31.320327 -32.910047) (xy 31.281593 -32.987836)
			(xy 31.235846 -33.06172) (xy 31.183477 -33.131067) (xy 31.124933 -33.195287) (xy 31.060713 -33.253831)
			(xy 30.991366 -33.3062) (xy 30.917482 -33.351947) (xy 30.839693 -33.390681) (xy 30.758661 -33.422073)
			(xy 30.675079 -33.445854) (xy 30.589659 -33.461822) (xy 30.50313 -33.46984) (xy 30.41623 -33.46984)
			(xy 30.329701 -33.461822) (xy 30.244281 -33.445854) (xy 30.160699 -33.422073) (xy 30.079667 -33.390681)
			(xy 30.001878 -33.351947) (xy 29.927994 -33.3062) (xy 29.858647 -33.253831) (xy 29.794427 -33.195287)
			(xy 29.735883 -33.131067) (xy 29.683514 -33.06172) (xy 29.637767 -32.987836) (xy 29.599033 -32.910047)
			(xy 29.567641 -32.829015) (xy 29.54386 -32.745433) (xy 29.527892 -32.660013) (xy 29.519874 -32.573484)
			(xy 29.24048 -32.573484) (xy 29.24048 -33.707118) (xy 41.909059 -33.707118) (xy 41.912945 -33.652759)
			(xy 41.924527 -33.599507) (xy 41.94357 -33.548446) (xy 41.969687 -33.500614) (xy 42.002345 -33.456986)
			(xy 42.04088 -33.41845) (xy 42.084507 -33.385791) (xy 42.132338 -33.359674) (xy 42.1834 -33.340629)
			(xy 42.236652 -33.329046) (xy 42.29101 -33.325159) (xy 42.345368 -33.329049) (xy 42.39862 -33.340635)
			(xy 42.44968 -33.359682) (xy 42.49751 -33.385802) (xy 42.5196 -33.401762) (xy 42.538612 -33.415358)
			(xy 42.580495 -33.43609) (xy 42.625463 -33.448816) (xy 42.672 -33.453106) (xy 42.718537 -33.448816)
			(xy 42.763505 -33.43609) (xy 42.805388 -33.415358) (xy 42.8244 -33.401762) (xy 42.846516 -33.385843)
			(xy 42.89434 -33.359726) (xy 42.945394 -33.340681) (xy 42.998639 -33.329096) (xy 43.05299 -33.325207)
			(xy 43.107342 -33.329094) (xy 43.160587 -33.340675) (xy 43.211642 -33.359717) (xy 43.259467 -33.385832)
			(xy 43.303088 -33.418487) (xy 43.341619 -33.457018) (xy 43.374273 -33.50064) (xy 43.400386 -33.548466)
			(xy 43.419427 -33.599521) (xy 43.431008 -33.652766) (xy 43.434893 -33.707118) (xy 43.795752 -33.707118)
			(xy 43.799638 -33.652758) (xy 43.811221 -33.599504) (xy 43.830265 -33.548441) (xy 43.856382 -33.500608)
			(xy 43.889042 -33.456979) (xy 43.927578 -33.418443) (xy 43.971207 -33.385783) (xy 44.01904 -33.359665)
			(xy 44.070103 -33.340621) (xy 44.123357 -33.329038) (xy 44.177717 -33.325152) (xy 44.232077 -33.329043)
			(xy 44.285329 -33.34063) (xy 44.336391 -33.359679) (xy 44.384221 -33.385801) (xy 44.406312 -33.401762)
			(xy 44.425324 -33.415358) (xy 44.467207 -33.43609) (xy 44.512175 -33.448816) (xy 44.558712 -33.453106)
			(xy 44.605249 -33.448816) (xy 44.650217 -33.43609) (xy 44.6921 -33.415358) (xy 44.711112 -33.401762)
			(xy 44.733228 -33.385844) (xy 44.781051 -33.359729) (xy 44.832104 -33.340686) (xy 44.885347 -33.329102)
			(xy 44.939697 -33.325215) (xy 44.994047 -33.329102) (xy 45.04729 -33.340684) (xy 45.098343 -33.359726)
			(xy 45.146167 -33.38584) (xy 45.189787 -33.418495) (xy 45.228315 -33.457025) (xy 45.260968 -33.500646)
			(xy 45.28708 -33.54847) (xy 45.30612 -33.599524) (xy 45.317701 -33.652768) (xy 45.321585 -33.707118)
			(xy 45.317695 -33.761468) (xy 45.30611 -33.814711) (xy 45.287065 -33.865763) (xy 45.260948 -33.913584)
			(xy 45.228292 -33.957203) (xy 45.189759 -33.995729) (xy 45.146136 -34.028379) (xy 45.09831 -34.054489)
			(xy 45.047256 -34.073526) (xy 44.994011 -34.085104) (xy 44.939661 -34.088985) (xy 44.885311 -34.085092)
			(xy 44.832069 -34.073504) (xy 44.781018 -34.054456) (xy 44.733198 -34.028337) (xy 44.711112 -34.012378)
			(xy 44.6921 -33.998782) (xy 44.650217 -33.97805) (xy 44.605249 -33.965324) (xy 44.558712 -33.961034)
			(xy 44.512175 -33.965324) (xy 44.467207 -33.97805) (xy 44.425324 -33.998782) (xy 44.406312 -34.012378)
			(xy 44.384252 -34.028379) (xy 44.336424 -34.054506) (xy 44.285364 -34.073559) (xy 44.232112 -34.085152)
			(xy 44.177753 -34.089048) (xy 44.123392 -34.085167) (xy 44.070138 -34.073589) (xy 44.019073 -34.05455)
			(xy 43.971237 -34.028437) (xy 43.927605 -33.995781) (xy 43.889065 -33.957248) (xy 43.856402 -33.913622)
			(xy 43.83028 -33.865792) (xy 43.811231 -33.81473) (xy 43.799643 -33.761478) (xy 43.795752 -33.707118)
			(xy 43.434893 -33.707118) (xy 43.431002 -33.761469) (xy 43.419417 -33.814714) (xy 43.400371 -33.865767)
			(xy 43.374253 -33.91359) (xy 43.341595 -33.95721) (xy 43.303061 -33.995737) (xy 43.259437 -34.028388)
			(xy 43.211609 -34.054498) (xy 43.160552 -34.073535) (xy 43.107306 -34.085112) (xy 43.052954 -34.088993)
			(xy 42.998603 -34.085098) (xy 42.945359 -34.073509) (xy 42.894307 -34.054459) (xy 42.846486 -34.028338)
			(xy 42.8244 -34.012378) (xy 42.805388 -33.998782) (xy 42.763505 -33.97805) (xy 42.718537 -33.965324)
			(xy 42.672 -33.961034) (xy 42.625463 -33.965324) (xy 42.580495 -33.97805) (xy 42.538612 -33.998782)
			(xy 42.5196 -34.012378) (xy 42.49754 -34.028378) (xy 42.449713 -34.054503) (xy 42.398654 -34.073555)
			(xy 42.345404 -34.085146) (xy 42.291046 -34.089041) (xy 42.236687 -34.085159) (xy 42.183434 -34.073581)
			(xy 42.132371 -34.054541) (xy 42.084538 -34.028428) (xy 42.040907 -33.995773) (xy 42.002369 -33.957241)
			(xy 41.969706 -33.913616) (xy 41.943585 -33.865787) (xy 41.924537 -33.814727) (xy 41.91295 -33.761476)
			(xy 41.909059 -33.707118) (xy 29.24048 -33.707118) (xy 29.24048 -35.113484) (xy 29.519874 -35.113484)
			(xy 29.519874 -35.026584) (xy 29.527892 -34.940055) (xy 29.54386 -34.854635) (xy 29.567641 -34.771053)
			(xy 29.599033 -34.690021) (xy 29.637767 -34.612232) (xy 29.683514 -34.538348) (xy 29.735883 -34.469001)
			(xy 29.794427 -34.404781) (xy 29.858647 -34.346237) (xy 29.927994 -34.293868) (xy 30.001878 -34.248121)
			(xy 30.079667 -34.209387) (xy 30.160699 -34.177995) (xy 30.244281 -34.154214) (xy 30.329701 -34.138246)
			(xy 30.41623 -34.130228) (xy 30.50313 -34.130228) (xy 30.589659 -34.138246) (xy 30.675079 -34.154214)
			(xy 30.758661 -34.177995) (xy 30.839693 -34.209387) (xy 30.917482 -34.248121) (xy 30.991366 -34.293868)
			(xy 31.060713 -34.346237) (xy 31.124933 -34.404781) (xy 31.183477 -34.469001) (xy 31.235846 -34.538348)
			(xy 31.281593 -34.612232) (xy 31.320327 -34.690021) (xy 31.351719 -34.771053) (xy 31.3755 -34.854635)
			(xy 31.391468 -34.940055) (xy 31.399486 -35.026584) (xy 31.399988 -35.070034) (xy 31.399486 -35.113484)
			(xy 34.599874 -35.113484) (xy 34.599874 -35.026584) (xy 34.607892 -34.940055) (xy 34.62386 -34.854635)
			(xy 34.647641 -34.771053) (xy 34.679033 -34.690021) (xy 34.717767 -34.612232) (xy 34.763514 -34.538348)
			(xy 34.815883 -34.469001) (xy 34.874427 -34.404781) (xy 34.938647 -34.346237) (xy 35.007994 -34.293868)
			(xy 35.081878 -34.248121) (xy 35.159667 -34.209387) (xy 35.240699 -34.177995) (xy 35.324281 -34.154214)
			(xy 35.409701 -34.138246) (xy 35.49623 -34.130228) (xy 35.58313 -34.130228) (xy 35.669659 -34.138246)
			(xy 35.755079 -34.154214) (xy 35.838661 -34.177995) (xy 35.919693 -34.209387) (xy 35.997482 -34.248121)
			(xy 36.071366 -34.293868) (xy 36.140713 -34.346237) (xy 36.204933 -34.404781) (xy 36.263477 -34.469001)
			(xy 36.315846 -34.538348) (xy 36.361593 -34.612232) (xy 36.400327 -34.690021) (xy 36.431719 -34.771053)
			(xy 36.4555 -34.854635) (xy 36.471468 -34.940055) (xy 36.479486 -35.026584) (xy 36.479988 -35.070034)
			(xy 36.479486 -35.113484) (xy 36.471468 -35.200013) (xy 36.4555 -35.285433) (xy 36.431719 -35.369015)
			(xy 36.400327 -35.450047) (xy 36.361593 -35.527836) (xy 36.315846 -35.60172) (xy 36.263477 -35.671067)
			(xy 36.220533 -35.718175) (xy 41.865737 -35.718175) (xy 41.869628 -35.66383) (xy 41.881213 -35.610591)
			(xy 41.900257 -35.559543) (xy 41.926372 -35.511726) (xy 41.959027 -35.468111) (xy 41.997556 -35.429588)
			(xy 42.041175 -35.39694) (xy 42.088997 -35.370833) (xy 42.140048 -35.351796) (xy 42.193288 -35.34022)
			(xy 42.247634 -35.336337) (xy 42.301979 -35.340229) (xy 42.355217 -35.351816) (xy 42.406264 -35.370861)
			(xy 42.454082 -35.396977) (xy 42.476166 -35.412934) (xy 42.495178 -35.42653) (xy 42.537061 -35.447262)
			(xy 42.582029 -35.459988) (xy 42.628566 -35.464278) (xy 42.675103 -35.459988) (xy 42.720071 -35.447262)
			(xy 42.761954 -35.42653) (xy 42.780966 -35.412934) (xy 42.803016 -35.396915) (xy 42.850846 -35.370783)
			(xy 42.901909 -35.351725) (xy 42.955164 -35.340128) (xy 43.009527 -35.336229) (xy 43.063892 -35.340108)
			(xy 43.117152 -35.351684) (xy 43.168222 -35.370723) (xy 43.216062 -35.396836) (xy 43.259699 -35.429493)
			(xy 43.298243 -35.468027) (xy 43.330911 -35.511655) (xy 43.357037 -35.559489) (xy 43.376088 -35.610554)
			(xy 43.387678 -35.663811) (xy 43.391571 -35.718175) (xy 43.75243 -35.718175) (xy 43.756321 -35.663828)
			(xy 43.767907 -35.610588) (xy 43.786951 -35.559539) (xy 43.813067 -35.51172) (xy 43.845723 -35.468104)
			(xy 43.884254 -35.42958) (xy 43.927875 -35.396932) (xy 43.975699 -35.370824) (xy 44.026751 -35.351788)
			(xy 44.079993 -35.340212) (xy 44.134341 -35.33633) (xy 44.188687 -35.340223) (xy 44.241927 -35.351811)
			(xy 44.292975 -35.370858) (xy 44.340793 -35.396976) (xy 44.362878 -35.412934) (xy 44.38189 -35.42653)
			(xy 44.423773 -35.447262) (xy 44.468741 -35.459988) (xy 44.515278 -35.464278) (xy 44.561815 -35.459988)
			(xy 44.606783 -35.447262) (xy 44.648666 -35.42653) (xy 44.667678 -35.412934) (xy 44.689727 -35.396916)
			(xy 44.737557 -35.370786) (xy 44.788618 -35.351729) (xy 44.841872 -35.340134) (xy 44.896234 -35.336237)
			(xy 44.950598 -35.340116) (xy 45.003855 -35.351692) (xy 45.054924 -35.370731) (xy 45.102762 -35.396844)
			(xy 45.146397 -35.4295) (xy 45.18494 -35.468034) (xy 45.217606 -35.511661) (xy 45.243731 -35.559494)
			(xy 45.262782 -35.610557) (xy 45.274371 -35.663812) (xy 45.278263 -35.718175) (xy 45.274379 -35.772538)
			(xy 45.262796 -35.825794) (xy 45.243752 -35.87686) (xy 45.217634 -35.924696) (xy 45.184973 -35.968328)
			(xy 45.146435 -36.006867) (xy 45.102804 -36.039528) (xy 45.054969 -36.065648) (xy 45.003904 -36.084693)
			(xy 44.950648 -36.096277) (xy 44.896285 -36.100163) (xy 44.841922 -36.096273) (xy 44.788667 -36.084685)
			(xy 44.737603 -36.065635) (xy 44.68977 -36.039512) (xy 44.667678 -36.02355) (xy 44.648666 -36.009954)
			(xy 44.606783 -35.989222) (xy 44.561815 -35.976496) (xy 44.515278 -35.972206) (xy 44.468741 -35.976496)
			(xy 44.423773 -35.989222) (xy 44.38189 -36.009954) (xy 44.362878 -36.02355) (xy 44.340751 -36.039451)
			(xy 44.292929 -36.065563) (xy 44.241879 -36.084603) (xy 44.188638 -36.096184) (xy 44.13429 -36.10007)
			(xy 44.079943 -36.096181) (xy 44.026703 -36.084598) (xy 43.975653 -36.065555) (xy 43.927833 -36.039441)
			(xy 43.884216 -36.006787) (xy 43.84569 -35.968258) (xy 43.81304 -35.924638) (xy 43.78693 -35.876815)
			(xy 43.767892 -35.825764) (xy 43.756314 -35.772522) (xy 43.75243 -35.718175) (xy 43.391571 -35.718175)
			(xy 43.387686 -35.772539) (xy 43.376103 -35.825798) (xy 43.357058 -35.876865) (xy 43.330938 -35.924702)
			(xy 43.298276 -35.968335) (xy 43.259737 -36.006874) (xy 43.216105 -36.039537) (xy 43.168268 -36.065656)
			(xy 43.117201 -36.084702) (xy 43.063942 -36.096285) (xy 43.009578 -36.100171) (xy 42.955214 -36.096279)
			(xy 42.901957 -36.084689) (xy 42.850892 -36.065638) (xy 42.803058 -36.039513) (xy 42.780966 -36.02355)
			(xy 42.761954 -36.009954) (xy 42.720071 -35.989222) (xy 42.675103 -35.976496) (xy 42.628566 -35.972206)
			(xy 42.582029 -35.976496) (xy 42.537061 -35.989222) (xy 42.495178 -36.009954) (xy 42.476166 -36.02355)
			(xy 42.454039 -36.03945) (xy 42.406219 -36.06556) (xy 42.355169 -36.084599) (xy 42.301929 -36.096178)
			(xy 42.247583 -36.100063) (xy 42.193238 -36.096173) (xy 42.14 -36.084589) (xy 42.088951 -36.065547)
			(xy 42.041133 -36.039433) (xy 41.997518 -36.006779) (xy 41.958994 -35.968251) (xy 41.926345 -35.924632)
			(xy 41.900236 -35.876811) (xy 41.881199 -35.82576) (xy 41.869621 -35.772521) (xy 41.865737 -35.718175)
			(xy 36.220533 -35.718175) (xy 36.204933 -35.735287) (xy 36.140713 -35.793831) (xy 36.071366 -35.8462)
			(xy 35.997482 -35.891947) (xy 35.919693 -35.930681) (xy 35.838661 -35.962073) (xy 35.755079 -35.985854)
			(xy 35.669659 -36.001822) (xy 35.58313 -36.00984) (xy 35.49623 -36.00984) (xy 35.409701 -36.001822)
			(xy 35.324281 -35.985854) (xy 35.240699 -35.962073) (xy 35.159667 -35.930681) (xy 35.081878 -35.891947)
			(xy 35.007994 -35.8462) (xy 34.938647 -35.793831) (xy 34.874427 -35.735287) (xy 34.815883 -35.671067)
			(xy 34.763514 -35.60172) (xy 34.717767 -35.527836) (xy 34.679033 -35.450047) (xy 34.647641 -35.369015)
			(xy 34.62386 -35.285433) (xy 34.607892 -35.200013) (xy 34.599874 -35.113484) (xy 31.399486 -35.113484)
			(xy 31.391468 -35.200013) (xy 31.3755 -35.285433) (xy 31.351719 -35.369015) (xy 31.320327 -35.450047)
			(xy 31.281593 -35.527836) (xy 31.235846 -35.60172) (xy 31.183477 -35.671067) (xy 31.124933 -35.735287)
			(xy 31.060713 -35.793831) (xy 30.991366 -35.8462) (xy 30.917482 -35.891947) (xy 30.839693 -35.930681)
			(xy 30.758661 -35.962073) (xy 30.675079 -35.985854) (xy 30.589659 -36.001822) (xy 30.50313 -36.00984)
			(xy 30.41623 -36.00984) (xy 30.329701 -36.001822) (xy 30.244281 -35.985854) (xy 30.160699 -35.962073)
			(xy 30.079667 -35.930681) (xy 30.001878 -35.891947) (xy 29.927994 -35.8462) (xy 29.858647 -35.793831)
			(xy 29.794427 -35.735287) (xy 29.735883 -35.671067) (xy 29.683514 -35.60172) (xy 29.637767 -35.527836)
			(xy 29.599033 -35.450047) (xy 29.567641 -35.369015) (xy 29.54386 -35.285433) (xy 29.527892 -35.200013)
			(xy 29.519874 -35.113484) (xy 29.24048 -35.113484) (xy 29.24048 -37.653484) (xy 29.519874 -37.653484)
			(xy 29.519874 -37.566584) (xy 29.527892 -37.480055) (xy 29.54386 -37.394635) (xy 29.567641 -37.311053)
			(xy 29.599033 -37.230021) (xy 29.637767 -37.152232) (xy 29.683514 -37.078348) (xy 29.735883 -37.009001)
			(xy 29.794427 -36.944781) (xy 29.858647 -36.886237) (xy 29.927994 -36.833868) (xy 30.001878 -36.788121)
			(xy 30.079667 -36.749387) (xy 30.160699 -36.717995) (xy 30.244281 -36.694214) (xy 30.329701 -36.678246)
			(xy 30.41623 -36.670228) (xy 30.50313 -36.670228) (xy 30.589659 -36.678246) (xy 30.675079 -36.694214)
			(xy 30.758661 -36.717995) (xy 30.839693 -36.749387) (xy 30.917482 -36.788121) (xy 30.991366 -36.833868)
			(xy 31.060713 -36.886237) (xy 31.124933 -36.944781) (xy 31.183477 -37.009001) (xy 31.235846 -37.078348)
			(xy 31.281593 -37.152232) (xy 31.320327 -37.230021) (xy 31.351719 -37.311053) (xy 31.3755 -37.394635)
			(xy 31.391468 -37.480055) (xy 31.399486 -37.566584) (xy 31.399988 -37.610034) (xy 31.399486 -37.653484)
			(xy 34.599874 -37.653484) (xy 34.599874 -37.566584) (xy 34.607892 -37.480055) (xy 34.62386 -37.394635)
			(xy 34.647641 -37.311053) (xy 34.679033 -37.230021) (xy 34.717767 -37.152232) (xy 34.763514 -37.078348)
			(xy 34.815883 -37.009001) (xy 34.874427 -36.944781) (xy 34.938647 -36.886237) (xy 35.007994 -36.833868)
			(xy 35.081878 -36.788121) (xy 35.159667 -36.749387) (xy 35.240699 -36.717995) (xy 35.324281 -36.694214)
			(xy 35.409701 -36.678246) (xy 35.49623 -36.670228) (xy 35.58313 -36.670228) (xy 35.669659 -36.678246)
			(xy 35.755079 -36.694214) (xy 35.838661 -36.717995) (xy 35.919693 -36.749387) (xy 35.997482 -36.788121)
			(xy 36.071366 -36.833868) (xy 36.140713 -36.886237) (xy 36.204933 -36.944781) (xy 36.263477 -37.009001)
			(xy 36.315846 -37.078348) (xy 36.361593 -37.152232) (xy 36.400327 -37.230021) (xy 36.431719 -37.311053)
			(xy 36.4555 -37.394635) (xy 36.471468 -37.480055) (xy 36.479486 -37.566584) (xy 36.479974 -37.608822)
			(xy 41.865675 -37.608822) (xy 41.86956 -37.554467) (xy 41.88114 -37.501219) (xy 41.900181 -37.45016)
			(xy 41.926294 -37.402331) (xy 41.958949 -37.358706) (xy 41.99748 -37.320171) (xy 42.041102 -37.287513)
			(xy 42.088929 -37.261395) (xy 42.139985 -37.24235) (xy 42.193233 -37.230764) (xy 42.247587 -37.226875)
			(xy 42.301942 -37.230761) (xy 42.35519 -37.242342) (xy 42.406248 -37.261384) (xy 42.454076 -37.287499)
			(xy 42.476166 -37.303456) (xy 42.495178 -37.317052) (xy 42.537061 -37.337784) (xy 42.582029 -37.35051)
			(xy 42.628566 -37.3548) (xy 42.675103 -37.35051) (xy 42.720071 -37.337784) (xy 42.761954 -37.317052)
			(xy 42.780966 -37.303456) (xy 42.803089 -37.287542) (xy 42.850914 -37.26142) (xy 42.901971 -37.242372)
			(xy 42.955219 -37.230783) (xy 43.009574 -37.226892) (xy 43.06393 -37.230776) (xy 43.117179 -37.242357)
			(xy 43.168239 -37.261399) (xy 43.216068 -37.287514) (xy 43.259693 -37.32017) (xy 43.298227 -37.358703)
			(xy 43.330884 -37.402329) (xy 43.356999 -37.450158) (xy 43.376042 -37.501217) (xy 43.387623 -37.554466)
			(xy 43.391508 -37.608822) (xy 43.752368 -37.608822) (xy 43.756252 -37.554465) (xy 43.767833 -37.501215)
			(xy 43.786875 -37.450155) (xy 43.81299 -37.402325) (xy 43.845645 -37.358699) (xy 43.884178 -37.320164)
			(xy 43.927802 -37.287505) (xy 43.97563 -37.261387) (xy 44.026689 -37.242341) (xy 44.079938 -37.230756)
			(xy 44.134294 -37.226868) (xy 44.18865 -37.230755) (xy 44.2419 -37.242338) (xy 44.292959 -37.261382)
			(xy 44.340788 -37.287498) (xy 44.362878 -37.303456) (xy 44.38189 -37.317052) (xy 44.423773 -37.337784)
			(xy 44.468741 -37.35051) (xy 44.515278 -37.3548) (xy 44.561815 -37.35051) (xy 44.606783 -37.337784)
			(xy 44.648666 -37.317052) (xy 44.667678 -37.303456) (xy 44.6898 -37.287543) (xy 44.737625 -37.261423)
			(xy 44.788681 -37.242376) (xy 44.841927 -37.23079) (xy 44.896281 -37.226899) (xy 44.950635 -37.230784)
			(xy 45.003883 -37.242366) (xy 45.05494 -37.261407) (xy 45.102768 -37.287522) (xy 45.146392 -37.320178)
			(xy 45.184924 -37.35871) (xy 45.217579 -37.402335) (xy 45.243694 -37.450162) (xy 45.262735 -37.50122)
			(xy 45.274316 -37.554468) (xy 45.278201 -37.608822) (xy 45.27431 -37.663175) (xy 45.262723 -37.716422)
			(xy 45.243676 -37.767477) (xy 45.228812 -37.794692) (xy 51.007772 -37.794692) (xy 52.65928 -37.794692)
			(xy 52.65928 -38.421056) (xy 66.315336 -38.421056) (xy 66.315336 -37.50945) (xy 66.315835 -37.478042)
			(xy 66.323592 -37.415706) (xy 66.338969 -37.354801) (xy 66.361731 -37.296254) (xy 66.391533 -37.240956)
			(xy 66.427919 -37.189752) (xy 66.470337 -37.14342) (xy 66.518139 -37.102666) (xy 66.570597 -37.068111)
			(xy 66.626913 -37.040282) (xy 66.686228 -37.019602) (xy 66.747638 -37.006387) (xy 66.810209 -37.000837)
			(xy 66.872987 -37.003038) (xy 66.935016 -37.012956) (xy 66.99535 -37.030439) (xy 67.053071 -37.055222)
			(xy 67.1073 -37.086927) (xy 67.157209 -37.125071) (xy 67.179952 -37.146738) (xy 67.196599 -37.162322)
			(xy 67.234306 -37.187956) (xy 67.275982 -37.206446) (xy 67.32029 -37.217201) (xy 67.365805 -37.219874)
			(xy 67.411067 -37.214379) (xy 67.454621 -37.200892) (xy 67.495069 -37.179848) (xy 67.53111 -37.151922)
			(xy 67.546728 -37.135308) (xy 67.567884 -37.112528) (xy 67.614782 -37.071716) (xy 67.666308 -37.036928)
			(xy 67.721692 -37.008685) (xy 67.780108 -36.987408) (xy 67.840682 -36.973414) (xy 67.902511 -36.966913)
			(xy 67.964671 -36.968001) (xy 68.026235 -36.976663) (xy 68.086282 -36.992769) (xy 68.143916 -37.016078)
			(xy 68.198278 -37.046244) (xy 68.248554 -37.082814) (xy 68.293995 -37.125243) (xy 68.314316 -37.14877)
			(xy 68.328559 -37.16514) (xy 68.361681 -37.19317) (xy 68.399081 -37.215169) (xy 68.439674 -37.230497)
			(xy 68.48228 -37.238711) (xy 68.525662 -37.239571) (xy 68.56856 -37.233053) (xy 68.609729 -37.219345)
			(xy 68.647972 -37.198846) (xy 68.682179 -37.172151) (xy 68.697094 -37.15639) (xy 68.719686 -37.132207)
			(xy 68.770146 -37.089386) (xy 68.825737 -37.053475) (xy 68.885517 -37.025082) (xy 68.948477 -37.004687)
			(xy 69.013551 -36.992634) (xy 69.079639 -36.989128) (xy 69.145623 -36.994227) (xy 69.210387 -37.007846)
			(xy 69.272836 -37.029754) (xy 69.331914 -37.059581) (xy 69.386622 -37.096823) (xy 69.436035 -37.140849)
			(xy 69.458078 -37.165534) (xy 69.472907 -37.181866) (xy 69.507092 -37.209739) (xy 69.545574 -37.231294)
			(xy 69.587199 -37.245885) (xy 69.630717 -37.253073) (xy 69.674823 -37.252644) (xy 69.718193 -37.244609)
			(xy 69.759525 -37.229211) (xy 69.79758 -37.206911) (xy 69.831216 -37.178377) (xy 69.845682 -37.161724)
			(xy 69.865965 -37.138112) (xy 69.911299 -37.095456) (xy 69.961501 -37.058654) (xy 70.015821 -37.028257)
			(xy 70.073446 -37.004719) (xy 70.133513 -36.988392) (xy 70.195125 -36.979522) (xy 70.257359 -36.97824)
			(xy 70.319283 -36.984567) (xy 70.379972 -36.998406) (xy 70.438517 -37.019552) (xy 70.494043 -37.047687)
			(xy 70.545717 -37.082391) (xy 70.592769 -37.123144) (xy 70.634492 -37.169337) (xy 70.670264 -37.220279)
			(xy 70.699548 -37.275207) (xy 70.721907 -37.333299) (xy 70.737006 -37.393687) (xy 70.74462 -37.455467)
			(xy 70.745096 -37.48659) (xy 70.745096 -38.421056) (xy 70.744579 -38.453782) (xy 70.736189 -38.518693)
			(xy 70.719543 -38.581993) (xy 70.694915 -38.642634) (xy 70.662713 -38.699616) (xy 70.643496 -38.72611)
			(xy 70.618096 -38.759892) (xy 70.618096 -38.777164) (xy 70.602856 -38.777164) (xy 70.567042 -38.80739)
			(xy 70.541865 -38.828243) (xy 70.487133 -38.863994) (xy 70.428268 -38.892433) (xy 70.366243 -38.913088)
			(xy 70.302081 -38.925619) (xy 70.236842 -38.929819) (xy 70.171603 -38.925619) (xy 70.107441 -38.913088)
			(xy 70.045416 -38.892433) (xy 69.986551 -38.863994) (xy 69.931819 -38.828243) (xy 69.906642 -38.80739)
			(xy 69.870828 -38.777164) (xy 69.855588 -38.777164) (xy 69.855588 -38.759892) (xy 69.830188 -38.72611)
			(xy 69.813021 -38.702506) (xy 69.78361 -38.652089) (xy 69.771514 -38.625526) (xy 69.764457 -38.610771)
			(xy 69.744099 -38.585186) (xy 69.71791 -38.565611) (xy 69.687609 -38.553327) (xy 69.655182 -38.549141)
			(xy 69.622755 -38.553327) (xy 69.592454 -38.565611) (xy 69.566265 -38.585186) (xy 69.545907 -38.610771)
			(xy 69.53885 -38.625526) (xy 69.526757 -38.65209) (xy 69.497347 -38.702508) (xy 69.480176 -38.72611)
			(xy 69.454776 -38.759892) (xy 69.454776 -38.777164) (xy 69.439536 -38.777164) (xy 69.403722 -38.80739)
			(xy 69.378545 -38.828243) (xy 69.323813 -38.863994) (xy 69.264948 -38.892433) (xy 69.202923 -38.913088)
			(xy 69.138761 -38.925619) (xy 69.073522 -38.929819) (xy 69.008283 -38.925619) (xy 68.944121 -38.913088)
			(xy 68.882096 -38.892433) (xy 68.823231 -38.863994) (xy 68.768499 -38.828243) (xy 68.743322 -38.80739)
			(xy 68.707508 -38.777164) (xy 68.692268 -38.777164) (xy 68.692268 -38.759892) (xy 68.666868 -38.72611)
			(xy 68.651744 -38.705348) (xy 68.625278 -38.661322) (xy 68.614036 -38.638226) (xy 68.606772 -38.623983)
			(xy 68.58639 -38.599365) (xy 68.560528 -38.580587) (xy 68.53081 -38.568826) (xy 68.499101 -38.564822)
			(xy 68.467392 -38.568826) (xy 68.437674 -38.580587) (xy 68.411812 -38.599365) (xy 68.39143 -38.623983)
			(xy 68.384166 -38.638226) (xy 68.37295 -38.661336) (xy 68.346478 -38.705361) (xy 68.331334 -38.72611)
			(xy 68.306188 -38.759892) (xy 68.306188 -38.777164) (xy 68.290694 -38.777164) (xy 68.25488 -38.80739)
			(xy 68.229703 -38.828243) (xy 68.174971 -38.863994) (xy 68.116106 -38.892433) (xy 68.054081 -38.913088)
			(xy 67.989919 -38.925619) (xy 67.92468 -38.929819) (xy 67.859441 -38.925619) (xy 67.795279 -38.913088)
			(xy 67.733254 -38.892433) (xy 67.674389 -38.863994) (xy 67.619657 -38.828243) (xy 67.59448 -38.80739)
			(xy 67.558666 -38.777164) (xy 67.543172 -38.777164) (xy 67.543172 -38.759892) (xy 67.518026 -38.72611)
			(xy 67.50891 -38.713803) (xy 67.492008 -38.688258) (xy 67.484244 -38.675056) (xy 67.47545 -38.66091)
			(xy 67.451906 -38.637367) (xy 67.423071 -38.620719) (xy 67.39091 -38.612102) (xy 67.357614 -38.612102)
			(xy 67.325453 -38.620719) (xy 67.296618 -38.637367) (xy 67.273074 -38.66091) (xy 67.26428 -38.675056)
			(xy 67.256513 -38.688256) (xy 67.23961 -38.7138) (xy 67.230498 -38.72611) (xy 67.205352 -38.759892)
			(xy 67.205352 -38.777164) (xy 67.189858 -38.777164) (xy 67.154044 -38.80739) (xy 67.128867 -38.828243)
			(xy 67.074135 -38.863994) (xy 67.01527 -38.892433) (xy 66.953245 -38.913088) (xy 66.889083 -38.925619)
			(xy 66.823844 -38.929819) (xy 66.758605 -38.925619) (xy 66.694443 -38.913088) (xy 66.632418 -38.892433)
			(xy 66.573553 -38.863994) (xy 66.518821 -38.828243) (xy 66.493644 -38.80739) (xy 66.45783 -38.777164)
			(xy 66.442336 -38.777164) (xy 66.442336 -38.759892) (xy 66.41719 -38.72611) (xy 66.397949 -38.699622)
			(xy 66.365683 -38.642655) (xy 66.340996 -38.582018) (xy 66.324297 -38.518714) (xy 66.315861 -38.453791)
			(xy 66.315336 -38.421056) (xy 52.65928 -38.421056) (xy 52.65928 -39.446708) (xy 51.007772 -39.446708)
			(xy 51.007772 -37.794692) (xy 45.228812 -37.794692) (xy 45.217556 -37.815302) (xy 45.184895 -37.858922)
			(xy 45.146359 -37.89745) (xy 45.102731 -37.930101) (xy 45.054901 -37.95621) (xy 45.003841 -37.975247)
			(xy 44.950592 -37.986822) (xy 44.896238 -37.990701) (xy 44.841885 -37.986804) (xy 44.788639 -37.975212)
			(xy 44.737586 -37.956159) (xy 44.689764 -37.930034) (xy 44.667678 -37.914072) (xy 44.648666 -37.900476)
			(xy 44.606783 -37.879744) (xy 44.561815 -37.867018) (xy 44.515278 -37.862728) (xy 44.468741 -37.867018)
			(xy 44.423773 -37.879744) (xy 44.38189 -37.900476) (xy 44.362878 -37.914072) (xy 44.340824 -37.930079)
			(xy 44.292998 -37.956201) (xy 44.241941 -37.97525) (xy 44.188693 -37.986839) (xy 44.134337 -37.990732)
			(xy 44.079981 -37.98685) (xy 44.02673 -37.975271) (xy 43.97567 -37.956231) (xy 43.927838 -37.930119)
			(xy 43.88421 -37.897465) (xy 43.845674 -37.858934) (xy 43.813013 -37.815311) (xy 43.786893 -37.767484)
			(xy 43.767846 -37.716426) (xy 43.756259 -37.663177) (xy 43.752368 -37.608822) (xy 43.391508 -37.608822)
			(xy 43.387617 -37.663177) (xy 43.37603 -37.716425) (xy 43.356981 -37.767482) (xy 43.330861 -37.815308)
			(xy 43.298199 -37.858929) (xy 43.259661 -37.897458) (xy 43.216032 -37.93011) (xy 43.168199 -37.956219)
			(xy 43.117138 -37.975255) (xy 43.063887 -37.98683) (xy 43.009531 -37.990708) (xy 42.955176 -37.98681)
			(xy 42.90193 -37.975216) (xy 42.850875 -37.956162) (xy 42.803052 -37.930035) (xy 42.780966 -37.914072)
			(xy 42.761954 -37.900476) (xy 42.720071 -37.879744) (xy 42.675103 -37.867018) (xy 42.628566 -37.862728)
			(xy 42.582029 -37.867018) (xy 42.537061 -37.879744) (xy 42.495178 -37.900476) (xy 42.476166 -37.914072)
			(xy 42.454112 -37.930078) (xy 42.406287 -37.956198) (xy 42.355231 -37.975245) (xy 42.301984 -37.986833)
			(xy 42.24763 -37.990725) (xy 42.193276 -37.986842) (xy 42.140027 -37.975262) (xy 42.088968 -37.956223)
			(xy 42.041139 -37.93011) (xy 41.997512 -37.897457) (xy 41.958977 -37.858927) (xy 41.926318 -37.815305)
			(xy 41.900199 -37.767479) (xy 41.881152 -37.716423) (xy 41.869566 -37.663176) (xy 41.865675 -37.608822)
			(xy 36.479974 -37.608822) (xy 36.479988 -37.610034) (xy 36.479486 -37.653484) (xy 36.471468 -37.740013)
			(xy 36.4555 -37.825433) (xy 36.431719 -37.909015) (xy 36.400327 -37.990047) (xy 36.361593 -38.067836)
			(xy 36.315846 -38.14172) (xy 36.263477 -38.211067) (xy 36.204933 -38.275287) (xy 36.140713 -38.333831)
			(xy 36.071366 -38.3862) (xy 35.997482 -38.431947) (xy 35.919693 -38.470681) (xy 35.838661 -38.502073)
			(xy 35.755079 -38.525854) (xy 35.669659 -38.541822) (xy 35.58313 -38.54984) (xy 35.49623 -38.54984)
			(xy 35.409701 -38.541822) (xy 35.324281 -38.525854) (xy 35.240699 -38.502073) (xy 35.159667 -38.470681)
			(xy 35.081878 -38.431947) (xy 35.007994 -38.3862) (xy 34.938647 -38.333831) (xy 34.874427 -38.275287)
			(xy 34.815883 -38.211067) (xy 34.763514 -38.14172) (xy 34.717767 -38.067836) (xy 34.679033 -37.990047)
			(xy 34.647641 -37.909015) (xy 34.62386 -37.825433) (xy 34.607892 -37.740013) (xy 34.599874 -37.653484)
			(xy 31.399486 -37.653484) (xy 31.391468 -37.740013) (xy 31.3755 -37.825433) (xy 31.351719 -37.909015)
			(xy 31.320327 -37.990047) (xy 31.281593 -38.067836) (xy 31.235846 -38.14172) (xy 31.183477 -38.211067)
			(xy 31.124933 -38.275287) (xy 31.060713 -38.333831) (xy 30.991366 -38.3862) (xy 30.917482 -38.431947)
			(xy 30.839693 -38.470681) (xy 30.758661 -38.502073) (xy 30.675079 -38.525854) (xy 30.589659 -38.541822)
			(xy 30.50313 -38.54984) (xy 30.41623 -38.54984) (xy 30.329701 -38.541822) (xy 30.244281 -38.525854)
			(xy 30.160699 -38.502073) (xy 30.079667 -38.470681) (xy 30.001878 -38.431947) (xy 29.927994 -38.3862)
			(xy 29.858647 -38.333831) (xy 29.794427 -38.275287) (xy 29.735883 -38.211067) (xy 29.683514 -38.14172)
			(xy 29.637767 -38.067836) (xy 29.599033 -37.990047) (xy 29.567641 -37.909015) (xy 29.54386 -37.825433)
			(xy 29.527892 -37.740013) (xy 29.519874 -37.653484) (xy 29.24048 -37.653484) (xy 29.24048 -38.661255)
			(xy 47.507896 -38.661255) (xy 47.507896 -38.580145) (xy 47.515846 -38.499426) (xy 47.531669 -38.419875)
			(xy 47.555214 -38.342259) (xy 47.586253 -38.267323) (xy 47.624488 -38.195791) (xy 47.66955 -38.128351)
			(xy 47.721005 -38.065652) (xy 47.778358 -38.008299) (xy 47.841057 -37.956844) (xy 47.908497 -37.911782)
			(xy 47.980029 -37.873547) (xy 48.054965 -37.842508) (xy 48.132581 -37.818963) (xy 48.212132 -37.80314)
			(xy 48.292851 -37.79519) (xy 48.373961 -37.79519) (xy 48.45468 -37.80314) (xy 48.534231 -37.818963)
			(xy 48.611847 -37.842508) (xy 48.686783 -37.873547) (xy 48.758315 -37.911782) (xy 48.825755 -37.956844)
			(xy 48.888454 -38.008299) (xy 48.945807 -38.065652) (xy 48.997262 -38.128351) (xy 49.042324 -38.195791)
			(xy 49.080559 -38.267323) (xy 49.111598 -38.342259) (xy 49.135143 -38.419875) (xy 49.150966 -38.499426)
			(xy 49.158916 -38.580145) (xy 49.159414 -38.6207) (xy 49.158916 -38.661255) (xy 49.150966 -38.741974)
			(xy 49.135143 -38.821525) (xy 49.111598 -38.899141) (xy 49.080559 -38.974077) (xy 49.042324 -39.045609)
			(xy 48.997262 -39.113049) (xy 48.945807 -39.175748) (xy 48.888454 -39.233101) (xy 48.825755 -39.284556)
			(xy 48.758315 -39.329618) (xy 48.686783 -39.367853) (xy 48.611847 -39.398892) (xy 48.534231 -39.422437)
			(xy 48.45468 -39.43826) (xy 48.373961 -39.44621) (xy 48.292851 -39.44621) (xy 48.212132 -39.43826)
			(xy 48.132581 -39.422437) (xy 48.054965 -39.398892) (xy 47.980029 -39.367853) (xy 47.908497 -39.329618)
			(xy 47.841057 -39.284556) (xy 47.778358 -39.233101) (xy 47.721005 -39.175748) (xy 47.66955 -39.113049)
			(xy 47.624488 -39.045609) (xy 47.586253 -38.974077) (xy 47.555214 -38.899141) (xy 47.531669 -38.821525)
			(xy 47.515846 -38.741974) (xy 47.507896 -38.661255) (xy 29.24048 -38.661255) (xy 29.24048 -40.193484)
			(xy 29.519874 -40.193484) (xy 29.519874 -40.106584) (xy 29.527892 -40.020055) (xy 29.54386 -39.934635)
			(xy 29.567641 -39.851053) (xy 29.599033 -39.770021) (xy 29.637767 -39.692232) (xy 29.683514 -39.618348)
			(xy 29.735883 -39.549001) (xy 29.794427 -39.484781) (xy 29.858647 -39.426237) (xy 29.927994 -39.373868)
			(xy 30.001878 -39.328121) (xy 30.079667 -39.289387) (xy 30.160699 -39.257995) (xy 30.244281 -39.234214)
			(xy 30.329701 -39.218246) (xy 30.41623 -39.210228) (xy 30.50313 -39.210228) (xy 30.589659 -39.218246)
			(xy 30.675079 -39.234214) (xy 30.758661 -39.257995) (xy 30.839693 -39.289387) (xy 30.917482 -39.328121)
			(xy 30.991366 -39.373868) (xy 31.060713 -39.426237) (xy 31.124933 -39.484781) (xy 31.183477 -39.549001)
			(xy 31.235846 -39.618348) (xy 31.281593 -39.692232) (xy 31.320327 -39.770021) (xy 31.351719 -39.851053)
			(xy 31.3755 -39.934635) (xy 31.391468 -40.020055) (xy 31.399486 -40.106584) (xy 31.399988 -40.150034)
			(xy 31.399486 -40.193484) (xy 34.599874 -40.193484) (xy 34.599874 -40.106584) (xy 34.607892 -40.020055)
			(xy 34.62386 -39.934635) (xy 34.647641 -39.851053) (xy 34.679033 -39.770021) (xy 34.717767 -39.692232)
			(xy 34.763514 -39.618348) (xy 34.815883 -39.549001) (xy 34.874427 -39.484781) (xy 34.938647 -39.426237)
			(xy 35.007994 -39.373868) (xy 35.081878 -39.328121) (xy 35.159667 -39.289387) (xy 35.240699 -39.257995)
			(xy 35.324281 -39.234214) (xy 35.409701 -39.218246) (xy 35.49623 -39.210228) (xy 35.58313 -39.210228)
			(xy 35.669659 -39.218246) (xy 35.755079 -39.234214) (xy 35.838661 -39.257995) (xy 35.919693 -39.289387)
			(xy 35.997482 -39.328121) (xy 36.071366 -39.373868) (xy 36.140713 -39.426237) (xy 36.204933 -39.484781)
			(xy 36.263477 -39.549001) (xy 36.315846 -39.618348) (xy 36.335379 -39.649895) (xy 41.86571 -39.649895)
			(xy 41.869598 -39.595546) (xy 41.881181 -39.542303) (xy 41.900224 -39.491251) (xy 41.926338 -39.443428)
			(xy 41.958993 -39.399809) (xy 41.997523 -39.361281) (xy 42.041144 -39.328628) (xy 42.088967 -39.302516)
			(xy 42.140021 -39.283476) (xy 42.193264 -39.271896) (xy 42.247614 -39.26801) (xy 42.301963 -39.271899)
			(xy 42.355205 -39.283484) (xy 42.406257 -39.302527) (xy 42.454079 -39.328643) (xy 42.476166 -39.3446)
			(xy 42.495178 -39.358196) (xy 42.537061 -39.378928) (xy 42.582029 -39.391654) (xy 42.628566 -39.395944)
			(xy 42.675103 -39.391654) (xy 42.720071 -39.378928) (xy 42.761954 -39.358196) (xy 42.780966 -39.3446)
			(xy 42.803047 -39.328626) (xy 42.850876 -39.302499) (xy 42.901936 -39.283445) (xy 42.955188 -39.271852)
			(xy 43.009548 -39.267957) (xy 43.063909 -39.271838) (xy 43.117164 -39.283416) (xy 43.168229 -39.302456)
			(xy 43.216065 -39.32857) (xy 43.259697 -39.361226) (xy 43.298236 -39.39976) (xy 43.330899 -39.443387)
			(xy 43.35702 -39.491219) (xy 43.376068 -39.542281) (xy 43.387654 -39.595535) (xy 43.391543 -39.649895)
			(xy 43.752403 -39.649895) (xy 43.756291 -39.595544) (xy 43.767875 -39.5423) (xy 43.786918 -39.491246)
			(xy 43.813034 -39.443422) (xy 43.845689 -39.399802) (xy 43.884221 -39.361273) (xy 43.927843 -39.32862)
			(xy 43.975669 -39.302508) (xy 44.026724 -39.283468) (xy 44.079969 -39.271888) (xy 44.13432 -39.268003)
			(xy 44.188671 -39.271893) (xy 44.241915 -39.283479) (xy 44.292968 -39.302525) (xy 44.340791 -39.328642)
			(xy 44.362878 -39.3446) (xy 44.38189 -39.358196) (xy 44.423773 -39.378928) (xy 44.468741 -39.391654)
			(xy 44.515278 -39.395944) (xy 44.561815 -39.391654) (xy 44.606783 -39.378928) (xy 44.648666 -39.358196)
			(xy 44.667678 -39.3446) (xy 44.689759 -39.328627) (xy 44.737587 -39.302502) (xy 44.788646 -39.28345)
			(xy 44.841896 -39.271858) (xy 44.896255 -39.267964) (xy 44.950614 -39.271846) (xy 45.003867 -39.283424)
			(xy 45.054931 -39.302464) (xy 45.102764 -39.328578) (xy 45.146395 -39.361234) (xy 45.184933 -39.399767)
			(xy 45.217595 -39.443393) (xy 45.243715 -39.491224) (xy 45.262762 -39.542284) (xy 45.274347 -39.595536)
			(xy 45.278236 -39.649895) (xy 45.274349 -39.704254) (xy 45.262764 -39.757506) (xy 45.243719 -39.808568)
			(xy 45.2176 -39.856399) (xy 45.184939 -39.900025) (xy 45.146402 -39.938559) (xy 45.102773 -39.971216)
			(xy 45.05494 -39.997332) (xy 45.003877 -40.016373) (xy 44.950623 -40.027953) (xy 44.896264 -40.031836)
			(xy 44.841906 -40.027943) (xy 44.788655 -40.016353) (xy 44.737595 -39.997302) (xy 44.689767 -39.971178)
			(xy 44.667678 -39.955216) (xy 44.648666 -39.94162) (xy 44.606783 -39.920888) (xy 44.561815 -39.908162)
			(xy 44.515278 -39.903872) (xy 44.468741 -39.908162) (xy 44.423773 -39.920888) (xy 44.38189 -39.94162)
			(xy 44.362878 -39.955216) (xy 44.340783 -39.971163) (xy 44.292959 -39.997279) (xy 44.241906 -40.016324)
			(xy 44.188662 -40.027908) (xy 44.134311 -40.031797) (xy 44.07996 -40.027911) (xy 44.026715 -40.01633)
			(xy 43.97566 -39.997288) (xy 43.927835 -39.971175) (xy 43.884213 -39.938521) (xy 43.845683 -39.899991)
			(xy 43.813028 -39.85637) (xy 43.786914 -39.808545) (xy 43.767872 -39.757491) (xy 43.75629 -39.704246)
			(xy 43.752403 -39.649895) (xy 43.391543 -39.649895) (xy 43.387656 -39.704256) (xy 43.376071 -39.75751)
			(xy 43.357024 -39.808572) (xy 43.330904 -39.856405) (xy 43.298243 -39.900032) (xy 43.259704 -39.938567)
			(xy 43.216073 -39.971225) (xy 43.168238 -39.99734) (xy 43.117173 -40.016381) (xy 43.063918 -40.027961)
			(xy 43.009557 -40.031843) (xy 42.955197 -40.027949) (xy 42.901945 -40.016357) (xy 42.850885 -39.997305)
			(xy 42.803056 -39.971179) (xy 42.780966 -39.955216) (xy 42.761954 -39.94162) (xy 42.720071 -39.920888)
			(xy 42.675103 -39.908162) (xy 42.628566 -39.903872) (xy 42.582029 -39.908162) (xy 42.537061 -39.920888)
			(xy 42.495178 -39.94162) (xy 42.476166 -39.955216) (xy 42.454071 -39.971162) (xy 42.406248 -39.997277)
			(xy 42.355196 -40.016319) (xy 42.301953 -40.027902) (xy 42.247604 -40.03179) (xy 42.193255 -40.027903)
			(xy 42.140011 -40.016321) (xy 42.088959 -39.99728) (xy 42.041135 -39.971166) (xy 41.997515 -39.938513)
			(xy 41.958986 -39.899984) (xy 41.926333 -39.856364) (xy 41.90022 -39.808541) (xy 41.881179 -39.757488)
			(xy 41.869597 -39.704245) (xy 41.86571 -39.649895) (xy 36.335379 -39.649895) (xy 36.361593 -39.692232)
			(xy 36.400327 -39.770021) (xy 36.431719 -39.851053) (xy 36.4555 -39.934635) (xy 36.471468 -40.020055)
			(xy 36.479486 -40.106584) (xy 36.479988 -40.150034) (xy 36.479486 -40.193484) (xy 36.471468 -40.280013)
			(xy 36.4555 -40.365433) (xy 36.431719 -40.449015) (xy 36.400327 -40.530047) (xy 36.361593 -40.607836)
			(xy 36.315846 -40.68172) (xy 36.263477 -40.751067) (xy 36.204933 -40.815287) (xy 36.140713 -40.873831)
			(xy 36.071366 -40.9262) (xy 35.997482 -40.971947) (xy 35.919693 -41.010681) (xy 35.838661 -41.042073)
			(xy 35.755079 -41.065854) (xy 35.669659 -41.081822) (xy 35.58313 -41.08984) (xy 35.49623 -41.08984)
			(xy 35.409701 -41.081822) (xy 35.324281 -41.065854) (xy 35.240699 -41.042073) (xy 35.159667 -41.010681)
			(xy 35.081878 -40.971947) (xy 35.007994 -40.9262) (xy 34.938647 -40.873831) (xy 34.874427 -40.815287)
			(xy 34.815883 -40.751067) (xy 34.763514 -40.68172) (xy 34.717767 -40.607836) (xy 34.679033 -40.530047)
			(xy 34.647641 -40.449015) (xy 34.62386 -40.365433) (xy 34.607892 -40.280013) (xy 34.599874 -40.193484)
			(xy 31.399486 -40.193484) (xy 31.391468 -40.280013) (xy 31.3755 -40.365433) (xy 31.351719 -40.449015)
			(xy 31.320327 -40.530047) (xy 31.281593 -40.607836) (xy 31.235846 -40.68172) (xy 31.183477 -40.751067)
			(xy 31.124933 -40.815287) (xy 31.060713 -40.873831) (xy 30.991366 -40.9262) (xy 30.917482 -40.971947)
			(xy 30.839693 -41.010681) (xy 30.758661 -41.042073) (xy 30.675079 -41.065854) (xy 30.589659 -41.081822)
			(xy 30.50313 -41.08984) (xy 30.41623 -41.08984) (xy 30.329701 -41.081822) (xy 30.244281 -41.065854)
			(xy 30.160699 -41.042073) (xy 30.079667 -41.010681) (xy 30.001878 -40.971947) (xy 29.927994 -40.9262)
			(xy 29.858647 -40.873831) (xy 29.794427 -40.815287) (xy 29.735883 -40.751067) (xy 29.683514 -40.68172)
			(xy 29.637767 -40.607836) (xy 29.599033 -40.530047) (xy 29.567641 -40.449015) (xy 29.54386 -40.365433)
			(xy 29.527892 -40.280013) (xy 29.519874 -40.193484) (xy 29.24048 -40.193484) (xy 29.24048 -41.55968)
			(xy 41.865731 -41.55968) (xy 41.869621 -41.505333) (xy 41.881206 -41.452094) (xy 41.900249 -41.401045)
			(xy 41.926364 -41.353226) (xy 41.959019 -41.309611) (xy 41.997548 -41.271086) (xy 42.041168 -41.238437)
			(xy 42.08899 -41.212329) (xy 42.140041 -41.193292) (xy 42.193282 -41.181714) (xy 42.247629 -41.177831)
			(xy 42.301975 -41.181722) (xy 42.355214 -41.193308) (xy 42.406263 -41.212353) (xy 42.454081 -41.238469)
			(xy 42.476166 -41.254426) (xy 42.495178 -41.268022) (xy 42.537061 -41.288754) (xy 42.582029 -41.30148)
			(xy 42.628566 -41.30577) (xy 42.675103 -41.30148) (xy 42.720071 -41.288754) (xy 42.761954 -41.268022)
			(xy 42.780966 -41.254426) (xy 42.803023 -41.238417) (xy 42.850853 -41.212287) (xy 42.901915 -41.19323)
			(xy 42.955169 -41.181634) (xy 43.009532 -41.177736) (xy 43.063896 -41.181615) (xy 43.117155 -41.193191)
			(xy 43.168224 -41.21223) (xy 43.216063 -41.238344) (xy 43.259698 -41.271) (xy 43.298242 -41.309535)
			(xy 43.330908 -41.353163) (xy 43.357033 -41.400996) (xy 43.376084 -41.45206) (xy 43.387673 -41.505316)
			(xy 43.391564 -41.55968) (xy 43.752424 -41.55968) (xy 43.756314 -41.505332) (xy 43.767899 -41.452091)
			(xy 43.786943 -41.401041) (xy 43.813059 -41.35322) (xy 43.845715 -41.309604) (xy 43.884246 -41.271078)
			(xy 43.927868 -41.238429) (xy 43.975692 -41.21232) (xy 44.026745 -41.193283) (xy 44.079988 -41.181706)
			(xy 44.134336 -41.177824) (xy 44.188684 -41.181716) (xy 44.241924 -41.193303) (xy 44.292974 -41.21235)
			(xy 44.340793 -41.238468) (xy 44.362878 -41.254426) (xy 44.38189 -41.268022) (xy 44.423773 -41.288754)
			(xy 44.468741 -41.30148) (xy 44.515278 -41.30577) (xy 44.561815 -41.30148) (xy 44.606783 -41.288754)
			(xy 44.648666 -41.268022) (xy 44.667678 -41.254426) (xy 44.689735 -41.238418) (xy 44.737564 -41.21229)
			(xy 44.788625 -41.193234) (xy 44.841878 -41.18164) (xy 44.896239 -41.177743) (xy 44.950601 -41.181623)
			(xy 45.003858 -41.1932) (xy 45.054925 -41.212239) (xy 45.102763 -41.238352) (xy 45.146396 -41.271008)
			(xy 45.184938 -41.309542) (xy 45.217604 -41.353169) (xy 45.243727 -41.401001) (xy 45.262777 -41.452064)
			(xy 45.274366 -41.505318) (xy 45.278257 -41.55968) (xy 45.274372 -41.614042) (xy 45.262789 -41.667297)
			(xy 45.243744 -41.718362) (xy 45.217626 -41.766197) (xy 45.184965 -41.809827) (xy 45.146427 -41.848365)
			(xy 45.102797 -41.881026) (xy 45.054962 -41.907144) (xy 45.003897 -41.926189) (xy 44.950642 -41.937771)
			(xy 44.89628 -41.941657) (xy 44.841918 -41.937766) (xy 44.788664 -41.926177) (xy 44.737601 -41.907127)
			(xy 44.689769 -41.881004) (xy 44.667678 -41.865042) (xy 44.648666 -41.851446) (xy 44.606783 -41.830714)
			(xy 44.561815 -41.817988) (xy 44.515278 -41.813698) (xy 44.468741 -41.817988) (xy 44.423773 -41.830714)
			(xy 44.38189 -41.851446) (xy 44.362878 -41.865042) (xy 44.340758 -41.880954) (xy 44.292936 -41.907067)
			(xy 44.241885 -41.926108) (xy 44.188643 -41.93769) (xy 44.134295 -41.941576) (xy 44.079947 -41.937688)
			(xy 44.026706 -41.926105) (xy 43.975655 -41.907063) (xy 43.927833 -41.880949) (xy 43.884215 -41.848295)
			(xy 43.845689 -41.809766) (xy 43.813037 -41.766145) (xy 43.786927 -41.718322) (xy 43.767888 -41.66727)
			(xy 43.756308 -41.614028) (xy 43.752424 -41.55968) (xy 43.391564 -41.55968) (xy 43.387679 -41.614043)
			(xy 43.376095 -41.6673) (xy 43.35705 -41.718367) (xy 43.33093 -41.766203) (xy 43.298268 -41.809834)
			(xy 43.259729 -41.848373) (xy 43.216097 -41.881034) (xy 43.168261 -41.907153) (xy 43.117194 -41.926197)
			(xy 43.063937 -41.937779) (xy 43.009573 -41.941664) (xy 42.95521 -41.937772) (xy 42.901954 -41.926182)
			(xy 42.85089 -41.90713) (xy 42.803057 -41.881005) (xy 42.780966 -41.865042) (xy 42.761954 -41.851446)
			(xy 42.720071 -41.830714) (xy 42.675103 -41.817988) (xy 42.628566 -41.813698) (xy 42.582029 -41.817988)
			(xy 42.537061 -41.830714) (xy 42.495178 -41.851446) (xy 42.476166 -41.865042) (xy 42.454047 -41.880953)
			(xy 42.406226 -41.907064) (xy 42.355175 -41.926103) (xy 42.301935 -41.937684) (xy 42.247588 -41.941569)
			(xy 42.193242 -41.93768) (xy 42.140002 -41.926097) (xy 42.088953 -41.907054) (xy 42.041134 -41.880941)
			(xy 41.997517 -41.848287) (xy 41.958992 -41.809759) (xy 41.926342 -41.766139) (xy 41.900232 -41.718318)
			(xy 41.881194 -41.667267) (xy 41.869615 -41.614026) (xy 41.865731 -41.55968) (xy 29.24048 -41.55968)
			(xy 29.24048 -42.733484) (xy 29.519874 -42.733484) (xy 29.519874 -42.646584) (xy 29.527892 -42.560055)
			(xy 29.54386 -42.474635) (xy 29.567641 -42.391053) (xy 29.599033 -42.310021) (xy 29.637767 -42.232232)
			(xy 29.683514 -42.158348) (xy 29.735883 -42.089001) (xy 29.794427 -42.024781) (xy 29.858647 -41.966237)
			(xy 29.927994 -41.913868) (xy 30.001878 -41.868121) (xy 30.079667 -41.829387) (xy 30.160699 -41.797995)
			(xy 30.244281 -41.774214) (xy 30.329701 -41.758246) (xy 30.41623 -41.750228) (xy 30.50313 -41.750228)
			(xy 30.589659 -41.758246) (xy 30.675079 -41.774214) (xy 30.758661 -41.797995) (xy 30.839693 -41.829387)
			(xy 30.917482 -41.868121) (xy 30.991366 -41.913868) (xy 31.060713 -41.966237) (xy 31.124933 -42.024781)
			(xy 31.183477 -42.089001) (xy 31.235846 -42.158348) (xy 31.281593 -42.232232) (xy 31.320327 -42.310021)
			(xy 31.351719 -42.391053) (xy 31.3755 -42.474635) (xy 31.391468 -42.560055) (xy 31.399486 -42.646584)
			(xy 31.399988 -42.690034) (xy 31.399486 -42.733484) (xy 34.599874 -42.733484) (xy 34.599874 -42.646584)
			(xy 34.607892 -42.560055) (xy 34.62386 -42.474635) (xy 34.647641 -42.391053) (xy 34.679033 -42.310021)
			(xy 34.717767 -42.232232) (xy 34.763514 -42.158348) (xy 34.815883 -42.089001) (xy 34.874427 -42.024781)
			(xy 34.938647 -41.966237) (xy 35.007994 -41.913868) (xy 35.081878 -41.868121) (xy 35.159667 -41.829387)
			(xy 35.240699 -41.797995) (xy 35.324281 -41.774214) (xy 35.409701 -41.758246) (xy 35.49623 -41.750228)
			(xy 35.58313 -41.750228) (xy 35.669659 -41.758246) (xy 35.755079 -41.774214) (xy 35.838661 -41.797995)
			(xy 35.919693 -41.829387) (xy 35.997482 -41.868121) (xy 36.071366 -41.913868) (xy 36.140713 -41.966237)
			(xy 36.204933 -42.024781) (xy 36.263477 -42.089001) (xy 36.315846 -42.158348) (xy 36.361593 -42.232232)
			(xy 36.400327 -42.310021) (xy 36.431719 -42.391053) (xy 36.4555 -42.474635) (xy 36.471468 -42.560055)
			(xy 36.479486 -42.646584) (xy 36.479988 -42.690034) (xy 36.479486 -42.733484) (xy 36.471468 -42.820013)
			(xy 36.4555 -42.905433) (xy 36.431719 -42.989015) (xy 36.400327 -43.070047) (xy 36.361593 -43.147836)
			(xy 36.315846 -43.22172) (xy 36.263477 -43.291067) (xy 36.204933 -43.355287) (xy 36.140713 -43.413831)
			(xy 36.071366 -43.4662) (xy 35.997482 -43.511947) (xy 35.919693 -43.550681) (xy 35.838661 -43.582073)
			(xy 35.755079 -43.605854) (xy 35.669659 -43.621822) (xy 35.58313 -43.62984) (xy 35.49623 -43.62984)
			(xy 35.409701 -43.621822) (xy 35.324281 -43.605854) (xy 35.240699 -43.582073) (xy 35.159667 -43.550681)
			(xy 35.081878 -43.511947) (xy 35.007994 -43.4662) (xy 34.938647 -43.413831) (xy 34.874427 -43.355287)
			(xy 34.815883 -43.291067) (xy 34.763514 -43.22172) (xy 34.717767 -43.147836) (xy 34.679033 -43.070047)
			(xy 34.647641 -42.989015) (xy 34.62386 -42.905433) (xy 34.607892 -42.820013) (xy 34.599874 -42.733484)
			(xy 31.399486 -42.733484) (xy 31.391468 -42.820013) (xy 31.3755 -42.905433) (xy 31.351719 -42.989015)
			(xy 31.320327 -43.070047) (xy 31.281593 -43.147836) (xy 31.235846 -43.22172) (xy 31.183477 -43.291067)
			(xy 31.124933 -43.355287) (xy 31.060713 -43.413831) (xy 30.991366 -43.4662) (xy 30.917482 -43.511947)
			(xy 30.839693 -43.550681) (xy 30.758661 -43.582073) (xy 30.675079 -43.605854) (xy 30.589659 -43.621822)
			(xy 30.50313 -43.62984) (xy 30.41623 -43.62984) (xy 30.329701 -43.621822) (xy 30.244281 -43.605854)
			(xy 30.160699 -43.582073) (xy 30.079667 -43.550681) (xy 30.001878 -43.511947) (xy 29.927994 -43.4662)
			(xy 29.858647 -43.413831) (xy 29.794427 -43.355287) (xy 29.735883 -43.291067) (xy 29.683514 -43.22172)
			(xy 29.637767 -43.147836) (xy 29.599033 -43.070047) (xy 29.567641 -42.989015) (xy 29.54386 -42.905433)
			(xy 29.527892 -42.820013) (xy 29.519874 -42.733484) (xy 29.24048 -42.733484) (xy 29.24048 -45.273484)
			(xy 29.519874 -45.273484) (xy 29.519874 -45.186584) (xy 29.527892 -45.100055) (xy 29.54386 -45.014635)
			(xy 29.567641 -44.931053) (xy 29.599033 -44.850021) (xy 29.637767 -44.772232) (xy 29.683514 -44.698348)
			(xy 29.735883 -44.629001) (xy 29.794427 -44.564781) (xy 29.858647 -44.506237) (xy 29.927994 -44.453868)
			(xy 30.001878 -44.408121) (xy 30.079667 -44.369387) (xy 30.160699 -44.337995) (xy 30.244281 -44.314214)
			(xy 30.329701 -44.298246) (xy 30.41623 -44.290228) (xy 30.50313 -44.290228) (xy 30.589659 -44.298246)
			(xy 30.675079 -44.314214) (xy 30.758661 -44.337995) (xy 30.839693 -44.369387) (xy 30.917482 -44.408121)
			(xy 30.991366 -44.453868) (xy 31.060713 -44.506237) (xy 31.124933 -44.564781) (xy 31.183477 -44.629001)
			(xy 31.235846 -44.698348) (xy 31.281593 -44.772232) (xy 31.320327 -44.850021) (xy 31.351719 -44.931053)
			(xy 31.3755 -45.014635) (xy 31.391468 -45.100055) (xy 31.399486 -45.186584) (xy 31.399988 -45.230034)
			(xy 31.399486 -45.273484) (xy 34.599874 -45.273484) (xy 34.599874 -45.186584) (xy 34.607892 -45.100055)
			(xy 34.62386 -45.014635) (xy 34.647641 -44.931053) (xy 34.679033 -44.850021) (xy 34.717767 -44.772232)
			(xy 34.763514 -44.698348) (xy 34.815883 -44.629001) (xy 34.874427 -44.564781) (xy 34.938647 -44.506237)
			(xy 35.007994 -44.453868) (xy 35.081878 -44.408121) (xy 35.159667 -44.369387) (xy 35.240699 -44.337995)
			(xy 35.324281 -44.314214) (xy 35.409701 -44.298246) (xy 35.49623 -44.290228) (xy 35.58313 -44.290228)
			(xy 35.669659 -44.298246) (xy 35.755079 -44.314214) (xy 35.838661 -44.337995) (xy 35.919693 -44.369387)
			(xy 35.997482 -44.408121) (xy 36.071366 -44.453868) (xy 36.140713 -44.506237) (xy 36.204933 -44.564781)
			(xy 36.263477 -44.629001) (xy 36.315846 -44.698348) (xy 36.361593 -44.772232) (xy 36.400327 -44.850021)
			(xy 36.431719 -44.931053) (xy 36.4555 -45.014635) (xy 36.471468 -45.100055) (xy 36.479486 -45.186584)
			(xy 36.479988 -45.230034) (xy 36.479486 -45.273484) (xy 36.471468 -45.360013) (xy 36.4555 -45.445433)
			(xy 36.431719 -45.529015) (xy 36.400327 -45.610047) (xy 36.361593 -45.687836) (xy 36.315846 -45.76172)
			(xy 36.263477 -45.831067) (xy 36.204933 -45.895287) (xy 36.140713 -45.953831) (xy 36.071366 -46.0062)
			(xy 35.997482 -46.051947) (xy 35.919693 -46.090681) (xy 35.838661 -46.122073) (xy 35.755079 -46.145854)
			(xy 35.669659 -46.161822) (xy 35.58313 -46.16984) (xy 35.49623 -46.16984) (xy 35.409701 -46.161822)
			(xy 35.324281 -46.145854) (xy 35.240699 -46.122073) (xy 35.159667 -46.090681) (xy 35.081878 -46.051947)
			(xy 35.007994 -46.0062) (xy 34.938647 -45.953831) (xy 34.874427 -45.895287) (xy 34.815883 -45.831067)
			(xy 34.763514 -45.76172) (xy 34.717767 -45.687836) (xy 34.679033 -45.610047) (xy 34.647641 -45.529015)
			(xy 34.62386 -45.445433) (xy 34.607892 -45.360013) (xy 34.599874 -45.273484) (xy 31.399486 -45.273484)
			(xy 31.391468 -45.360013) (xy 31.3755 -45.445433) (xy 31.351719 -45.529015) (xy 31.320327 -45.610047)
			(xy 31.281593 -45.687836) (xy 31.235846 -45.76172) (xy 31.183477 -45.831067) (xy 31.124933 -45.895287)
			(xy 31.060713 -45.953831) (xy 30.991366 -46.0062) (xy 30.917482 -46.051947) (xy 30.839693 -46.090681)
			(xy 30.758661 -46.122073) (xy 30.675079 -46.145854) (xy 30.589659 -46.161822) (xy 30.50313 -46.16984)
			(xy 30.41623 -46.16984) (xy 30.329701 -46.161822) (xy 30.244281 -46.145854) (xy 30.160699 -46.122073)
			(xy 30.079667 -46.090681) (xy 30.001878 -46.051947) (xy 29.927994 -46.0062) (xy 29.858647 -45.953831)
			(xy 29.794427 -45.895287) (xy 29.735883 -45.831067) (xy 29.683514 -45.76172) (xy 29.637767 -45.687836)
			(xy 29.599033 -45.610047) (xy 29.567641 -45.529015) (xy 29.54386 -45.445433) (xy 29.527892 -45.360013)
			(xy 29.519874 -45.273484) (xy 29.24048 -45.273484) (xy 29.24048 -47.813484) (xy 29.519874 -47.813484)
			(xy 29.519874 -47.726584) (xy 29.527892 -47.640055) (xy 29.54386 -47.554635) (xy 29.567641 -47.471053)
			(xy 29.599033 -47.390021) (xy 29.637767 -47.312232) (xy 29.683514 -47.238348) (xy 29.735883 -47.169001)
			(xy 29.794427 -47.104781) (xy 29.858647 -47.046237) (xy 29.927994 -46.993868) (xy 30.001878 -46.948121)
			(xy 30.079667 -46.909387) (xy 30.160699 -46.877995) (xy 30.244281 -46.854214) (xy 30.329701 -46.838246)
			(xy 30.41623 -46.830228) (xy 30.50313 -46.830228) (xy 30.589659 -46.838246) (xy 30.675079 -46.854214)
			(xy 30.758661 -46.877995) (xy 30.839693 -46.909387) (xy 30.917482 -46.948121) (xy 30.991366 -46.993868)
			(xy 31.060713 -47.046237) (xy 31.124933 -47.104781) (xy 31.183477 -47.169001) (xy 31.235846 -47.238348)
			(xy 31.281593 -47.312232) (xy 31.320327 -47.390021) (xy 31.351719 -47.471053) (xy 31.3755 -47.554635)
			(xy 31.391468 -47.640055) (xy 31.399486 -47.726584) (xy 31.399988 -47.770034) (xy 31.399486 -47.813484)
			(xy 34.599874 -47.813484) (xy 34.599874 -47.726584) (xy 34.607892 -47.640055) (xy 34.62386 -47.554635)
			(xy 34.647641 -47.471053) (xy 34.679033 -47.390021) (xy 34.717767 -47.312232) (xy 34.763514 -47.238348)
			(xy 34.815883 -47.169001) (xy 34.874427 -47.104781) (xy 34.938647 -47.046237) (xy 35.007994 -46.993868)
			(xy 35.081878 -46.948121) (xy 35.159667 -46.909387) (xy 35.240699 -46.877995) (xy 35.324281 -46.854214)
			(xy 35.409701 -46.838246) (xy 35.49623 -46.830228) (xy 35.58313 -46.830228) (xy 35.669659 -46.838246)
			(xy 35.755079 -46.854214) (xy 35.838661 -46.877995) (xy 35.919693 -46.909387) (xy 35.997482 -46.948121)
			(xy 36.071366 -46.993868) (xy 36.140713 -47.046237) (xy 36.204933 -47.104781) (xy 36.263477 -47.169001)
			(xy 36.315846 -47.238348) (xy 36.361593 -47.312232) (xy 36.400327 -47.390021) (xy 36.431719 -47.471053)
			(xy 36.4555 -47.554635) (xy 36.471468 -47.640055) (xy 36.479486 -47.726584) (xy 36.479988 -47.770034)
			(xy 36.479486 -47.813484) (xy 36.471468 -47.900013) (xy 36.4555 -47.985433) (xy 36.431719 -48.069015)
			(xy 36.400327 -48.150047) (xy 36.361593 -48.227836) (xy 36.315846 -48.30172) (xy 36.263477 -48.371067)
			(xy 36.204933 -48.435287) (xy 36.140713 -48.493831) (xy 36.071366 -48.5462) (xy 35.997482 -48.591947)
			(xy 35.919693 -48.630681) (xy 35.838661 -48.662073) (xy 35.755079 -48.685854) (xy 35.669659 -48.701822)
			(xy 35.58313 -48.70984) (xy 35.49623 -48.70984) (xy 35.409701 -48.701822) (xy 35.324281 -48.685854)
			(xy 35.240699 -48.662073) (xy 35.159667 -48.630681) (xy 35.081878 -48.591947) (xy 35.007994 -48.5462)
			(xy 34.938647 -48.493831) (xy 34.874427 -48.435287) (xy 34.815883 -48.371067) (xy 34.763514 -48.30172)
			(xy 34.717767 -48.227836) (xy 34.679033 -48.150047) (xy 34.647641 -48.069015) (xy 34.62386 -47.985433)
			(xy 34.607892 -47.900013) (xy 34.599874 -47.813484) (xy 31.399486 -47.813484) (xy 31.391468 -47.900013)
			(xy 31.3755 -47.985433) (xy 31.351719 -48.069015) (xy 31.320327 -48.150047) (xy 31.281593 -48.227836)
			(xy 31.235846 -48.30172) (xy 31.183477 -48.371067) (xy 31.124933 -48.435287) (xy 31.060713 -48.493831)
			(xy 30.991366 -48.5462) (xy 30.917482 -48.591947) (xy 30.839693 -48.630681) (xy 30.758661 -48.662073)
			(xy 30.675079 -48.685854) (xy 30.589659 -48.701822) (xy 30.50313 -48.70984) (xy 30.41623 -48.70984)
			(xy 30.329701 -48.701822) (xy 30.244281 -48.685854) (xy 30.160699 -48.662073) (xy 30.079667 -48.630681)
			(xy 30.001878 -48.591947) (xy 29.927994 -48.5462) (xy 29.858647 -48.493831) (xy 29.794427 -48.435287)
			(xy 29.735883 -48.371067) (xy 29.683514 -48.30172) (xy 29.637767 -48.227836) (xy 29.599033 -48.150047)
			(xy 29.567641 -48.069015) (xy 29.54386 -47.985433) (xy 29.527892 -47.900013) (xy 29.519874 -47.813484)
			(xy 29.24048 -47.813484) (xy 29.24048 -50.353484) (xy 29.519874 -50.353484) (xy 29.519874 -50.266584)
			(xy 29.527892 -50.180055) (xy 29.54386 -50.094635) (xy 29.567641 -50.011053) (xy 29.599033 -49.930021)
			(xy 29.637767 -49.852232) (xy 29.683514 -49.778348) (xy 29.735883 -49.709001) (xy 29.794427 -49.644781)
			(xy 29.858647 -49.586237) (xy 29.927994 -49.533868) (xy 30.001878 -49.488121) (xy 30.079667 -49.449387)
			(xy 30.160699 -49.417995) (xy 30.244281 -49.394214) (xy 30.329701 -49.378246) (xy 30.41623 -49.370228)
			(xy 30.50313 -49.370228) (xy 30.589659 -49.378246) (xy 30.675079 -49.394214) (xy 30.758661 -49.417995)
			(xy 30.839693 -49.449387) (xy 30.917482 -49.488121) (xy 30.991366 -49.533868) (xy 31.060713 -49.586237)
			(xy 31.124933 -49.644781) (xy 31.183477 -49.709001) (xy 31.235846 -49.778348) (xy 31.281593 -49.852232)
			(xy 31.320327 -49.930021) (xy 31.351719 -50.011053) (xy 31.3755 -50.094635) (xy 31.391468 -50.180055)
			(xy 31.399486 -50.266584) (xy 31.399988 -50.310034) (xy 31.399486 -50.353484) (xy 34.599874 -50.353484)
			(xy 34.599874 -50.266584) (xy 34.607892 -50.180055) (xy 34.62386 -50.094635) (xy 34.647641 -50.011053)
			(xy 34.679033 -49.930021) (xy 34.717767 -49.852232) (xy 34.763514 -49.778348) (xy 34.815883 -49.709001)
			(xy 34.874427 -49.644781) (xy 34.938647 -49.586237) (xy 35.007994 -49.533868) (xy 35.081878 -49.488121)
			(xy 35.159667 -49.449387) (xy 35.240699 -49.417995) (xy 35.324281 -49.394214) (xy 35.409701 -49.378246)
			(xy 35.49623 -49.370228) (xy 35.58313 -49.370228) (xy 35.669659 -49.378246) (xy 35.755079 -49.394214)
			(xy 35.838661 -49.417995) (xy 35.919693 -49.449387) (xy 35.997482 -49.488121) (xy 36.071366 -49.533868)
			(xy 36.140713 -49.586237) (xy 36.204933 -49.644781) (xy 36.263477 -49.709001) (xy 36.315846 -49.778348)
			(xy 36.361593 -49.852232) (xy 36.400327 -49.930021) (xy 36.431719 -50.011053) (xy 36.4555 -50.094635)
			(xy 36.471468 -50.180055) (xy 36.479486 -50.266584) (xy 36.479988 -50.310034) (xy 36.479486 -50.353484)
			(xy 36.471468 -50.440013) (xy 36.4555 -50.525433) (xy 36.431719 -50.609015) (xy 36.400327 -50.690047)
			(xy 36.361593 -50.767836) (xy 36.315846 -50.84172) (xy 36.263477 -50.911067) (xy 36.204933 -50.975287)
			(xy 36.140713 -51.033831) (xy 36.071366 -51.0862) (xy 35.997482 -51.131947) (xy 35.919693 -51.170681)
			(xy 35.838661 -51.202073) (xy 35.755079 -51.225854) (xy 35.669659 -51.241822) (xy 35.58313 -51.24984)
			(xy 35.49623 -51.24984) (xy 35.409701 -51.241822) (xy 35.324281 -51.225854) (xy 35.240699 -51.202073)
			(xy 35.159667 -51.170681) (xy 35.081878 -51.131947) (xy 35.007994 -51.0862) (xy 34.938647 -51.033831)
			(xy 34.874427 -50.975287) (xy 34.815883 -50.911067) (xy 34.763514 -50.84172) (xy 34.717767 -50.767836)
			(xy 34.679033 -50.690047) (xy 34.647641 -50.609015) (xy 34.62386 -50.525433) (xy 34.607892 -50.440013)
			(xy 34.599874 -50.353484) (xy 31.399486 -50.353484) (xy 31.391468 -50.440013) (xy 31.3755 -50.525433)
			(xy 31.351719 -50.609015) (xy 31.320327 -50.690047) (xy 31.281593 -50.767836) (xy 31.235846 -50.84172)
			(xy 31.183477 -50.911067) (xy 31.124933 -50.975287) (xy 31.060713 -51.033831) (xy 30.991366 -51.0862)
			(xy 30.917482 -51.131947) (xy 30.839693 -51.170681) (xy 30.758661 -51.202073) (xy 30.675079 -51.225854)
			(xy 30.589659 -51.241822) (xy 30.50313 -51.24984) (xy 30.41623 -51.24984) (xy 30.329701 -51.241822)
			(xy 30.244281 -51.225854) (xy 30.160699 -51.202073) (xy 30.079667 -51.170681) (xy 30.001878 -51.131947)
			(xy 29.927994 -51.0862) (xy 29.858647 -51.033831) (xy 29.794427 -50.975287) (xy 29.735883 -50.911067)
			(xy 29.683514 -50.84172) (xy 29.637767 -50.767836) (xy 29.599033 -50.690047) (xy 29.567641 -50.609015)
			(xy 29.54386 -50.525433) (xy 29.527892 -50.440013) (xy 29.519874 -50.353484) (xy 29.24048 -50.353484)
			(xy 29.24048 -51.36007) (xy 39.818564 -51.36007) (xy 39.819054 -51.302663) (xy 39.826889 -51.188117)
			(xy 39.842523 -51.074372) (xy 39.865882 -50.96196) (xy 39.896859 -50.851403) (xy 39.935308 -50.743218)
			(xy 39.98105 -50.63791) (xy 40.033872 -50.535968) (xy 40.093527 -50.437869) (xy 40.159738 -50.344069)
			(xy 40.232196 -50.255007) (xy 40.310562 -50.171096) (xy 40.394473 -50.09273) (xy 40.483535 -50.020272)
			(xy 40.577335 -49.954061) (xy 40.675434 -49.894406) (xy 40.777376 -49.841584) (xy 40.882684 -49.795842)
			(xy 40.990869 -49.757393) (xy 41.101426 -49.726416) (xy 41.213838 -49.703057) (xy 41.327583 -49.687423)
			(xy 41.442129 -49.679588) (xy 41.556943 -49.679588) (xy 41.671489 -49.687423) (xy 41.785234 -49.703057)
			(xy 41.897646 -49.726416) (xy 42.008203 -49.757393) (xy 42.116388 -49.795842) (xy 42.221696 -49.841584)
			(xy 42.323638 -49.894406) (xy 42.421737 -49.954061) (xy 42.50107 -50.01006) (xy 43.327577 -50.01006)
			(xy 43.331612 -49.934356) (xy 43.343671 -49.859511) (xy 43.363617 -49.78637) (xy 43.391224 -49.715765)
			(xy 43.42618 -49.648494) (xy 43.468088 -49.585319) (xy 43.516474 -49.526957) (xy 43.57079 -49.474069)
			(xy 43.630419 -49.427254) (xy 43.694687 -49.387042) (xy 43.762864 -49.35389) (xy 43.83418 -49.328172)
			(xy 43.907825 -49.31018) (xy 43.982965 -49.300118) (xy 44.058749 -49.298099) (xy 44.134319 -49.304148)
			(xy 44.208817 -49.318195) (xy 44.2814 -49.340081) (xy 44.351246 -49.369558) (xy 44.417563 -49.406293)
			(xy 44.479599 -49.449868) (xy 44.536652 -49.49979) (xy 44.588076 -49.555494) (xy 44.633287 -49.616349)
			(xy 44.671774 -49.681664) (xy 44.7031 -49.7507) (xy 44.72691 -49.822675) (xy 44.742935 -49.896773)
			(xy 44.750994 -49.972154) (xy 44.751498 -50.01006) (xy 45.867577 -50.01006) (xy 45.871612 -49.934356)
			(xy 45.883671 -49.859511) (xy 45.903617 -49.78637) (xy 45.931224 -49.715765) (xy 45.96618 -49.648494)
			(xy 46.008088 -49.585319) (xy 46.056474 -49.526957) (xy 46.11079 -49.474069) (xy 46.170419 -49.427254)
			(xy 46.234687 -49.387042) (xy 46.302864 -49.35389) (xy 46.37418 -49.328172) (xy 46.447825 -49.31018)
			(xy 46.522965 -49.300118) (xy 46.598749 -49.298099) (xy 46.674319 -49.304148) (xy 46.748817 -49.318195)
			(xy 46.8214 -49.340081) (xy 46.891246 -49.369558) (xy 46.957563 -49.406293) (xy 47.019599 -49.449868)
			(xy 47.076652 -49.49979) (xy 47.128076 -49.555494) (xy 47.173287 -49.616349) (xy 47.211774 -49.681664)
			(xy 47.2431 -49.7507) (xy 47.26691 -49.822675) (xy 47.282935 -49.896773) (xy 47.290994 -49.972154)
			(xy 47.291498 -50.01006) (xy 48.407577 -50.01006) (xy 48.411612 -49.934356) (xy 48.423671 -49.859511)
			(xy 48.443617 -49.78637) (xy 48.471224 -49.715765) (xy 48.50618 -49.648494) (xy 48.548088 -49.585319)
			(xy 48.596474 -49.526957) (xy 48.65079 -49.474069) (xy 48.710419 -49.427254) (xy 48.774687 -49.387042)
			(xy 48.842864 -49.35389) (xy 48.91418 -49.328172) (xy 48.987825 -49.31018) (xy 49.062965 -49.300118)
			(xy 49.138749 -49.298099) (xy 49.214319 -49.304148) (xy 49.288817 -49.318195) (xy 49.3614 -49.340081)
			(xy 49.431246 -49.369558) (xy 49.497563 -49.406293) (xy 49.559599 -49.449868) (xy 49.616652 -49.49979)
			(xy 49.668076 -49.555494) (xy 49.713287 -49.616349) (xy 49.751774 -49.681664) (xy 49.7831 -49.7507)
			(xy 49.80691 -49.822675) (xy 49.822935 -49.896773) (xy 49.830994 -49.972154) (xy 49.831498 -50.01006)
			(xy 50.947577 -50.01006) (xy 50.951612 -49.934356) (xy 50.963671 -49.859511) (xy 50.983617 -49.78637)
			(xy 51.011224 -49.715765) (xy 51.04618 -49.648494) (xy 51.088088 -49.585319) (xy 51.136474 -49.526957)
			(xy 51.19079 -49.474069) (xy 51.250419 -49.427254) (xy 51.314687 -49.387042) (xy 51.382864 -49.35389)
			(xy 51.45418 -49.328172) (xy 51.527825 -49.31018) (xy 51.602965 -49.300118) (xy 51.678749 -49.298099)
			(xy 51.754319 -49.304148) (xy 51.828817 -49.318195) (xy 51.9014 -49.340081) (xy 51.971246 -49.369558)
			(xy 52.037563 -49.406293) (xy 52.099599 -49.449868) (xy 52.156652 -49.49979) (xy 52.208076 -49.555494)
			(xy 52.253287 -49.616349) (xy 52.291774 -49.681664) (xy 52.3231 -49.7507) (xy 52.34691 -49.822675)
			(xy 52.362935 -49.896773) (xy 52.370994 -49.972154) (xy 52.371498 -50.01006) (xy 53.487577 -50.01006)
			(xy 53.491612 -49.934356) (xy 53.503671 -49.859511) (xy 53.523617 -49.78637) (xy 53.551224 -49.715765)
			(xy 53.58618 -49.648494) (xy 53.628088 -49.585319) (xy 53.676474 -49.526957) (xy 53.73079 -49.474069)
			(xy 53.790419 -49.427254) (xy 53.854687 -49.387042) (xy 53.922864 -49.35389) (xy 53.99418 -49.328172)
			(xy 54.067825 -49.31018) (xy 54.142965 -49.300118) (xy 54.218749 -49.298099) (xy 54.294319 -49.304148)
			(xy 54.368817 -49.318195) (xy 54.4414 -49.340081) (xy 54.511246 -49.369558) (xy 54.577563 -49.406293)
			(xy 54.639599 -49.449868) (xy 54.696652 -49.49979) (xy 54.748076 -49.555494) (xy 54.793287 -49.616349)
			(xy 54.831774 -49.681664) (xy 54.8631 -49.7507) (xy 54.88691 -49.822675) (xy 54.902935 -49.896773)
			(xy 54.910994 -49.972154) (xy 54.911498 -50.01006) (xy 56.027577 -50.01006) (xy 56.031612 -49.934356)
			(xy 56.043671 -49.859511) (xy 56.063617 -49.78637) (xy 56.091224 -49.715765) (xy 56.12618 -49.648494)
			(xy 56.168088 -49.585319) (xy 56.216474 -49.526957) (xy 56.27079 -49.474069) (xy 56.330419 -49.427254)
			(xy 56.394687 -49.387042) (xy 56.462864 -49.35389) (xy 56.53418 -49.328172) (xy 56.607825 -49.31018)
			(xy 56.682965 -49.300118) (xy 56.758749 -49.298099) (xy 56.834319 -49.304148) (xy 56.908817 -49.318195)
			(xy 56.9814 -49.340081) (xy 57.051246 -49.369558) (xy 57.117563 -49.406293) (xy 57.179599 -49.449868)
			(xy 57.236652 -49.49979) (xy 57.288076 -49.555494) (xy 57.333287 -49.616349) (xy 57.371774 -49.681664)
			(xy 57.4031 -49.7507) (xy 57.42691 -49.822675) (xy 57.442935 -49.896773) (xy 57.450994 -49.972154)
			(xy 57.451498 -50.01006) (xy 58.567577 -50.01006) (xy 58.571612 -49.934356) (xy 58.583671 -49.859511)
			(xy 58.603617 -49.78637) (xy 58.631224 -49.715765) (xy 58.66618 -49.648494) (xy 58.708088 -49.585319)
			(xy 58.756474 -49.526957) (xy 58.81079 -49.474069) (xy 58.870419 -49.427254) (xy 58.934687 -49.387042)
			(xy 59.002864 -49.35389) (xy 59.07418 -49.328172) (xy 59.147825 -49.31018) (xy 59.222965 -49.300118)
			(xy 59.298749 -49.298099) (xy 59.374319 -49.304148) (xy 59.448817 -49.318195) (xy 59.5214 -49.340081)
			(xy 59.591246 -49.369558) (xy 59.657563 -49.406293) (xy 59.719599 -49.449868) (xy 59.776652 -49.49979)
			(xy 59.828076 -49.555494) (xy 59.873287 -49.616349) (xy 59.911774 -49.681664) (xy 59.9431 -49.7507)
			(xy 59.96691 -49.822675) (xy 59.982935 -49.896773) (xy 59.990994 -49.972154) (xy 59.991498 -50.01006)
			(xy 61.107577 -50.01006) (xy 61.111612 -49.934356) (xy 61.123671 -49.859511) (xy 61.143617 -49.78637)
			(xy 61.171224 -49.715765) (xy 61.20618 -49.648494) (xy 61.248088 -49.585319) (xy 61.296474 -49.526957)
			(xy 61.35079 -49.474069) (xy 61.410419 -49.427254) (xy 61.474687 -49.387042) (xy 61.542864 -49.35389)
			(xy 61.61418 -49.328172) (xy 61.687825 -49.31018) (xy 61.762965 -49.300118) (xy 61.838749 -49.298099)
			(xy 61.914319 -49.304148) (xy 61.988817 -49.318195) (xy 62.0614 -49.340081) (xy 62.131246 -49.369558)
			(xy 62.197563 -49.406293) (xy 62.259599 -49.449868) (xy 62.265544 -49.45507) (xy 86.197697 -49.45507)
			(xy 86.201732 -49.379366) (xy 86.213791 -49.304521) (xy 86.233737 -49.23138) (xy 86.261344 -49.160775)
			(xy 86.2963 -49.093504) (xy 86.338208 -49.030329) (xy 86.386594 -48.971967) (xy 86.44091 -48.919079)
			(xy 86.500539 -48.872264) (xy 86.564807 -48.832052) (xy 86.632984 -48.7989) (xy 86.7043 -48.773182)
			(xy 86.777945 -48.75519) (xy 86.853085 -48.745128) (xy 86.928869 -48.743109) (xy 87.004439 -48.749158)
			(xy 87.078937 -48.763205) (xy 87.15152 -48.785091) (xy 87.221366 -48.814568) (xy 87.287683 -48.851303)
			(xy 87.349719 -48.894878) (xy 87.406772 -48.9448) (xy 87.458196 -49.000504) (xy 87.503407 -49.061359)
			(xy 87.541894 -49.126674) (xy 87.57322 -49.19571) (xy 87.59703 -49.267685) (xy 87.613055 -49.341783)
			(xy 87.621114 -49.417164) (xy 87.621618 -49.45507) (xy 88.737697 -49.45507) (xy 88.741732 -49.379366)
			(xy 88.753791 -49.304521) (xy 88.773737 -49.23138) (xy 88.801344 -49.160775) (xy 88.8363 -49.093504)
			(xy 88.878208 -49.030329) (xy 88.926594 -48.971967) (xy 88.98091 -48.919079) (xy 89.040539 -48.872264)
			(xy 89.104807 -48.832052) (xy 89.172984 -48.7989) (xy 89.2443 -48.773182) (xy 89.317945 -48.75519)
			(xy 89.393085 -48.745128) (xy 89.468869 -48.743109) (xy 89.544439 -48.749158) (xy 89.618937 -48.763205)
			(xy 89.69152 -48.785091) (xy 89.761366 -48.814568) (xy 89.827683 -48.851303) (xy 89.889719 -48.894878)
			(xy 89.946772 -48.9448) (xy 89.998196 -49.000504) (xy 90.043407 -49.061359) (xy 90.081894 -49.126674)
			(xy 90.11322 -49.19571) (xy 90.13703 -49.267685) (xy 90.153055 -49.341783) (xy 90.161114 -49.417164)
			(xy 90.161618 -49.45507) (xy 91.277697 -49.45507) (xy 91.281732 -49.379366) (xy 91.293791 -49.304521)
			(xy 91.313737 -49.23138) (xy 91.341344 -49.160775) (xy 91.3763 -49.093504) (xy 91.418208 -49.030329)
			(xy 91.466594 -48.971967) (xy 91.52091 -48.919079) (xy 91.580539 -48.872264) (xy 91.644807 -48.832052)
			(xy 91.712984 -48.7989) (xy 91.7843 -48.773182) (xy 91.857945 -48.75519) (xy 91.933085 -48.745128)
			(xy 92.008869 -48.743109) (xy 92.084439 -48.749158) (xy 92.158937 -48.763205) (xy 92.23152 -48.785091)
			(xy 92.301366 -48.814568) (xy 92.367683 -48.851303) (xy 92.429719 -48.894878) (xy 92.486772 -48.9448)
			(xy 92.538196 -49.000504) (xy 92.583407 -49.061359) (xy 92.621894 -49.126674) (xy 92.65322 -49.19571)
			(xy 92.67703 -49.267685) (xy 92.693055 -49.341783) (xy 92.701114 -49.417164) (xy 92.701618 -49.45507)
			(xy 92.701114 -49.492976) (xy 92.693055 -49.568357) (xy 92.67703 -49.642455) (xy 92.65322 -49.71443)
			(xy 92.621894 -49.783466) (xy 92.583407 -49.848781) (xy 92.538196 -49.909636) (xy 92.486772 -49.96534)
			(xy 92.429719 -50.015262) (xy 92.367683 -50.058837) (xy 92.301366 -50.095572) (xy 92.23152 -50.125049)
			(xy 92.158937 -50.146935) (xy 92.084439 -50.160982) (xy 92.008869 -50.167031) (xy 91.933085 -50.165012)
			(xy 91.857945 -50.15495) (xy 91.7843 -50.136958) (xy 91.712984 -50.11124) (xy 91.644807 -50.078088)
			(xy 91.580539 -50.037876) (xy 91.52091 -49.991061) (xy 91.466594 -49.938173) (xy 91.418208 -49.879811)
			(xy 91.3763 -49.816636) (xy 91.341344 -49.749365) (xy 91.313737 -49.67876) (xy 91.293791 -49.605619)
			(xy 91.281732 -49.530774) (xy 91.277697 -49.45507) (xy 90.161618 -49.45507) (xy 90.161114 -49.492976)
			(xy 90.153055 -49.568357) (xy 90.13703 -49.642455) (xy 90.11322 -49.71443) (xy 90.081894 -49.783466)
			(xy 90.043407 -49.848781) (xy 89.998196 -49.909636) (xy 89.946772 -49.96534) (xy 89.889719 -50.015262)
			(xy 89.827683 -50.058837) (xy 89.761366 -50.095572) (xy 89.69152 -50.125049) (xy 89.618937 -50.146935)
			(xy 89.544439 -50.160982) (xy 89.468869 -50.167031) (xy 89.393085 -50.165012) (xy 89.317945 -50.15495)
			(xy 89.2443 -50.136958) (xy 89.172984 -50.11124) (xy 89.104807 -50.078088) (xy 89.040539 -50.037876)
			(xy 88.98091 -49.991061) (xy 88.926594 -49.938173) (xy 88.878208 -49.879811) (xy 88.8363 -49.816636)
			(xy 88.801344 -49.749365) (xy 88.773737 -49.67876) (xy 88.753791 -49.605619) (xy 88.741732 -49.530774)
			(xy 88.737697 -49.45507) (xy 87.621618 -49.45507) (xy 87.621114 -49.492976) (xy 87.613055 -49.568357)
			(xy 87.59703 -49.642455) (xy 87.57322 -49.71443) (xy 87.541894 -49.783466) (xy 87.503407 -49.848781)
			(xy 87.458196 -49.909636) (xy 87.406772 -49.96534) (xy 87.349719 -50.015262) (xy 87.287683 -50.058837)
			(xy 87.221366 -50.095572) (xy 87.15152 -50.125049) (xy 87.078937 -50.146935) (xy 87.004439 -50.160982)
			(xy 86.928869 -50.167031) (xy 86.853085 -50.165012) (xy 86.777945 -50.15495) (xy 86.7043 -50.136958)
			(xy 86.632984 -50.11124) (xy 86.564807 -50.078088) (xy 86.500539 -50.037876) (xy 86.44091 -49.991061)
			(xy 86.386594 -49.938173) (xy 86.338208 -49.879811) (xy 86.2963 -49.816636) (xy 86.261344 -49.749365)
			(xy 86.233737 -49.67876) (xy 86.213791 -49.605619) (xy 86.201732 -49.530774) (xy 86.197697 -49.45507)
			(xy 62.265544 -49.45507) (xy 62.316652 -49.49979) (xy 62.368076 -49.555494) (xy 62.413287 -49.616349)
			(xy 62.451774 -49.681664) (xy 62.4831 -49.7507) (xy 62.50691 -49.822675) (xy 62.522935 -49.896773)
			(xy 62.530994 -49.972154) (xy 62.531498 -50.01006) (xy 62.530994 -50.047966) (xy 62.522935 -50.123347)
			(xy 62.50691 -50.197445) (xy 62.4831 -50.26942) (xy 62.451774 -50.338456) (xy 62.413287 -50.403771)
			(xy 62.368076 -50.464626) (xy 62.316652 -50.52033) (xy 62.259599 -50.570252) (xy 62.197563 -50.613827)
			(xy 62.131246 -50.650562) (xy 62.0614 -50.680039) (xy 61.988817 -50.701925) (xy 61.914319 -50.715972)
			(xy 61.838749 -50.722021) (xy 61.762965 -50.720002) (xy 61.687825 -50.70994) (xy 61.61418 -50.691948)
			(xy 61.542864 -50.66623) (xy 61.474687 -50.633078) (xy 61.410419 -50.592866) (xy 61.35079 -50.546051)
			(xy 61.296474 -50.493163) (xy 61.248088 -50.434801) (xy 61.20618 -50.371626) (xy 61.171224 -50.304355)
			(xy 61.143617 -50.23375) (xy 61.123671 -50.160609) (xy 61.111612 -50.085764) (xy 61.107577 -50.01006)
			(xy 59.991498 -50.01006) (xy 59.990994 -50.047966) (xy 59.982935 -50.123347) (xy 59.96691 -50.197445)
			(xy 59.9431 -50.26942) (xy 59.911774 -50.338456) (xy 59.873287 -50.403771) (xy 59.828076 -50.464626)
			(xy 59.776652 -50.52033) (xy 59.719599 -50.570252) (xy 59.657563 -50.613827) (xy 59.591246 -50.650562)
			(xy 59.5214 -50.680039) (xy 59.448817 -50.701925) (xy 59.374319 -50.715972) (xy 59.298749 -50.722021)
			(xy 59.222965 -50.720002) (xy 59.147825 -50.70994) (xy 59.07418 -50.691948) (xy 59.002864 -50.66623)
			(xy 58.934687 -50.633078) (xy 58.870419 -50.592866) (xy 58.81079 -50.546051) (xy 58.756474 -50.493163)
			(xy 58.708088 -50.434801) (xy 58.66618 -50.371626) (xy 58.631224 -50.304355) (xy 58.603617 -50.23375)
			(xy 58.583671 -50.160609) (xy 58.571612 -50.085764) (xy 58.567577 -50.01006) (xy 57.451498 -50.01006)
			(xy 57.450994 -50.047966) (xy 57.442935 -50.123347) (xy 57.42691 -50.197445) (xy 57.4031 -50.26942)
			(xy 57.371774 -50.338456) (xy 57.333287 -50.403771) (xy 57.288076 -50.464626) (xy 57.236652 -50.52033)
			(xy 57.179599 -50.570252) (xy 57.117563 -50.613827) (xy 57.051246 -50.650562) (xy 56.9814 -50.680039)
			(xy 56.908817 -50.701925) (xy 56.834319 -50.715972) (xy 56.758749 -50.722021) (xy 56.682965 -50.720002)
			(xy 56.607825 -50.70994) (xy 56.53418 -50.691948) (xy 56.462864 -50.66623) (xy 56.394687 -50.633078)
			(xy 56.330419 -50.592866) (xy 56.27079 -50.546051) (xy 56.216474 -50.493163) (xy 56.168088 -50.434801)
			(xy 56.12618 -50.371626) (xy 56.091224 -50.304355) (xy 56.063617 -50.23375) (xy 56.043671 -50.160609)
			(xy 56.031612 -50.085764) (xy 56.027577 -50.01006) (xy 54.911498 -50.01006) (xy 54.910994 -50.047966)
			(xy 54.902935 -50.123347) (xy 54.88691 -50.197445) (xy 54.8631 -50.26942) (xy 54.831774 -50.338456)
			(xy 54.793287 -50.403771) (xy 54.748076 -50.464626) (xy 54.696652 -50.52033) (xy 54.639599 -50.570252)
			(xy 54.577563 -50.613827) (xy 54.511246 -50.650562) (xy 54.4414 -50.680039) (xy 54.368817 -50.701925)
			(xy 54.294319 -50.715972) (xy 54.218749 -50.722021) (xy 54.142965 -50.720002) (xy 54.067825 -50.70994)
			(xy 53.99418 -50.691948) (xy 53.922864 -50.66623) (xy 53.854687 -50.633078) (xy 53.790419 -50.592866)
			(xy 53.73079 -50.546051) (xy 53.676474 -50.493163) (xy 53.628088 -50.434801) (xy 53.58618 -50.371626)
			(xy 53.551224 -50.304355) (xy 53.523617 -50.23375) (xy 53.503671 -50.160609) (xy 53.491612 -50.085764)
			(xy 53.487577 -50.01006) (xy 52.371498 -50.01006) (xy 52.370994 -50.047966) (xy 52.362935 -50.123347)
			(xy 52.34691 -50.197445) (xy 52.3231 -50.26942) (xy 52.291774 -50.338456) (xy 52.253287 -50.403771)
			(xy 52.208076 -50.464626) (xy 52.156652 -50.52033) (xy 52.099599 -50.570252) (xy 52.037563 -50.613827)
			(xy 51.971246 -50.650562) (xy 51.9014 -50.680039) (xy 51.828817 -50.701925) (xy 51.754319 -50.715972)
			(xy 51.678749 -50.722021) (xy 51.602965 -50.720002) (xy 51.527825 -50.70994) (xy 51.45418 -50.691948)
			(xy 51.382864 -50.66623) (xy 51.314687 -50.633078) (xy 51.250419 -50.592866) (xy 51.19079 -50.546051)
			(xy 51.136474 -50.493163) (xy 51.088088 -50.434801) (xy 51.04618 -50.371626) (xy 51.011224 -50.304355)
			(xy 50.983617 -50.23375) (xy 50.963671 -50.160609) (xy 50.951612 -50.085764) (xy 50.947577 -50.01006)
			(xy 49.831498 -50.01006) (xy 49.830994 -50.047966) (xy 49.822935 -50.123347) (xy 49.80691 -50.197445)
			(xy 49.7831 -50.26942) (xy 49.751774 -50.338456) (xy 49.713287 -50.403771) (xy 49.668076 -50.464626)
			(xy 49.616652 -50.52033) (xy 49.559599 -50.570252) (xy 49.497563 -50.613827) (xy 49.431246 -50.650562)
			(xy 49.3614 -50.680039) (xy 49.288817 -50.701925) (xy 49.214319 -50.715972) (xy 49.138749 -50.722021)
			(xy 49.062965 -50.720002) (xy 48.987825 -50.70994) (xy 48.91418 -50.691948) (xy 48.842864 -50.66623)
			(xy 48.774687 -50.633078) (xy 48.710419 -50.592866) (xy 48.65079 -50.546051) (xy 48.596474 -50.493163)
			(xy 48.548088 -50.434801) (xy 48.50618 -50.371626) (xy 48.471224 -50.304355) (xy 48.443617 -50.23375)
			(xy 48.423671 -50.160609) (xy 48.411612 -50.085764) (xy 48.407577 -50.01006) (xy 47.291498 -50.01006)
			(xy 47.290994 -50.047966) (xy 47.282935 -50.123347) (xy 47.26691 -50.197445) (xy 47.2431 -50.26942)
			(xy 47.211774 -50.338456) (xy 47.173287 -50.403771) (xy 47.128076 -50.464626) (xy 47.076652 -50.52033)
			(xy 47.019599 -50.570252) (xy 46.957563 -50.613827) (xy 46.891246 -50.650562) (xy 46.8214 -50.680039)
			(xy 46.748817 -50.701925) (xy 46.674319 -50.715972) (xy 46.598749 -50.722021) (xy 46.522965 -50.720002)
			(xy 46.447825 -50.70994) (xy 46.37418 -50.691948) (xy 46.302864 -50.66623) (xy 46.234687 -50.633078)
			(xy 46.170419 -50.592866) (xy 46.11079 -50.546051) (xy 46.056474 -50.493163) (xy 46.008088 -50.434801)
			(xy 45.96618 -50.371626) (xy 45.931224 -50.304355) (xy 45.903617 -50.23375) (xy 45.883671 -50.160609)
			(xy 45.871612 -50.085764) (xy 45.867577 -50.01006) (xy 44.751498 -50.01006) (xy 44.750994 -50.047966)
			(xy 44.742935 -50.123347) (xy 44.72691 -50.197445) (xy 44.7031 -50.26942) (xy 44.671774 -50.338456)
			(xy 44.633287 -50.403771) (xy 44.588076 -50.464626) (xy 44.536652 -50.52033) (xy 44.479599 -50.570252)
			(xy 44.417563 -50.613827) (xy 44.351246 -50.650562) (xy 44.2814 -50.680039) (xy 44.208817 -50.701925)
			(xy 44.134319 -50.715972) (xy 44.058749 -50.722021) (xy 43.982965 -50.720002) (xy 43.907825 -50.70994)
			(xy 43.83418 -50.691948) (xy 43.762864 -50.66623) (xy 43.694687 -50.633078) (xy 43.630419 -50.592866)
			(xy 43.57079 -50.546051) (xy 43.516474 -50.493163) (xy 43.468088 -50.434801) (xy 43.42618 -50.371626)
			(xy 43.391224 -50.304355) (xy 43.363617 -50.23375) (xy 43.343671 -50.160609) (xy 43.331612 -50.085764)
			(xy 43.327577 -50.01006) (xy 42.50107 -50.01006) (xy 42.515537 -50.020272) (xy 42.604599 -50.09273)
			(xy 42.68851 -50.171096) (xy 42.766876 -50.255007) (xy 42.839334 -50.344069) (xy 42.905545 -50.437869)
			(xy 42.9652 -50.535968) (xy 43.018022 -50.63791) (xy 43.055881 -50.72507) (xy 84.927697 -50.72507)
			(xy 84.931732 -50.649366) (xy 84.943791 -50.574521) (xy 84.963737 -50.50138) (xy 84.991344 -50.430775)
			(xy 85.0263 -50.363504) (xy 85.068208 -50.300329) (xy 85.116594 -50.241967) (xy 85.17091 -50.189079)
			(xy 85.230539 -50.142264) (xy 85.294807 -50.102052) (xy 85.362984 -50.0689) (xy 85.4343 -50.043182)
			(xy 85.507945 -50.02519) (xy 85.583085 -50.015128) (xy 85.658869 -50.013109) (xy 85.734439 -50.019158)
			(xy 85.808937 -50.033205) (xy 85.88152 -50.055091) (xy 85.951366 -50.084568) (xy 86.017683 -50.121303)
			(xy 86.079719 -50.164878) (xy 86.136772 -50.2148) (xy 86.188196 -50.270504) (xy 86.233407 -50.331359)
			(xy 86.271894 -50.396674) (xy 86.30322 -50.46571) (xy 86.32703 -50.537685) (xy 86.343055 -50.611783)
			(xy 86.351114 -50.687164) (xy 86.351618 -50.72507) (xy 87.467697 -50.72507) (xy 87.471732 -50.649366)
			(xy 87.483791 -50.574521) (xy 87.503737 -50.50138) (xy 87.531344 -50.430775) (xy 87.5663 -50.363504)
			(xy 87.608208 -50.300329) (xy 87.656594 -50.241967) (xy 87.71091 -50.189079) (xy 87.770539 -50.142264)
			(xy 87.834807 -50.102052) (xy 87.902984 -50.0689) (xy 87.9743 -50.043182) (xy 88.047945 -50.02519)
			(xy 88.123085 -50.015128) (xy 88.198869 -50.013109) (xy 88.274439 -50.019158) (xy 88.348937 -50.033205)
			(xy 88.42152 -50.055091) (xy 88.491366 -50.084568) (xy 88.557683 -50.121303) (xy 88.619719 -50.164878)
			(xy 88.676772 -50.2148) (xy 88.728196 -50.270504) (xy 88.773407 -50.331359) (xy 88.811894 -50.396674)
			(xy 88.84322 -50.46571) (xy 88.86703 -50.537685) (xy 88.883055 -50.611783) (xy 88.891114 -50.687164)
			(xy 88.891618 -50.72507) (xy 90.007697 -50.72507) (xy 90.011732 -50.649366) (xy 90.023791 -50.574521)
			(xy 90.043737 -50.50138) (xy 90.071344 -50.430775) (xy 90.1063 -50.363504) (xy 90.148208 -50.300329)
			(xy 90.196594 -50.241967) (xy 90.25091 -50.189079) (xy 90.310539 -50.142264) (xy 90.374807 -50.102052)
			(xy 90.442984 -50.0689) (xy 90.5143 -50.043182) (xy 90.587945 -50.02519) (xy 90.663085 -50.015128)
			(xy 90.738869 -50.013109) (xy 90.814439 -50.019158) (xy 90.888937 -50.033205) (xy 90.96152 -50.055091)
			(xy 91.031366 -50.084568) (xy 91.097683 -50.121303) (xy 91.159719 -50.164878) (xy 91.216772 -50.2148)
			(xy 91.268196 -50.270504) (xy 91.313407 -50.331359) (xy 91.351894 -50.396674) (xy 91.38322 -50.46571)
			(xy 91.40703 -50.537685) (xy 91.423055 -50.611783) (xy 91.431114 -50.687164) (xy 91.431618 -50.72507)
			(xy 91.431114 -50.762976) (xy 91.423055 -50.838357) (xy 91.40703 -50.912455) (xy 91.38322 -50.98443)
			(xy 91.351894 -51.053466) (xy 91.313407 -51.118781) (xy 91.268196 -51.179636) (xy 91.216772 -51.23534)
			(xy 91.159719 -51.285262) (xy 91.097683 -51.328837) (xy 91.031366 -51.365572) (xy 90.96152 -51.395049)
			(xy 90.888937 -51.416935) (xy 90.814439 -51.430982) (xy 90.738869 -51.437031) (xy 90.663085 -51.435012)
			(xy 90.587945 -51.42495) (xy 90.5143 -51.406958) (xy 90.442984 -51.38124) (xy 90.374807 -51.348088)
			(xy 90.310539 -51.307876) (xy 90.25091 -51.261061) (xy 90.196594 -51.208173) (xy 90.148208 -51.149811)
			(xy 90.1063 -51.086636) (xy 90.071344 -51.019365) (xy 90.043737 -50.94876) (xy 90.023791 -50.875619)
			(xy 90.011732 -50.800774) (xy 90.007697 -50.72507) (xy 88.891618 -50.72507) (xy 88.891114 -50.762976)
			(xy 88.883055 -50.838357) (xy 88.86703 -50.912455) (xy 88.84322 -50.98443) (xy 88.811894 -51.053466)
			(xy 88.773407 -51.118781) (xy 88.728196 -51.179636) (xy 88.676772 -51.23534) (xy 88.619719 -51.285262)
			(xy 88.557683 -51.328837) (xy 88.491366 -51.365572) (xy 88.42152 -51.395049) (xy 88.348937 -51.416935)
			(xy 88.274439 -51.430982) (xy 88.198869 -51.437031) (xy 88.123085 -51.435012) (xy 88.047945 -51.42495)
			(xy 87.9743 -51.406958) (xy 87.902984 -51.38124) (xy 87.834807 -51.348088) (xy 87.770539 -51.307876)
			(xy 87.71091 -51.261061) (xy 87.656594 -51.208173) (xy 87.608208 -51.149811) (xy 87.5663 -51.086636)
			(xy 87.531344 -51.019365) (xy 87.503737 -50.94876) (xy 87.483791 -50.875619) (xy 87.471732 -50.800774)
			(xy 87.467697 -50.72507) (xy 86.351618 -50.72507) (xy 86.351114 -50.762976) (xy 86.343055 -50.838357)
			(xy 86.32703 -50.912455) (xy 86.30322 -50.98443) (xy 86.271894 -51.053466) (xy 86.233407 -51.118781)
			(xy 86.188196 -51.179636) (xy 86.136772 -51.23534) (xy 86.079719 -51.285262) (xy 86.017683 -51.328837)
			(xy 85.951366 -51.365572) (xy 85.88152 -51.395049) (xy 85.808937 -51.416935) (xy 85.734439 -51.430982)
			(xy 85.658869 -51.437031) (xy 85.583085 -51.435012) (xy 85.507945 -51.42495) (xy 85.4343 -51.406958)
			(xy 85.362984 -51.38124) (xy 85.294807 -51.348088) (xy 85.230539 -51.307876) (xy 85.17091 -51.261061)
			(xy 85.116594 -51.208173) (xy 85.068208 -51.149811) (xy 85.0263 -51.086636) (xy 84.991344 -51.019365)
			(xy 84.963737 -50.94876) (xy 84.943791 -50.875619) (xy 84.931732 -50.800774) (xy 84.927697 -50.72507)
			(xy 43.055881 -50.72507) (xy 43.063764 -50.743218) (xy 43.102213 -50.851403) (xy 43.13319 -50.96196)
			(xy 43.156549 -51.074372) (xy 43.172183 -51.188117) (xy 43.180018 -51.302663) (xy 43.180508 -51.36007)
			(xy 43.180381 -51.393251) (xy 43.177842 -51.459565) (xy 43.175428 -51.492658) (xy 43.170272 -51.550942)
			(xy 43.152948 -51.666671) (xy 43.127616 -51.780914) (xy 43.094401 -51.893119) (xy 43.056327 -51.99507)
			(xy 86.197697 -51.99507) (xy 86.201732 -51.919366) (xy 86.213791 -51.844521) (xy 86.233737 -51.77138)
			(xy 86.261344 -51.700775) (xy 86.2963 -51.633504) (xy 86.338208 -51.570329) (xy 86.386594 -51.511967)
			(xy 86.44091 -51.459079) (xy 86.500539 -51.412264) (xy 86.564807 -51.372052) (xy 86.632984 -51.3389)
			(xy 86.7043 -51.313182) (xy 86.777945 -51.29519) (xy 86.853085 -51.285128) (xy 86.928869 -51.283109)
			(xy 87.004439 -51.289158) (xy 87.078937 -51.303205) (xy 87.15152 -51.325091) (xy 87.221366 -51.354568)
			(xy 87.287683 -51.391303) (xy 87.349719 -51.434878) (xy 87.406772 -51.4848) (xy 87.458196 -51.540504)
			(xy 87.503407 -51.601359) (xy 87.541894 -51.666674) (xy 87.57322 -51.73571) (xy 87.59703 -51.807685)
			(xy 87.613055 -51.881783) (xy 87.621114 -51.957164) (xy 87.621618 -51.99507) (xy 88.737697 -51.99507)
			(xy 88.741732 -51.919366) (xy 88.753791 -51.844521) (xy 88.773737 -51.77138) (xy 88.801344 -51.700775)
			(xy 88.8363 -51.633504) (xy 88.878208 -51.570329) (xy 88.926594 -51.511967) (xy 88.98091 -51.459079)
			(xy 89.040539 -51.412264) (xy 89.104807 -51.372052) (xy 89.172984 -51.3389) (xy 89.2443 -51.313182)
			(xy 89.317945 -51.29519) (xy 89.393085 -51.285128) (xy 89.468869 -51.283109) (xy 89.544439 -51.289158)
			(xy 89.618937 -51.303205) (xy 89.69152 -51.325091) (xy 89.761366 -51.354568) (xy 89.827683 -51.391303)
			(xy 89.889719 -51.434878) (xy 89.946772 -51.4848) (xy 89.998196 -51.540504) (xy 90.043407 -51.601359)
			(xy 90.081894 -51.666674) (xy 90.11322 -51.73571) (xy 90.13703 -51.807685) (xy 90.153055 -51.881783)
			(xy 90.161114 -51.957164) (xy 90.161618 -51.99507) (xy 91.277697 -51.99507) (xy 91.281732 -51.919366)
			(xy 91.293791 -51.844521) (xy 91.313737 -51.77138) (xy 91.341344 -51.700775) (xy 91.3763 -51.633504)
			(xy 91.418208 -51.570329) (xy 91.466594 -51.511967) (xy 91.52091 -51.459079) (xy 91.580539 -51.412264)
			(xy 91.644807 -51.372052) (xy 91.712984 -51.3389) (xy 91.7843 -51.313182) (xy 91.857945 -51.29519)
			(xy 91.933085 -51.285128) (xy 92.008869 -51.283109) (xy 92.084439 -51.289158) (xy 92.158937 -51.303205)
			(xy 92.23152 -51.325091) (xy 92.301366 -51.354568) (xy 92.367683 -51.391303) (xy 92.429719 -51.434878)
			(xy 92.486772 -51.4848) (xy 92.538196 -51.540504) (xy 92.583407 -51.601359) (xy 92.621894 -51.666674)
			(xy 92.65322 -51.73571) (xy 92.67703 -51.807685) (xy 92.693055 -51.881783) (xy 92.701114 -51.957164)
			(xy 92.701618 -51.99507) (xy 92.701114 -52.032976) (xy 92.693055 -52.108357) (xy 92.67703 -52.182455)
			(xy 92.65322 -52.25443) (xy 92.621894 -52.323466) (xy 92.583407 -52.388781) (xy 92.538196 -52.449636)
			(xy 92.486772 -52.50534) (xy 92.429719 -52.555262) (xy 92.367683 -52.598837) (xy 92.301366 -52.635572)
			(xy 92.23152 -52.665049) (xy 92.158937 -52.686935) (xy 92.084439 -52.700982) (xy 92.008869 -52.707031)
			(xy 91.933085 -52.705012) (xy 91.857945 -52.69495) (xy 91.7843 -52.676958) (xy 91.712984 -52.65124)
			(xy 91.644807 -52.618088) (xy 91.580539 -52.577876) (xy 91.52091 -52.531061) (xy 91.466594 -52.478173)
			(xy 91.418208 -52.419811) (xy 91.3763 -52.356636) (xy 91.341344 -52.289365) (xy 91.313737 -52.21876)
			(xy 91.293791 -52.145619) (xy 91.281732 -52.070774) (xy 91.277697 -51.99507) (xy 90.161618 -51.99507)
			(xy 90.161114 -52.032976) (xy 90.153055 -52.108357) (xy 90.13703 -52.182455) (xy 90.11322 -52.25443)
			(xy 90.081894 -52.323466) (xy 90.043407 -52.388781) (xy 89.998196 -52.449636) (xy 89.946772 -52.50534)
			(xy 89.889719 -52.555262) (xy 89.827683 -52.598837) (xy 89.761366 -52.635572) (xy 89.69152 -52.665049)
			(xy 89.618937 -52.686935) (xy 89.544439 -52.700982) (xy 89.468869 -52.707031) (xy 89.393085 -52.705012)
			(xy 89.317945 -52.69495) (xy 89.2443 -52.676958) (xy 89.172984 -52.65124) (xy 89.104807 -52.618088)
			(xy 89.040539 -52.577876) (xy 88.98091 -52.531061) (xy 88.926594 -52.478173) (xy 88.878208 -52.419811)
			(xy 88.8363 -52.356636) (xy 88.801344 -52.289365) (xy 88.773737 -52.21876) (xy 88.753791 -52.145619)
			(xy 88.741732 -52.070774) (xy 88.737697 -51.99507) (xy 87.621618 -51.99507) (xy 87.621114 -52.032976)
			(xy 87.613055 -52.108357) (xy 87.59703 -52.182455) (xy 87.57322 -52.25443) (xy 87.541894 -52.323466)
			(xy 87.503407 -52.388781) (xy 87.458196 -52.449636) (xy 87.406772 -52.50534) (xy 87.349719 -52.555262)
			(xy 87.287683 -52.598837) (xy 87.221366 -52.635572) (xy 87.15152 -52.665049) (xy 87.078937 -52.686935)
			(xy 87.004439 -52.700982) (xy 86.928869 -52.707031) (xy 86.853085 -52.705012) (xy 86.777945 -52.69495)
			(xy 86.7043 -52.676958) (xy 86.632984 -52.65124) (xy 86.564807 -52.618088) (xy 86.500539 -52.577876)
			(xy 86.44091 -52.531061) (xy 86.386594 -52.478173) (xy 86.338208 -52.419811) (xy 86.2963 -52.356636)
			(xy 86.261344 -52.289365) (xy 86.233737 -52.21876) (xy 86.213791 -52.145619) (xy 86.201732 -52.070774)
			(xy 86.197697 -51.99507) (xy 43.056327 -51.99507) (xy 43.055094 -51.998372) (xy 43.328336 -51.998372)
			(xy 44.751244 -51.998372) (xy 44.751244 -52.71008) (xy 45.867577 -52.71008) (xy 45.871612 -52.634376)
			(xy 45.883671 -52.559531) (xy 45.903617 -52.48639) (xy 45.931224 -52.415785) (xy 45.96618 -52.348514)
			(xy 46.008088 -52.285339) (xy 46.056474 -52.226977) (xy 46.11079 -52.174089) (xy 46.170419 -52.127274)
			(xy 46.234687 -52.087062) (xy 46.302864 -52.05391) (xy 46.37418 -52.028192) (xy 46.447825 -52.0102)
			(xy 46.522965 -52.000138) (xy 46.598749 -51.998119) (xy 46.674319 -52.004168) (xy 46.748817 -52.018215)
			(xy 46.8214 -52.040101) (xy 46.891246 -52.069578) (xy 46.957563 -52.106313) (xy 47.019599 -52.149888)
			(xy 47.076652 -52.19981) (xy 47.128076 -52.255514) (xy 47.173287 -52.316369) (xy 47.211774 -52.381684)
			(xy 47.2431 -52.45072) (xy 47.26691 -52.522695) (xy 47.282935 -52.596793) (xy 47.290994 -52.672174)
			(xy 47.291498 -52.71008) (xy 48.407577 -52.71008) (xy 48.411612 -52.634376) (xy 48.423671 -52.559531)
			(xy 48.443617 -52.48639) (xy 48.471224 -52.415785) (xy 48.50618 -52.348514) (xy 48.548088 -52.285339)
			(xy 48.596474 -52.226977) (xy 48.65079 -52.174089) (xy 48.710419 -52.127274) (xy 48.774687 -52.087062)
			(xy 48.842864 -52.05391) (xy 48.91418 -52.028192) (xy 48.987825 -52.0102) (xy 49.062965 -52.000138)
			(xy 49.138749 -51.998119) (xy 49.214319 -52.004168) (xy 49.288817 -52.018215) (xy 49.3614 -52.040101)
			(xy 49.431246 -52.069578) (xy 49.497563 -52.106313) (xy 49.559599 -52.149888) (xy 49.616652 -52.19981)
			(xy 49.668076 -52.255514) (xy 49.713287 -52.316369) (xy 49.751774 -52.381684) (xy 49.7831 -52.45072)
			(xy 49.80691 -52.522695) (xy 49.822935 -52.596793) (xy 49.830994 -52.672174) (xy 49.831498 -52.71008)
			(xy 50.947577 -52.71008) (xy 50.951612 -52.634376) (xy 50.963671 -52.559531) (xy 50.983617 -52.48639)
			(xy 51.011224 -52.415785) (xy 51.04618 -52.348514) (xy 51.088088 -52.285339) (xy 51.136474 -52.226977)
			(xy 51.19079 -52.174089) (xy 51.250419 -52.127274) (xy 51.314687 -52.087062) (xy 51.382864 -52.05391)
			(xy 51.45418 -52.028192) (xy 51.527825 -52.0102) (xy 51.602965 -52.000138) (xy 51.678749 -51.998119)
			(xy 51.754319 -52.004168) (xy 51.828817 -52.018215) (xy 51.9014 -52.040101) (xy 51.971246 -52.069578)
			(xy 52.037563 -52.106313) (xy 52.099599 -52.149888) (xy 52.156652 -52.19981) (xy 52.208076 -52.255514)
			(xy 52.253287 -52.316369) (xy 52.291774 -52.381684) (xy 52.3231 -52.45072) (xy 52.34691 -52.522695)
			(xy 52.362935 -52.596793) (xy 52.370994 -52.672174) (xy 52.371498 -52.71008) (xy 53.487577 -52.71008)
			(xy 53.491612 -52.634376) (xy 53.503671 -52.559531) (xy 53.523617 -52.48639) (xy 53.551224 -52.415785)
			(xy 53.58618 -52.348514) (xy 53.628088 -52.285339) (xy 53.676474 -52.226977) (xy 53.73079 -52.174089)
			(xy 53.790419 -52.127274) (xy 53.854687 -52.087062) (xy 53.922864 -52.05391) (xy 53.99418 -52.028192)
			(xy 54.067825 -52.0102) (xy 54.142965 -52.000138) (xy 54.218749 -51.998119) (xy 54.294319 -52.004168)
			(xy 54.368817 -52.018215) (xy 54.4414 -52.040101) (xy 54.511246 -52.069578) (xy 54.577563 -52.106313)
			(xy 54.639599 -52.149888) (xy 54.696652 -52.19981) (xy 54.748076 -52.255514) (xy 54.793287 -52.316369)
			(xy 54.831774 -52.381684) (xy 54.8631 -52.45072) (xy 54.88691 -52.522695) (xy 54.902935 -52.596793)
			(xy 54.910994 -52.672174) (xy 54.911498 -52.71008) (xy 56.027577 -52.71008) (xy 56.031612 -52.634376)
			(xy 56.043671 -52.559531) (xy 56.063617 -52.48639) (xy 56.091224 -52.415785) (xy 56.12618 -52.348514)
			(xy 56.168088 -52.285339) (xy 56.216474 -52.226977) (xy 56.27079 -52.174089) (xy 56.330419 -52.127274)
			(xy 56.394687 -52.087062) (xy 56.462864 -52.05391) (xy 56.53418 -52.028192) (xy 56.607825 -52.0102)
			(xy 56.682965 -52.000138) (xy 56.758749 -51.998119) (xy 56.834319 -52.004168) (xy 56.908817 -52.018215)
			(xy 56.9814 -52.040101) (xy 57.051246 -52.069578) (xy 57.117563 -52.106313) (xy 57.179599 -52.149888)
			(xy 57.236652 -52.19981) (xy 57.288076 -52.255514) (xy 57.333287 -52.316369) (xy 57.371774 -52.381684)
			(xy 57.4031 -52.45072) (xy 57.42691 -52.522695) (xy 57.442935 -52.596793) (xy 57.450994 -52.672174)
			(xy 57.451498 -52.71008) (xy 58.567577 -52.71008) (xy 58.571612 -52.634376) (xy 58.583671 -52.559531)
			(xy 58.603617 -52.48639) (xy 58.631224 -52.415785) (xy 58.66618 -52.348514) (xy 58.708088 -52.285339)
			(xy 58.756474 -52.226977) (xy 58.81079 -52.174089) (xy 58.870419 -52.127274) (xy 58.934687 -52.087062)
			(xy 59.002864 -52.05391) (xy 59.07418 -52.028192) (xy 59.147825 -52.0102) (xy 59.222965 -52.000138)
			(xy 59.298749 -51.998119) (xy 59.374319 -52.004168) (xy 59.448817 -52.018215) (xy 59.5214 -52.040101)
			(xy 59.591246 -52.069578) (xy 59.657563 -52.106313) (xy 59.719599 -52.149888) (xy 59.776652 -52.19981)
			(xy 59.828076 -52.255514) (xy 59.873287 -52.316369) (xy 59.911774 -52.381684) (xy 59.9431 -52.45072)
			(xy 59.96691 -52.522695) (xy 59.982935 -52.596793) (xy 59.990994 -52.672174) (xy 59.991498 -52.71008)
			(xy 61.107577 -52.71008) (xy 61.111612 -52.634376) (xy 61.123671 -52.559531) (xy 61.143617 -52.48639)
			(xy 61.171224 -52.415785) (xy 61.20618 -52.348514) (xy 61.248088 -52.285339) (xy 61.296474 -52.226977)
			(xy 61.35079 -52.174089) (xy 61.410419 -52.127274) (xy 61.474687 -52.087062) (xy 61.542864 -52.05391)
			(xy 61.61418 -52.028192) (xy 61.687825 -52.0102) (xy 61.762965 -52.000138) (xy 61.838749 -51.998119)
			(xy 61.914319 -52.004168) (xy 61.988817 -52.018215) (xy 62.0614 -52.040101) (xy 62.131246 -52.069578)
			(xy 62.197563 -52.106313) (xy 62.259599 -52.149888) (xy 62.316652 -52.19981) (xy 62.368076 -52.255514)
			(xy 62.413287 -52.316369) (xy 62.451774 -52.381684) (xy 62.4831 -52.45072) (xy 62.50691 -52.522695)
			(xy 62.522935 -52.596793) (xy 62.530994 -52.672174) (xy 62.531498 -52.71008) (xy 62.530994 -52.747986)
			(xy 62.522935 -52.823367) (xy 62.50691 -52.897465) (xy 62.4831 -52.96944) (xy 62.451774 -53.038476)
			(xy 62.413287 -53.103791) (xy 62.368076 -53.164646) (xy 62.316652 -53.22035) (xy 62.265544 -53.26507)
			(xy 84.927697 -53.26507) (xy 84.931732 -53.189366) (xy 84.943791 -53.114521) (xy 84.963737 -53.04138)
			(xy 84.991344 -52.970775) (xy 85.0263 -52.903504) (xy 85.068208 -52.840329) (xy 85.116594 -52.781967)
			(xy 85.17091 -52.729079) (xy 85.230539 -52.682264) (xy 85.294807 -52.642052) (xy 85.362984 -52.6089)
			(xy 85.4343 -52.583182) (xy 85.507945 -52.56519) (xy 85.583085 -52.555128) (xy 85.658869 -52.553109)
			(xy 85.734439 -52.559158) (xy 85.808937 -52.573205) (xy 85.88152 -52.595091) (xy 85.951366 -52.624568)
			(xy 86.017683 -52.661303) (xy 86.079719 -52.704878) (xy 86.136772 -52.7548) (xy 86.188196 -52.810504)
			(xy 86.233407 -52.871359) (xy 86.271894 -52.936674) (xy 86.30322 -53.00571) (xy 86.32703 -53.077685)
			(xy 86.343055 -53.151783) (xy 86.351114 -53.227164) (xy 86.351618 -53.26507) (xy 87.467697 -53.26507)
			(xy 87.471732 -53.189366) (xy 87.483791 -53.114521) (xy 87.503737 -53.04138) (xy 87.531344 -52.970775)
			(xy 87.5663 -52.903504) (xy 87.608208 -52.840329) (xy 87.656594 -52.781967) (xy 87.71091 -52.729079)
			(xy 87.770539 -52.682264) (xy 87.834807 -52.642052) (xy 87.902984 -52.6089) (xy 87.9743 -52.583182)
			(xy 88.047945 -52.56519) (xy 88.123085 -52.555128) (xy 88.198869 -52.553109) (xy 88.274439 -52.559158)
			(xy 88.348937 -52.573205) (xy 88.42152 -52.595091) (xy 88.491366 -52.624568) (xy 88.557683 -52.661303)
			(xy 88.619719 -52.704878) (xy 88.676772 -52.7548) (xy 88.728196 -52.810504) (xy 88.773407 -52.871359)
			(xy 88.811894 -52.936674) (xy 88.84322 -53.00571) (xy 88.86703 -53.077685) (xy 88.883055 -53.151783)
			(xy 88.891114 -53.227164) (xy 88.891618 -53.26507) (xy 90.007697 -53.26507) (xy 90.011732 -53.189366)
			(xy 90.023791 -53.114521) (xy 90.043737 -53.04138) (xy 90.071344 -52.970775) (xy 90.1063 -52.903504)
			(xy 90.148208 -52.840329) (xy 90.196594 -52.781967) (xy 90.25091 -52.729079) (xy 90.310539 -52.682264)
			(xy 90.374807 -52.642052) (xy 90.442984 -52.6089) (xy 90.5143 -52.583182) (xy 90.587945 -52.56519)
			(xy 90.663085 -52.555128) (xy 90.738869 -52.553109) (xy 90.814439 -52.559158) (xy 90.888937 -52.573205)
			(xy 90.96152 -52.595091) (xy 91.031366 -52.624568) (xy 91.097683 -52.661303) (xy 91.159719 -52.704878)
			(xy 91.165664 -52.71008) (xy 93.154506 -52.71008) (xy 93.158522 -52.59381) (xy 93.170549 -52.478095)
			(xy 93.190531 -52.363485) (xy 93.218373 -52.250526) (xy 93.253942 -52.139758) (xy 93.297068 -52.031707)
			(xy 93.347545 -51.926889) (xy 93.405134 -51.825804) (xy 93.46956 -51.728932) (xy 93.540515 -51.636736)
			(xy 93.617662 -51.549655) (xy 93.700633 -51.468104) (xy 93.789033 -51.392472) (xy 93.88244 -51.323118)
			(xy 93.980409 -51.260375) (xy 94.082473 -51.204539) (xy 94.188147 -51.155878) (xy 94.296926 -51.114624)
			(xy 94.408291 -51.080973) (xy 94.521714 -51.055085) (xy 94.636651 -51.037084) (xy 94.752557 -51.027055)
			(xy 94.868879 -51.025047) (xy 94.985062 -51.031069) (xy 95.100553 -51.045092) (xy 95.214801 -51.06705)
			(xy 95.327262 -51.096837) (xy 95.4374 -51.134312) (xy 95.54469 -51.179297) (xy 95.648621 -51.231576)
			(xy 95.748697 -51.290901) (xy 95.844443 -51.356989) (xy 95.9354 -51.429525) (xy 96.021136 -51.508164)
			(xy 96.101243 -51.59253) (xy 96.175339 -51.682222) (xy 96.243069 -51.776812) (xy 96.304113 -51.87585)
			(xy 96.358178 -51.978863) (xy 96.405008 -52.08536) (xy 96.444379 -52.194835) (xy 96.476103 -52.306765)
			(xy 96.500029 -52.420617) (xy 96.516043 -52.535849) (xy 96.52407 -52.651911) (xy 96.524572 -52.71008)
			(xy 96.52407 -52.768249) (xy 96.516043 -52.884311) (xy 96.500029 -52.999543) (xy 96.476103 -53.113395)
			(xy 96.444379 -53.225325) (xy 96.405008 -53.3348) (xy 96.358178 -53.441297) (xy 96.304113 -53.54431)
			(xy 96.243069 -53.643348) (xy 96.175339 -53.737938) (xy 96.101243 -53.82763) (xy 96.021136 -53.911996)
			(xy 95.9354 -53.990635) (xy 95.844443 -54.063171) (xy 95.748697 -54.129259) (xy 95.648621 -54.188584)
			(xy 95.54469 -54.240863) (xy 95.4374 -54.285848) (xy 95.327262 -54.323323) (xy 95.214801 -54.35311)
			(xy 95.100553 -54.375068) (xy 94.985062 -54.389091) (xy 94.868879 -54.395113) (xy 94.752557 -54.393105)
			(xy 94.636651 -54.383076) (xy 94.521714 -54.365075) (xy 94.408291 -54.339187) (xy 94.296926 -54.305536)
			(xy 94.188147 -54.264282) (xy 94.082473 -54.215621) (xy 93.980409 -54.159785) (xy 93.88244 -54.097042)
			(xy 93.789033 -54.027688) (xy 93.700633 -53.952056) (xy 93.617662 -53.870505) (xy 93.540515 -53.783424)
			(xy 93.46956 -53.691228) (xy 93.405134 -53.594356) (xy 93.347545 -53.493271) (xy 93.297068 -53.388453)
			(xy 93.253942 -53.280402) (xy 93.218373 -53.169634) (xy 93.190531 -53.056675) (xy 93.170549 -52.942065)
			(xy 93.158522 -52.82635) (xy 93.154506 -52.71008) (xy 91.165664 -52.71008) (xy 91.216772 -52.7548)
			(xy 91.268196 -52.810504) (xy 91.313407 -52.871359) (xy 91.351894 -52.936674) (xy 91.38322 -53.00571)
			(xy 91.40703 -53.077685) (xy 91.423055 -53.151783) (xy 91.431114 -53.227164) (xy 91.431618 -53.26507)
			(xy 91.431114 -53.302976) (xy 91.423055 -53.378357) (xy 91.40703 -53.452455) (xy 91.38322 -53.52443)
			(xy 91.351894 -53.593466) (xy 91.313407 -53.658781) (xy 91.268196 -53.719636) (xy 91.216772 -53.77534)
			(xy 91.159719 -53.825262) (xy 91.097683 -53.868837) (xy 91.031366 -53.905572) (xy 90.96152 -53.935049)
			(xy 90.888937 -53.956935) (xy 90.814439 -53.970982) (xy 90.738869 -53.977031) (xy 90.663085 -53.975012)
			(xy 90.587945 -53.96495) (xy 90.5143 -53.946958) (xy 90.442984 -53.92124) (xy 90.374807 -53.888088)
			(xy 90.310539 -53.847876) (xy 90.25091 -53.801061) (xy 90.196594 -53.748173) (xy 90.148208 -53.689811)
			(xy 90.1063 -53.626636) (xy 90.071344 -53.559365) (xy 90.043737 -53.48876) (xy 90.023791 -53.415619)
			(xy 90.011732 -53.340774) (xy 90.007697 -53.26507) (xy 88.891618 -53.26507) (xy 88.891114 -53.302976)
			(xy 88.883055 -53.378357) (xy 88.86703 -53.452455) (xy 88.84322 -53.52443) (xy 88.811894 -53.593466)
			(xy 88.773407 -53.658781) (xy 88.728196 -53.719636) (xy 88.676772 -53.77534) (xy 88.619719 -53.825262)
			(xy 88.557683 -53.868837) (xy 88.491366 -53.905572) (xy 88.42152 -53.935049) (xy 88.348937 -53.956935)
			(xy 88.274439 -53.970982) (xy 88.198869 -53.977031) (xy 88.123085 -53.975012) (xy 88.047945 -53.96495)
			(xy 87.9743 -53.946958) (xy 87.902984 -53.92124) (xy 87.834807 -53.888088) (xy 87.770539 -53.847876)
			(xy 87.71091 -53.801061) (xy 87.656594 -53.748173) (xy 87.608208 -53.689811) (xy 87.5663 -53.626636)
			(xy 87.531344 -53.559365) (xy 87.503737 -53.48876) (xy 87.483791 -53.415619) (xy 87.471732 -53.340774)
			(xy 87.467697 -53.26507) (xy 86.351618 -53.26507) (xy 86.351114 -53.302976) (xy 86.343055 -53.378357)
			(xy 86.32703 -53.452455) (xy 86.30322 -53.52443) (xy 86.271894 -53.593466) (xy 86.233407 -53.658781)
			(xy 86.188196 -53.719636) (xy 86.136772 -53.77534) (xy 86.079719 -53.825262) (xy 86.017683 -53.868837)
			(xy 85.951366 -53.905572) (xy 85.88152 -53.935049) (xy 85.808937 -53.956935) (xy 85.734439 -53.970982)
			(xy 85.658869 -53.977031) (xy 85.583085 -53.975012) (xy 85.507945 -53.96495) (xy 85.4343 -53.946958)
			(xy 85.362984 -53.92124) (xy 85.294807 -53.888088) (xy 85.230539 -53.847876) (xy 85.17091 -53.801061)
			(xy 85.116594 -53.748173) (xy 85.068208 -53.689811) (xy 85.0263 -53.626636) (xy 84.991344 -53.559365)
			(xy 84.963737 -53.48876) (xy 84.943791 -53.415619) (xy 84.931732 -53.340774) (xy 84.927697 -53.26507)
			(xy 62.265544 -53.26507) (xy 62.259599 -53.270272) (xy 62.197563 -53.313847) (xy 62.131246 -53.350582)
			(xy 62.0614 -53.380059) (xy 61.988817 -53.401945) (xy 61.914319 -53.415992) (xy 61.838749 -53.422041)
			(xy 61.762965 -53.420022) (xy 61.687825 -53.40996) (xy 61.61418 -53.391968) (xy 61.542864 -53.36625)
			(xy 61.474687 -53.333098) (xy 61.410419 -53.292886) (xy 61.35079 -53.246071) (xy 61.296474 -53.193183)
			(xy 61.248088 -53.134821) (xy 61.20618 -53.071646) (xy 61.171224 -53.004375) (xy 61.143617 -52.93377)
			(xy 61.123671 -52.860629) (xy 61.111612 -52.785784) (xy 61.107577 -52.71008) (xy 59.991498 -52.71008)
			(xy 59.990994 -52.747986) (xy 59.982935 -52.823367) (xy 59.96691 -52.897465) (xy 59.9431 -52.96944)
			(xy 59.911774 -53.038476) (xy 59.873287 -53.103791) (xy 59.828076 -53.164646) (xy 59.776652 -53.22035)
			(xy 59.719599 -53.270272) (xy 59.657563 -53.313847) (xy 59.591246 -53.350582) (xy 59.5214 -53.380059)
			(xy 59.448817 -53.401945) (xy 59.374319 -53.415992) (xy 59.298749 -53.422041) (xy 59.222965 -53.420022)
			(xy 59.147825 -53.40996) (xy 59.07418 -53.391968) (xy 59.002864 -53.36625) (xy 58.934687 -53.333098)
			(xy 58.870419 -53.292886) (xy 58.81079 -53.246071) (xy 58.756474 -53.193183) (xy 58.708088 -53.134821)
			(xy 58.66618 -53.071646) (xy 58.631224 -53.004375) (xy 58.603617 -52.93377) (xy 58.583671 -52.860629)
			(xy 58.571612 -52.785784) (xy 58.567577 -52.71008) (xy 57.451498 -52.71008) (xy 57.450994 -52.747986)
			(xy 57.442935 -52.823367) (xy 57.42691 -52.897465) (xy 57.4031 -52.96944) (xy 57.371774 -53.038476)
			(xy 57.333287 -53.103791) (xy 57.288076 -53.164646) (xy 57.236652 -53.22035) (xy 57.179599 -53.270272)
			(xy 57.117563 -53.313847) (xy 57.051246 -53.350582) (xy 56.9814 -53.380059) (xy 56.908817 -53.401945)
			(xy 56.834319 -53.415992) (xy 56.758749 -53.422041) (xy 56.682965 -53.420022) (xy 56.607825 -53.40996)
			(xy 56.53418 -53.391968) (xy 56.462864 -53.36625) (xy 56.394687 -53.333098) (xy 56.330419 -53.292886)
			(xy 56.27079 -53.246071) (xy 56.216474 -53.193183) (xy 56.168088 -53.134821) (xy 56.12618 -53.071646)
			(xy 56.091224 -53.004375) (xy 56.063617 -52.93377) (xy 56.043671 -52.860629) (xy 56.031612 -52.785784)
			(xy 56.027577 -52.71008) (xy 54.911498 -52.71008) (xy 54.910994 -52.747986) (xy 54.902935 -52.823367)
			(xy 54.88691 -52.897465) (xy 54.8631 -52.96944) (xy 54.831774 -53.038476) (xy 54.793287 -53.103791)
			(xy 54.748076 -53.164646) (xy 54.696652 -53.22035) (xy 54.639599 -53.270272) (xy 54.577563 -53.313847)
			(xy 54.511246 -53.350582) (xy 54.4414 -53.380059) (xy 54.368817 -53.401945) (xy 54.294319 -53.415992)
			(xy 54.218749 -53.422041) (xy 54.142965 -53.420022) (xy 54.067825 -53.40996) (xy 53.99418 -53.391968)
			(xy 53.922864 -53.36625) (xy 53.854687 -53.333098) (xy 53.790419 -53.292886) (xy 53.73079 -53.246071)
			(xy 53.676474 -53.193183) (xy 53.628088 -53.134821) (xy 53.58618 -53.071646) (xy 53.551224 -53.004375)
			(xy 53.523617 -52.93377) (xy 53.503671 -52.860629) (xy 53.491612 -52.785784) (xy 53.487577 -52.71008)
			(xy 52.371498 -52.71008) (xy 52.370994 -52.747986) (xy 52.362935 -52.823367) (xy 52.34691 -52.897465)
			(xy 52.3231 -52.96944) (xy 52.291774 -53.038476) (xy 52.253287 -53.103791) (xy 52.208076 -53.164646)
			(xy 52.156652 -53.22035) (xy 52.099599 -53.270272) (xy 52.037563 -53.313847) (xy 51.971246 -53.350582)
			(xy 51.9014 -53.380059) (xy 51.828817 -53.401945) (xy 51.754319 -53.415992) (xy 51.678749 -53.422041)
			(xy 51.602965 -53.420022) (xy 51.527825 -53.40996) (xy 51.45418 -53.391968) (xy 51.382864 -53.36625)
			(xy 51.314687 -53.333098) (xy 51.250419 -53.292886) (xy 51.19079 -53.246071) (xy 51.136474 -53.193183)
			(xy 51.088088 -53.134821) (xy 51.04618 -53.071646) (xy 51.011224 -53.004375) (xy 50.983617 -52.93377)
			(xy 50.963671 -52.860629) (xy 50.951612 -52.785784) (xy 50.947577 -52.71008) (xy 49.831498 -52.71008)
			(xy 49.830994 -52.747986) (xy 49.822935 -52.823367) (xy 49.80691 -52.897465) (xy 49.7831 -52.96944)
			(xy 49.751774 -53.038476) (xy 49.713287 -53.103791) (xy 49.668076 -53.164646) (xy 49.616652 -53.22035)
			(xy 49.559599 -53.270272) (xy 49.497563 -53.313847) (xy 49.431246 -53.350582) (xy 49.3614 -53.380059)
			(xy 49.288817 -53.401945) (xy 49.214319 -53.415992) (xy 49.138749 -53.422041) (xy 49.062965 -53.420022)
			(xy 48.987825 -53.40996) (xy 48.91418 -53.391968) (xy 48.842864 -53.36625) (xy 48.774687 -53.333098)
			(xy 48.710419 -53.292886) (xy 48.65079 -53.246071) (xy 48.596474 -53.193183) (xy 48.548088 -53.134821)
			(xy 48.50618 -53.071646) (xy 48.471224 -53.004375) (xy 48.443617 -52.93377) (xy 48.423671 -52.860629)
			(xy 48.411612 -52.785784) (xy 48.407577 -52.71008) (xy 47.291498 -52.71008) (xy 47.290994 -52.747986)
			(xy 47.282935 -52.823367) (xy 47.26691 -52.897465) (xy 47.2431 -52.96944) (xy 47.211774 -53.038476)
			(xy 47.173287 -53.103791) (xy 47.128076 -53.164646) (xy 47.076652 -53.22035) (xy 47.019599 -53.270272)
			(xy 46.957563 -53.313847) (xy 46.891246 -53.350582) (xy 46.8214 -53.380059) (xy 46.748817 -53.401945)
			(xy 46.674319 -53.415992) (xy 46.598749 -53.422041) (xy 46.522965 -53.420022) (xy 46.447825 -53.40996)
			(xy 46.37418 -53.391968) (xy 46.302864 -53.36625) (xy 46.234687 -53.333098) (xy 46.170419 -53.292886)
			(xy 46.11079 -53.246071) (xy 46.056474 -53.193183) (xy 46.008088 -53.134821) (xy 45.96618 -53.071646)
			(xy 45.931224 -53.004375) (xy 45.903617 -52.93377) (xy 45.883671 -52.860629) (xy 45.871612 -52.785784)
			(xy 45.867577 -52.71008) (xy 44.751244 -52.71008) (xy 44.751244 -53.421788) (xy 43.328336 -53.421788)
			(xy 43.328336 -51.998372) (xy 43.055094 -51.998372) (xy 43.053462 -52.002742) (xy 43.004999 -52.109253)
			(xy 42.949245 -52.212135) (xy 42.886471 -52.310891) (xy 42.816981 -52.405042) (xy 42.741111 -52.494132)
			(xy 42.659229 -52.577729) (xy 42.571732 -52.65543) (xy 42.479042 -52.726857) (xy 42.381609 -52.791665)
			(xy 42.279905 -52.84954) (xy 42.174422 -52.900202) (xy 42.065671 -52.943404) (xy 41.954179 -52.978939)
			(xy 41.840485 -53.006634) (xy 41.725141 -53.026354) (xy 41.608704 -53.038005) (xy 41.491739 -53.04153)
			(xy 41.374812 -53.036912) (xy 41.258489 -53.024173) (xy 41.143334 -53.003375) (xy 41.029905 -52.974618)
			(xy 40.91875 -52.938042) (xy 40.810407 -52.893825) (xy 40.705403 -52.842179) (xy 40.604244 -52.783356)
			(xy 40.507421 -52.71764) (xy 40.415403 -52.645349) (xy 40.328636 -52.566834) (xy 40.247539 -52.482474)
			(xy 40.172506 -52.392679) (xy 40.103899 -52.297883) (xy 40.042051 -52.198544) (xy 39.987262 -52.095145)
			(xy 39.939796 -51.988186) (xy 39.899884 -51.878185) (xy 39.86772 -51.765674) (xy 39.843457 -51.651199)
			(xy 39.827215 -51.535313) (xy 39.819072 -51.418579) (xy 39.818564 -51.36007) (xy 29.24048 -51.36007)
			(xy 29.24048 -52.893484) (xy 29.519874 -52.893484) (xy 29.519874 -52.806584) (xy 29.527892 -52.720055)
			(xy 29.54386 -52.634635) (xy 29.567641 -52.551053) (xy 29.599033 -52.470021) (xy 29.637767 -52.392232)
			(xy 29.683514 -52.318348) (xy 29.735883 -52.249001) (xy 29.794427 -52.184781) (xy 29.858647 -52.126237)
			(xy 29.927994 -52.073868) (xy 30.001878 -52.028121) (xy 30.079667 -51.989387) (xy 30.160699 -51.957995)
			(xy 30.244281 -51.934214) (xy 30.329701 -51.918246) (xy 30.41623 -51.910228) (xy 30.50313 -51.910228)
			(xy 30.589659 -51.918246) (xy 30.675079 -51.934214) (xy 30.758661 -51.957995) (xy 30.839693 -51.989387)
			(xy 30.917482 -52.028121) (xy 30.991366 -52.073868) (xy 31.060713 -52.126237) (xy 31.124933 -52.184781)
			(xy 31.183477 -52.249001) (xy 31.235846 -52.318348) (xy 31.281593 -52.392232) (xy 31.320327 -52.470021)
			(xy 31.351719 -52.551053) (xy 31.3755 -52.634635) (xy 31.391468 -52.720055) (xy 31.399486 -52.806584)
			(xy 31.399988 -52.850034) (xy 31.399486 -52.893484) (xy 34.599874 -52.893484) (xy 34.599874 -52.806584)
			(xy 34.607892 -52.720055) (xy 34.62386 -52.634635) (xy 34.647641 -52.551053) (xy 34.679033 -52.470021)
			(xy 34.717767 -52.392232) (xy 34.763514 -52.318348) (xy 34.815883 -52.249001) (xy 34.874427 -52.184781)
			(xy 34.938647 -52.126237) (xy 35.007994 -52.073868) (xy 35.081878 -52.028121) (xy 35.159667 -51.989387)
			(xy 35.240699 -51.957995) (xy 35.324281 -51.934214) (xy 35.409701 -51.918246) (xy 35.49623 -51.910228)
			(xy 35.58313 -51.910228) (xy 35.669659 -51.918246) (xy 35.755079 -51.934214) (xy 35.838661 -51.957995)
			(xy 35.919693 -51.989387) (xy 35.997482 -52.028121) (xy 36.071366 -52.073868) (xy 36.140713 -52.126237)
			(xy 36.204933 -52.184781) (xy 36.263477 -52.249001) (xy 36.315846 -52.318348) (xy 36.361593 -52.392232)
			(xy 36.400327 -52.470021) (xy 36.431719 -52.551053) (xy 36.4555 -52.634635) (xy 36.471468 -52.720055)
			(xy 36.479486 -52.806584) (xy 36.479988 -52.850034) (xy 36.479486 -52.893484) (xy 36.471468 -52.980013)
			(xy 36.4555 -53.065433) (xy 36.431719 -53.149015) (xy 36.400327 -53.230047) (xy 36.361593 -53.307836)
			(xy 36.315846 -53.38172) (xy 36.263477 -53.451067) (xy 36.204933 -53.515287) (xy 36.140713 -53.573831)
			(xy 36.071366 -53.6262) (xy 35.997482 -53.671947) (xy 35.919693 -53.710681) (xy 35.838661 -53.742073)
			(xy 35.755079 -53.765854) (xy 35.669659 -53.781822) (xy 35.58313 -53.78984) (xy 35.49623 -53.78984)
			(xy 35.409701 -53.781822) (xy 35.324281 -53.765854) (xy 35.240699 -53.742073) (xy 35.159667 -53.710681)
			(xy 35.081878 -53.671947) (xy 35.007994 -53.6262) (xy 34.938647 -53.573831) (xy 34.874427 -53.515287)
			(xy 34.815883 -53.451067) (xy 34.763514 -53.38172) (xy 34.717767 -53.307836) (xy 34.679033 -53.230047)
			(xy 34.647641 -53.149015) (xy 34.62386 -53.065433) (xy 34.607892 -52.980013) (xy 34.599874 -52.893484)
			(xy 31.399486 -52.893484) (xy 31.391468 -52.980013) (xy 31.3755 -53.065433) (xy 31.351719 -53.149015)
			(xy 31.320327 -53.230047) (xy 31.281593 -53.307836) (xy 31.235846 -53.38172) (xy 31.183477 -53.451067)
			(xy 31.124933 -53.515287) (xy 31.060713 -53.573831) (xy 30.991366 -53.6262) (xy 30.917482 -53.671947)
			(xy 30.839693 -53.710681) (xy 30.758661 -53.742073) (xy 30.675079 -53.765854) (xy 30.589659 -53.781822)
			(xy 30.50313 -53.78984) (xy 30.41623 -53.78984) (xy 30.329701 -53.781822) (xy 30.244281 -53.765854)
			(xy 30.160699 -53.742073) (xy 30.079667 -53.710681) (xy 30.001878 -53.671947) (xy 29.927994 -53.6262)
			(xy 29.858647 -53.573831) (xy 29.794427 -53.515287) (xy 29.735883 -53.451067) (xy 29.683514 -53.38172)
			(xy 29.637767 -53.307836) (xy 29.599033 -53.230047) (xy 29.567641 -53.149015) (xy 29.54386 -53.065433)
			(xy 29.527892 -52.980013) (xy 29.519874 -52.893484) (xy 29.24048 -52.893484) (xy 29.24048 -57.398666)
			(xy 80.99247 -57.398666) (xy 80.996541 -57.343044) (xy 81.008667 -57.288607) (xy 81.02859 -57.236516)
			(xy 81.055886 -57.187881) (xy 81.089972 -57.143738) (xy 81.130121 -57.105029) (xy 81.175479 -57.072578)
			(xy 81.225079 -57.047077) (xy 81.277863 -57.02907) (xy 81.332706 -57.01894) (xy 81.38844 -57.016903)
			(xy 81.443877 -57.023003) (xy 81.497834 -57.037109) (xy 81.549163 -57.058921) (xy 81.596769 -57.087975)
			(xy 81.639637 -57.12365) (xy 81.676854 -57.165187) (xy 81.707627 -57.2117) (xy 81.731299 -57.262197)
			(xy 81.747367 -57.315604) (xy 81.755487 -57.37078) (xy 81.755996 -57.398666) (xy 81.755487 -57.426552)
			(xy 81.747367 -57.481728) (xy 81.731299 -57.535135) (xy 81.707627 -57.585632) (xy 81.676854 -57.632145)
			(xy 81.639637 -57.673682) (xy 81.596769 -57.709357) (xy 81.549163 -57.738411) (xy 81.497834 -57.760223)
			(xy 81.443877 -57.774329) (xy 81.38844 -57.780429) (xy 81.332706 -57.778392) (xy 81.277863 -57.768262)
			(xy 81.225079 -57.750255) (xy 81.175479 -57.724754) (xy 81.130121 -57.692303) (xy 81.089972 -57.653594)
			(xy 81.055886 -57.609451) (xy 81.02859 -57.560816) (xy 81.008667 -57.508725) (xy 80.996541 -57.454288)
			(xy 80.99247 -57.398666) (xy 29.24048 -57.398666) (xy 29.24048 -58.88228) (xy 80.412334 -58.88228)
			(xy 80.416405 -58.826658) (xy 80.428531 -58.772221) (xy 80.448454 -58.72013) (xy 80.47575 -58.671495)
			(xy 80.509836 -58.627352) (xy 80.549985 -58.588643) (xy 80.595343 -58.556192) (xy 80.644943 -58.530691)
			(xy 80.697727 -58.512684) (xy 80.75257 -58.502554) (xy 80.808304 -58.500517) (xy 80.863741 -58.506617)
			(xy 80.917698 -58.520723) (xy 80.969027 -58.542535) (xy 81.016633 -58.571589) (xy 81.059501 -58.607264)
			(xy 81.096718 -58.648801) (xy 81.127491 -58.695314) (xy 81.151163 -58.745811) (xy 81.167231 -58.799218)
			(xy 81.170484 -58.82132) (xy 82.094068 -58.82132) (xy 82.098139 -58.765698) (xy 82.110265 -58.711261)
			(xy 82.130188 -58.65917) (xy 82.157484 -58.610535) (xy 82.19157 -58.566392) (xy 82.231719 -58.527683)
			(xy 82.277077 -58.495232) (xy 82.326677 -58.469731) (xy 82.379461 -58.451724) (xy 82.434304 -58.441594)
			(xy 82.490038 -58.439557) (xy 82.545475 -58.445657) (xy 82.599432 -58.459763) (xy 82.650761 -58.481575)
			(xy 82.698367 -58.510629) (xy 82.741235 -58.546304) (xy 82.778452 -58.587841) (xy 82.809225 -58.634354)
			(xy 82.832897 -58.684851) (xy 82.848965 -58.738258) (xy 82.857085 -58.793434) (xy 82.857594 -58.82132)
			(xy 82.857085 -58.849206) (xy 82.848965 -58.904382) (xy 82.840255 -58.933334) (xy 83.703666 -58.933334)
			(xy 83.707737 -58.877712) (xy 83.719863 -58.823275) (xy 83.739786 -58.771184) (xy 83.767082 -58.722549)
			(xy 83.801168 -58.678406) (xy 83.841317 -58.639697) (xy 83.886675 -58.607246) (xy 83.936275 -58.581745)
			(xy 83.989059 -58.563738) (xy 84.043902 -58.553608) (xy 84.099636 -58.551571) (xy 84.155073 -58.557671)
			(xy 84.20903 -58.571777) (xy 84.260359 -58.593589) (xy 84.307965 -58.622643) (xy 84.350833 -58.658318)
			(xy 84.38805 -58.699855) (xy 84.418823 -58.746368) (xy 84.442495 -58.796865) (xy 84.458563 -58.850272)
			(xy 84.466683 -58.905448) (xy 84.467192 -58.933334) (xy 84.466683 -58.96122) (xy 84.458563 -59.016396)
			(xy 84.442495 -59.069803) (xy 84.418823 -59.1203) (xy 84.38805 -59.166813) (xy 84.350833 -59.20835)
			(xy 84.307965 -59.244025) (xy 84.260359 -59.273079) (xy 84.20903 -59.294891) (xy 84.155073 -59.308997)
			(xy 84.099636 -59.315097) (xy 84.043902 -59.31306) (xy 83.989059 -59.30293) (xy 83.936275 -59.284923)
			(xy 83.886675 -59.259422) (xy 83.841317 -59.226971) (xy 83.801168 -59.188262) (xy 83.767082 -59.144119)
			(xy 83.739786 -59.095484) (xy 83.719863 -59.043393) (xy 83.707737 -58.988956) (xy 83.703666 -58.933334)
			(xy 82.840255 -58.933334) (xy 82.832897 -58.957789) (xy 82.809225 -59.008286) (xy 82.778452 -59.054799)
			(xy 82.741235 -59.096336) (xy 82.698367 -59.132011) (xy 82.650761 -59.161065) (xy 82.599432 -59.182877)
			(xy 82.545475 -59.196983) (xy 82.490038 -59.203083) (xy 82.434304 -59.201046) (xy 82.379461 -59.190916)
			(xy 82.326677 -59.172909) (xy 82.277077 -59.147408) (xy 82.231719 -59.114957) (xy 82.19157 -59.076248)
			(xy 82.157484 -59.032105) (xy 82.130188 -58.98347) (xy 82.110265 -58.931379) (xy 82.098139 -58.876942)
			(xy 82.094068 -58.82132) (xy 81.170484 -58.82132) (xy 81.175351 -58.854394) (xy 81.17586 -58.88228)
			(xy 81.175351 -58.910166) (xy 81.167231 -58.965342) (xy 81.151163 -59.018749) (xy 81.127491 -59.069246)
			(xy 81.096718 -59.115759) (xy 81.059501 -59.157296) (xy 81.016633 -59.192971) (xy 80.969027 -59.222025)
			(xy 80.917698 -59.243837) (xy 80.863741 -59.257943) (xy 80.808304 -59.264043) (xy 80.75257 -59.262006)
			(xy 80.697727 -59.251876) (xy 80.644943 -59.233869) (xy 80.595343 -59.208368) (xy 80.549985 -59.175917)
			(xy 80.509836 -59.137208) (xy 80.47575 -59.093065) (xy 80.448454 -59.04443) (xy 80.428531 -58.992339)
			(xy 80.416405 -58.937902) (xy 80.412334 -58.88228) (xy 29.24048 -58.88228) (xy 29.24048 -60.395098)
			(xy 56.695513 -60.395098) (xy 56.6994 -60.340749) (xy 56.710983 -60.287507) (xy 56.730025 -60.236455)
			(xy 56.756138 -60.188633) (xy 56.788792 -60.145014) (xy 56.82732 -60.106486) (xy 56.87094 -60.073834)
			(xy 56.918763 -60.047722) (xy 56.969815 -60.028681) (xy 57.023057 -60.017099) (xy 57.077405 -60.013213)
			(xy 57.131754 -60.017101) (xy 57.184996 -60.028684) (xy 57.236047 -60.047726) (xy 57.283869 -60.07384)
			(xy 57.305956 -60.089796) (xy 57.324968 -60.103392) (xy 57.366851 -60.124124) (xy 57.411819 -60.13685)
			(xy 57.458356 -60.14114) (xy 57.504893 -60.13685) (xy 57.549861 -60.124124) (xy 57.591744 -60.103392)
			(xy 57.610756 -60.089796) (xy 57.632841 -60.073827) (xy 57.68067 -60.047699) (xy 57.731731 -60.028644)
			(xy 57.784984 -60.01705) (xy 57.839345 -60.013154) (xy 57.893706 -60.017034) (xy 57.946963 -60.028612)
			(xy 57.998029 -60.047653) (xy 58.045865 -60.073767) (xy 58.089498 -60.106424) (xy 58.128038 -60.144958)
			(xy 58.160702 -60.188586) (xy 58.186823 -60.236419) (xy 58.205871 -60.287482) (xy 58.217457 -60.340736)
			(xy 58.221346 -60.395098) (xy 58.217458 -60.449459) (xy 58.207954 -60.493148) (xy 79.606138 -60.493148)
			(xy 79.610209 -60.437526) (xy 79.622335 -60.383089) (xy 79.642258 -60.330998) (xy 79.669554 -60.282363)
			(xy 79.70364 -60.23822) (xy 79.743789 -60.199511) (xy 79.789147 -60.16706) (xy 79.838747 -60.141559)
			(xy 79.891531 -60.123552) (xy 79.946374 -60.113422) (xy 80.002108 -60.111385) (xy 80.057545 -60.117485)
			(xy 80.111502 -60.131591) (xy 80.162831 -60.153403) (xy 80.210437 -60.182457) (xy 80.253305 -60.218132)
			(xy 80.290522 -60.259669) (xy 80.321295 -60.306182) (xy 80.344967 -60.356679) (xy 80.361035 -60.410086)
			(xy 80.369155 -60.465262) (xy 80.369548 -60.486798) (xy 81.380328 -60.486798) (xy 81.384399 -60.431176)
			(xy 81.396525 -60.376739) (xy 81.416448 -60.324648) (xy 81.443744 -60.276013) (xy 81.47783 -60.23187)
			(xy 81.517979 -60.193161) (xy 81.563337 -60.16071) (xy 81.612937 -60.135209) (xy 81.665721 -60.117202)
			(xy 81.720564 -60.107072) (xy 81.776298 -60.105035) (xy 81.831735 -60.111135) (xy 81.885692 -60.125241)
			(xy 81.937021 -60.147053) (xy 81.984627 -60.176107) (xy 82.027495 -60.211782) (xy 82.064712 -60.253319)
			(xy 82.095485 -60.299832) (xy 82.119157 -60.350329) (xy 82.135225 -60.403736) (xy 82.143345 -60.458912)
			(xy 82.143854 -60.486798) (xy 82.143345 -60.514684) (xy 82.135225 -60.56986) (xy 82.119157 -60.623267)
			(xy 82.095485 -60.673764) (xy 82.064712 -60.720277) (xy 82.027495 -60.761814) (xy 81.984627 -60.797489)
			(xy 81.937021 -60.826543) (xy 81.885692 -60.848355) (xy 81.831735 -60.862461) (xy 81.776298 -60.868561)
			(xy 81.720564 -60.866524) (xy 81.665721 -60.856394) (xy 81.612937 -60.838387) (xy 81.563337 -60.812886)
			(xy 81.517979 -60.780435) (xy 81.47783 -60.741726) (xy 81.443744 -60.697583) (xy 81.416448 -60.648948)
			(xy 81.396525 -60.596857) (xy 81.384399 -60.54242) (xy 81.380328 -60.486798) (xy 80.369548 -60.486798)
			(xy 80.369664 -60.493148) (xy 80.369155 -60.521034) (xy 80.361035 -60.57621) (xy 80.344967 -60.629617)
			(xy 80.321295 -60.680114) (xy 80.290522 -60.726627) (xy 80.253305 -60.768164) (xy 80.210437 -60.803839)
			(xy 80.162831 -60.832893) (xy 80.111502 -60.854705) (xy 80.057545 -60.868811) (xy 80.002108 -60.874911)
			(xy 79.946374 -60.872874) (xy 79.891531 -60.862744) (xy 79.838747 -60.844737) (xy 79.789147 -60.819236)
			(xy 79.743789 -60.786785) (xy 79.70364 -60.748076) (xy 79.669554 -60.703933) (xy 79.642258 -60.655298)
			(xy 79.622335 -60.603207) (xy 79.610209 -60.54877) (xy 79.606138 -60.493148) (xy 58.207954 -60.493148)
			(xy 58.205873 -60.502714) (xy 58.186825 -60.553777) (xy 58.160704 -60.60161) (xy 58.128041 -60.645238)
			(xy 58.089501 -60.683773) (xy 58.045869 -60.71643) (xy 57.998033 -60.742545) (xy 57.946967 -60.761586)
			(xy 57.893711 -60.773165) (xy 57.839349 -60.777046) (xy 57.784988 -60.773151) (xy 57.731735 -60.761558)
			(xy 57.680675 -60.742503) (xy 57.632845 -60.716376) (xy 57.610756 -60.700412) (xy 57.591744 -60.686816)
			(xy 57.549861 -60.666084) (xy 57.504893 -60.653358) (xy 57.458356 -60.649068) (xy 57.411819 -60.653358)
			(xy 57.366851 -60.666084) (xy 57.324968 -60.686816) (xy 57.305956 -60.700412) (xy 57.283865 -60.716363)
			(xy 57.236043 -60.742476) (xy 57.184991 -60.761518) (xy 57.131749 -60.7731) (xy 57.077401 -60.776987)
			(xy 57.023052 -60.7731) (xy 56.96981 -60.761518) (xy 56.918758 -60.742477) (xy 56.870936 -60.716363)
			(xy 56.827317 -60.68371) (xy 56.788788 -60.645182) (xy 56.756136 -60.601563) (xy 56.730023 -60.55374)
			(xy 56.710982 -60.502688) (xy 56.6994 -60.449446) (xy 56.695513 -60.395098) (xy 29.24048 -60.395098)
			(xy 29.24048 -61.21654) (xy 77.4098 -61.21654) (xy 77.413871 -61.160918) (xy 77.425997 -61.106481)
			(xy 77.44592 -61.05439) (xy 77.473216 -61.005755) (xy 77.507302 -60.961612) (xy 77.547451 -60.922903)
			(xy 77.592809 -60.890452) (xy 77.642409 -60.864951) (xy 77.695193 -60.846944) (xy 77.750036 -60.836814)
			(xy 77.80577 -60.834777) (xy 77.861207 -60.840877) (xy 77.915164 -60.854983) (xy 77.966493 -60.876795)
			(xy 78.014099 -60.905849) (xy 78.056967 -60.941524) (xy 78.094184 -60.983061) (xy 78.124957 -61.029574)
			(xy 78.148629 -61.080071) (xy 78.164697 -61.133478) (xy 78.172817 -61.188654) (xy 78.173326 -61.21654)
			(xy 78.172817 -61.244426) (xy 78.164697 -61.299602) (xy 78.148629 -61.353009) (xy 78.124957 -61.403506)
			(xy 78.094184 -61.450019) (xy 78.056967 -61.491556) (xy 78.014099 -61.527231) (xy 77.966493 -61.556285)
			(xy 77.915164 -61.578097) (xy 77.861207 -61.592203) (xy 77.80577 -61.598303) (xy 77.750036 -61.596266)
			(xy 77.695193 -61.586136) (xy 77.642409 -61.568129) (xy 77.592809 -61.542628) (xy 77.547451 -61.510177)
			(xy 77.507302 -61.471468) (xy 77.473216 -61.427325) (xy 77.44592 -61.37869) (xy 77.425997 -61.326599)
			(xy 77.413871 -61.272162) (xy 77.4098 -61.21654) (xy 29.24048 -61.21654) (xy 29.24048 -62.056264)
			(xy 51.025044 -62.056264) (xy 52.676552 -62.056264) (xy 52.676552 -62.228682) (xy 56.695534 -62.228682)
			(xy 56.699423 -62.174337) (xy 56.711007 -62.121098) (xy 56.73005 -62.07005) (xy 56.756164 -62.022232)
			(xy 56.788818 -61.978616) (xy 56.827346 -61.940092) (xy 56.870964 -61.907443) (xy 56.918785 -61.881334)
			(xy 56.969836 -61.862296) (xy 57.023075 -61.850718) (xy 57.077421 -61.846834) (xy 57.131766 -61.850724)
			(xy 57.185005 -61.862308) (xy 57.236053 -61.881351) (xy 57.283871 -61.907466) (xy 57.305956 -61.923422)
			(xy 57.324968 -61.937018) (xy 57.366851 -61.95775) (xy 57.411819 -61.970476) (xy 57.458356 -61.974766)
			(xy 57.504893 -61.970476) (xy 57.549861 -61.95775) (xy 57.591744 -61.937018) (xy 57.610756 -61.923422)
			(xy 57.632817 -61.907418) (xy 57.680647 -61.881286) (xy 57.73171 -61.862228) (xy 57.784965 -61.850632)
			(xy 57.839329 -61.846733) (xy 57.893694 -61.850612) (xy 57.946954 -61.862188) (xy 57.998023 -61.881227)
			(xy 58.045863 -61.907341) (xy 58.0895 -61.939998) (xy 58.128044 -61.978533) (xy 58.160711 -62.022162)
			(xy 58.186836 -62.069996) (xy 58.205887 -62.121061) (xy 58.217476 -62.174318) (xy 58.221367 -62.228682)
			(xy 58.936509 -62.228682) (xy 58.940399 -62.174331) (xy 58.951984 -62.121087) (xy 58.97103 -62.070034)
			(xy 58.997148 -62.022211) (xy 59.029806 -61.978592) (xy 59.068339 -61.940064) (xy 59.111964 -61.907414)
			(xy 59.159791 -61.881304) (xy 59.210847 -61.862267) (xy 59.264093 -61.85069) (xy 59.318445 -61.846809)
			(xy 59.372796 -61.850703) (xy 59.426039 -61.862292) (xy 59.477091 -61.881341) (xy 59.524912 -61.907462)
			(xy 59.546998 -61.923422) (xy 59.56601 -61.937018) (xy 59.607893 -61.95775) (xy 59.652861 -61.970476)
			(xy 59.699398 -61.974766) (xy 59.745935 -61.970476) (xy 59.790903 -61.95775) (xy 59.832786 -61.937018)
			(xy 59.851798 -61.923422) (xy 59.873858 -61.907421) (xy 59.921686 -61.881296) (xy 59.972744 -61.862244)
			(xy 60.025995 -61.850653) (xy 60.080353 -61.846758) (xy 60.134712 -61.85064) (xy 60.187965 -61.862218)
			(xy 60.239029 -61.881257) (xy 60.286863 -61.90737) (xy 60.330493 -61.940025) (xy 60.369032 -61.978558)
			(xy 60.401694 -62.022183) (xy 60.427816 -62.070012) (xy 60.446864 -62.121072) (xy 60.458451 -62.174324)
			(xy 60.462342 -62.228682) (xy 60.840518 -62.228682) (xy 60.844408 -62.174333) (xy 60.855993 -62.121091)
			(xy 60.875038 -62.07004) (xy 60.901154 -62.022219) (xy 60.93381 -61.978601) (xy 60.972342 -61.940075)
			(xy 61.015964 -61.907425) (xy 61.063789 -61.881315) (xy 61.114843 -61.862278) (xy 61.168086 -61.8507)
			(xy 61.222436 -61.846818) (xy 61.276784 -61.850711) (xy 61.330026 -61.862298) (xy 61.381076 -61.881345)
			(xy 61.428896 -61.907464) (xy 61.450982 -61.923422) (xy 61.469994 -61.937018) (xy 61.511877 -61.95775)
			(xy 61.556845 -61.970476) (xy 61.603382 -61.974766) (xy 61.649919 -61.970476) (xy 61.694887 -61.95775)
			(xy 61.73677 -61.937018) (xy 61.755782 -61.923422) (xy 61.777842 -61.90742) (xy 61.825671 -61.881293)
			(xy 61.876731 -61.862238) (xy 61.929983 -61.850645) (xy 61.984344 -61.846749) (xy 62.038705 -61.850629)
			(xy 62.091961 -61.862206) (xy 62.143027 -61.881246) (xy 62.190863 -61.907359) (xy 62.234496 -61.940015)
			(xy 62.273036 -61.978548) (xy 62.305701 -62.022175) (xy 62.331823 -62.070006) (xy 62.350873 -62.121068)
			(xy 62.362461 -62.174321) (xy 62.366351 -62.228682) (xy 62.362466 -62.283043) (xy 62.350883 -62.336298)
			(xy 62.331838 -62.387361) (xy 62.30572 -62.435195) (xy 62.27306 -62.478824) (xy 62.234523 -62.517361)
			(xy 62.190893 -62.550021) (xy 62.143059 -62.576139) (xy 62.091995 -62.595183) (xy 62.038741 -62.606766)
			(xy 61.98438 -62.610651) (xy 61.930019 -62.60676) (xy 61.876766 -62.595172) (xy 61.825704 -62.576122)
			(xy 61.777873 -62.549999) (xy 61.755782 -62.534038) (xy 61.73677 -62.520442) (xy 61.694887 -62.49971)
			(xy 61.649919 -62.486984) (xy 61.603382 -62.482694) (xy 61.556845 -62.486984) (xy 61.511877 -62.49971)
			(xy 61.469994 -62.520442) (xy 61.450982 -62.534038) (xy 61.428866 -62.549956) (xy 61.381044 -62.57607)
			(xy 61.329991 -62.595112) (xy 61.276749 -62.606695) (xy 61.2224 -62.610582) (xy 61.168051 -62.606694)
			(xy 61.114808 -62.595112) (xy 61.063756 -62.57607) (xy 61.015934 -62.549956) (xy 60.972314 -62.517302)
			(xy 60.933787 -62.478772) (xy 60.901134 -62.435151) (xy 60.875023 -62.387327) (xy 60.855983 -62.336274)
			(xy 60.844403 -62.283031) (xy 60.840518 -62.228682) (xy 60.462342 -62.228682) (xy 60.458456 -62.283041)
			(xy 60.446874 -62.336293) (xy 60.427831 -62.387355) (xy 60.401714 -62.435187) (xy 60.369055 -62.478815)
			(xy 60.33052 -62.517351) (xy 60.286893 -62.55001) (xy 60.239061 -62.576128) (xy 60.188 -62.595172)
			(xy 60.134748 -62.606755) (xy 60.080389 -62.610642) (xy 60.02603 -62.606752) (xy 59.972779 -62.595166)
			(xy 59.921718 -62.576118) (xy 59.873888 -62.549998) (xy 59.851798 -62.534038) (xy 59.832786 -62.520442)
			(xy 59.790903 -62.49971) (xy 59.745935 -62.486984) (xy 59.699398 -62.482694) (xy 59.652861 -62.486984)
			(xy 59.607893 -62.49971) (xy 59.56601 -62.520442) (xy 59.546998 -62.534038) (xy 59.524882 -62.549957)
			(xy 59.477058 -62.576074) (xy 59.426004 -62.595118) (xy 59.37276 -62.606703) (xy 59.318409 -62.610591)
			(xy 59.264058 -62.606705) (xy 59.210813 -62.595123) (xy 59.159758 -62.576081) (xy 59.111933 -62.549967)
			(xy 59.068312 -62.517312) (xy 59.029782 -62.478781) (xy 58.997128 -62.435159) (xy 58.971015 -62.387334)
			(xy 58.951974 -62.336279) (xy 58.940394 -62.283033) (xy 58.936509 -62.228682) (xy 58.221367 -62.228682)
			(xy 58.217481 -62.283047) (xy 58.205897 -62.336304) (xy 58.186851 -62.387372) (xy 58.16073 -62.435208)
			(xy 58.128067 -62.47884) (xy 58.089527 -62.517378) (xy 58.045894 -62.55004) (xy 57.998056 -62.576158)
			(xy 57.946988 -62.595202) (xy 57.89373 -62.606783) (xy 57.839365 -62.610667) (xy 57.785001 -62.606773)
			(xy 57.731745 -62.595182) (xy 57.68068 -62.576129) (xy 57.632847 -62.550002) (xy 57.610756 -62.534038)
			(xy 57.591744 -62.520442) (xy 57.549861 -62.49971) (xy 57.504893 -62.486984) (xy 57.458356 -62.482694)
			(xy 57.411819 -62.486984) (xy 57.366851 -62.49971) (xy 57.324968 -62.520442) (xy 57.305956 -62.534038)
			(xy 57.283841 -62.549954) (xy 57.23602 -62.576064) (xy 57.18497 -62.595102) (xy 57.131731 -62.606681)
			(xy 57.077385 -62.610566) (xy 57.02304 -62.606677) (xy 56.969801 -62.595093) (xy 56.918753 -62.576051)
			(xy 56.870934 -62.549938) (xy 56.827318 -62.517284) (xy 56.788794 -62.478757) (xy 56.756145 -62.435138)
			(xy 56.730035 -62.387317) (xy 56.710997 -62.336267) (xy 56.699418 -62.283028) (xy 56.695534 -62.228682)
			(xy 52.676552 -62.228682) (xy 52.676552 -63.211202) (xy 77.86446 -63.211202) (xy 77.868531 -63.15558)
			(xy 77.880657 -63.101143) (xy 77.90058 -63.049052) (xy 77.927876 -63.000417) (xy 77.961962 -62.956274)
			(xy 78.002111 -62.917565) (xy 78.047469 -62.885114) (xy 78.097069 -62.859613) (xy 78.149853 -62.841606)
			(xy 78.204696 -62.831476) (xy 78.26043 -62.829439) (xy 78.315867 -62.835539) (xy 78.369824 -62.849645)
			(xy 78.421153 -62.871457) (xy 78.468759 -62.900511) (xy 78.511627 -62.936186) (xy 78.548844 -62.977723)
			(xy 78.579617 -63.024236) (xy 78.603289 -63.074733) (xy 78.619357 -63.12814) (xy 78.627477 -63.183316)
			(xy 78.627986 -63.211202) (xy 78.627477 -63.239088) (xy 78.619357 -63.294264) (xy 78.603289 -63.347671)
			(xy 78.579617 -63.398168) (xy 78.548844 -63.444681) (xy 78.511627 -63.486218) (xy 78.468759 -63.521893)
			(xy 78.460932 -63.52667) (xy 81.142076 -63.52667) (xy 81.146147 -63.471048) (xy 81.158273 -63.416611)
			(xy 81.178196 -63.36452) (xy 81.205492 -63.315885) (xy 81.239578 -63.271742) (xy 81.279727 -63.233033)
			(xy 81.325085 -63.200582) (xy 81.374685 -63.175081) (xy 81.427469 -63.157074) (xy 81.482312 -63.146944)
			(xy 81.538046 -63.144907) (xy 81.593483 -63.151007) (xy 81.64744 -63.165113) (xy 81.698769 -63.186925)
			(xy 81.746375 -63.215979) (xy 81.789243 -63.251654) (xy 81.82646 -63.293191) (xy 81.857233 -63.339704)
			(xy 81.880905 -63.390201) (xy 81.896973 -63.443608) (xy 81.905093 -63.498784) (xy 81.905602 -63.52667)
			(xy 81.905093 -63.554556) (xy 81.896973 -63.609732) (xy 81.880905 -63.663139) (xy 81.857233 -63.713636)
			(xy 81.82646 -63.760149) (xy 81.789243 -63.801686) (xy 81.746375 -63.837361) (xy 81.698769 -63.866415)
			(xy 81.64744 -63.888227) (xy 81.593483 -63.902333) (xy 81.538046 -63.908433) (xy 81.482312 -63.906396)
			(xy 81.427469 -63.896266) (xy 81.374685 -63.878259) (xy 81.325085 -63.852758) (xy 81.279727 -63.820307)
			(xy 81.239578 -63.781598) (xy 81.205492 -63.737455) (xy 81.178196 -63.68882) (xy 81.158273 -63.636729)
			(xy 81.146147 -63.582292) (xy 81.142076 -63.52667) (xy 78.460932 -63.52667) (xy 78.421153 -63.550947)
			(xy 78.369824 -63.572759) (xy 78.315867 -63.586865) (xy 78.26043 -63.592965) (xy 78.204696 -63.590928)
			(xy 78.149853 -63.580798) (xy 78.097069 -63.562791) (xy 78.047469 -63.53729) (xy 78.002111 -63.504839)
			(xy 77.961962 -63.46613) (xy 77.927876 -63.421987) (xy 77.90058 -63.373352) (xy 77.880657 -63.321261)
			(xy 77.868531 -63.266824) (xy 77.86446 -63.211202) (xy 52.676552 -63.211202) (xy 52.676552 -63.70828)
			(xy 51.025044 -63.70828) (xy 51.025044 -62.056264) (xy 29.24048 -62.056264) (xy 29.24048 -62.922827)
			(xy 47.525168 -62.922827) (xy 47.525168 -62.841717) (xy 47.533118 -62.760998) (xy 47.548941 -62.681447)
			(xy 47.572486 -62.603831) (xy 47.603525 -62.528895) (xy 47.64176 -62.457363) (xy 47.686822 -62.389923)
			(xy 47.738277 -62.327224) (xy 47.79563 -62.269871) (xy 47.858329 -62.218416) (xy 47.925769 -62.173354)
			(xy 47.997301 -62.135119) (xy 48.072237 -62.10408) (xy 48.149853 -62.080535) (xy 48.229404 -62.064712)
			(xy 48.310123 -62.056762) (xy 48.391233 -62.056762) (xy 48.471952 -62.064712) (xy 48.551503 -62.080535)
			(xy 48.629119 -62.10408) (xy 48.704055 -62.135119) (xy 48.775587 -62.173354) (xy 48.843027 -62.218416)
			(xy 48.905726 -62.269871) (xy 48.963079 -62.327224) (xy 49.014534 -62.389923) (xy 49.059596 -62.457363)
			(xy 49.097831 -62.528895) (xy 49.12887 -62.603831) (xy 49.152415 -62.681447) (xy 49.168238 -62.760998)
			(xy 49.176188 -62.841717) (xy 49.176686 -62.882272) (xy 49.176188 -62.922827) (xy 49.168238 -63.003546)
			(xy 49.152415 -63.083097) (xy 49.12887 -63.160713) (xy 49.097831 -63.235649) (xy 49.059596 -63.307181)
			(xy 49.014534 -63.374621) (xy 48.963079 -63.43732) (xy 48.905726 -63.494673) (xy 48.843027 -63.546128)
			(xy 48.775587 -63.59119) (xy 48.704055 -63.629425) (xy 48.629119 -63.660464) (xy 48.551503 -63.684009)
			(xy 48.471952 -63.699832) (xy 48.391233 -63.707782) (xy 48.310123 -63.707782) (xy 48.229404 -63.699832)
			(xy 48.149853 -63.684009) (xy 48.072237 -63.660464) (xy 47.997301 -63.629425) (xy 47.925769 -63.59119)
			(xy 47.858329 -63.546128) (xy 47.79563 -63.494673) (xy 47.738277 -63.43732) (xy 47.686822 -63.374621)
			(xy 47.64176 -63.307181) (xy 47.603525 -63.235649) (xy 47.572486 -63.160713) (xy 47.548941 -63.083097)
			(xy 47.533118 -63.003546) (xy 47.525168 -62.922827) (xy 29.24048 -62.922827) (xy 29.24048 -64.12972)
			(xy 56.695483 -64.12972) (xy 56.699367 -64.075367) (xy 56.710947 -64.02212) (xy 56.729988 -63.971064)
			(xy 56.7561 -63.923236) (xy 56.788754 -63.879612) (xy 56.827283 -63.841078) (xy 56.870904 -63.808421)
			(xy 56.918729 -63.782303) (xy 56.969784 -63.763258) (xy 57.02303 -63.751673) (xy 57.077383 -63.747783)
			(xy 57.131736 -63.751668) (xy 57.184982 -63.763248) (xy 57.236039 -63.782289) (xy 57.283866 -63.808402)
			(xy 57.305956 -63.824358) (xy 57.324968 -63.837954) (xy 57.366851 -63.858686) (xy 57.411819 -63.871412)
			(xy 57.458356 -63.875702) (xy 57.504893 -63.871412) (xy 57.549861 -63.858686) (xy 57.591744 -63.837954)
			(xy 57.610756 -63.824358) (xy 57.632877 -63.80844) (xy 57.680704 -63.782317) (xy 57.731761 -63.763267)
			(xy 57.785011 -63.751677) (xy 57.839367 -63.747784) (xy 57.893725 -63.751668) (xy 57.946976 -63.763248)
			(xy 57.998037 -63.78229) (xy 58.045868 -63.808405) (xy 58.089495 -63.841062) (xy 58.12803 -63.879596)
			(xy 58.160689 -63.923222) (xy 58.186805 -63.971052) (xy 58.205848 -64.022112) (xy 58.217431 -64.075363)
			(xy 58.221316 -64.12972) (xy 58.936457 -64.12972) (xy 58.940343 -64.075362) (xy 58.951924 -64.022109)
			(xy 58.970967 -63.971047) (xy 58.997084 -63.923215) (xy 59.029742 -63.879587) (xy 59.068276 -63.841051)
			(xy 59.111904 -63.808391) (xy 59.159735 -63.782273) (xy 59.210796 -63.763228) (xy 59.264048 -63.751645)
			(xy 59.318407 -63.747757) (xy 59.372765 -63.751646) (xy 59.426017 -63.763232) (xy 59.477077 -63.782279)
			(xy 59.524907 -63.808398) (xy 59.546998 -63.824358) (xy 59.56601 -63.837954) (xy 59.607893 -63.858686)
			(xy 59.652861 -63.871412) (xy 59.699398 -63.875702) (xy 59.745935 -63.871412) (xy 59.790903 -63.858686)
			(xy 59.832786 -63.837954) (xy 59.851798 -63.824358) (xy 59.873918 -63.808444) (xy 59.921742 -63.782327)
			(xy 59.972796 -63.763283) (xy 60.02604 -63.751698) (xy 60.080391 -63.747809) (xy 60.134743 -63.751696)
			(xy 60.187988 -63.763278) (xy 60.239042 -63.78232) (xy 60.286867 -63.808434) (xy 60.330488 -63.841089)
			(xy 60.369018 -63.87962) (xy 60.401672 -63.923243) (xy 60.427785 -63.971068) (xy 60.446826 -64.022123)
			(xy 60.458406 -64.075369) (xy 60.462291 -64.12972) (xy 60.840467 -64.12972) (xy 60.844352 -64.075364)
			(xy 60.855933 -64.022114) (xy 60.874975 -63.971053) (xy 60.90109 -63.923223) (xy 60.933746 -63.879596)
			(xy 60.972279 -63.841061) (xy 61.015904 -63.808402) (xy 61.063733 -63.782285) (xy 61.114791 -63.76324)
			(xy 61.168041 -63.751655) (xy 61.222397 -63.747767) (xy 61.276754 -63.751654) (xy 61.330004 -63.763238)
			(xy 61.381063 -63.782283) (xy 61.428892 -63.8084) (xy 61.450982 -63.824358) (xy 61.469994 -63.837954)
			(xy 61.511877 -63.858686) (xy 61.556845 -63.871412) (xy 61.603382 -63.875702) (xy 61.649919 -63.871412)
			(xy 61.694887 -63.858686) (xy 61.73677 -63.837954) (xy 61.755782 -63.824358) (xy 61.777902 -63.808442)
			(xy 61.825727 -63.782323) (xy 61.876782 -63.763277) (xy 61.930029 -63.75169) (xy 61.984382 -63.7478)
			(xy 62.038736 -63.751685) (xy 62.091983 -63.763266) (xy 62.14304 -63.782308) (xy 62.190867 -63.808423)
			(xy 62.234491 -63.841079) (xy 62.273023 -63.879611) (xy 62.305678 -63.923235) (xy 62.331793 -63.971062)
			(xy 62.350834 -64.022119) (xy 62.362415 -64.075367) (xy 62.3663 -64.12972) (xy 62.36241 -64.184074)
			(xy 62.350823 -64.23732) (xy 62.331776 -64.288375) (xy 62.305656 -64.3362) (xy 62.272996 -64.37982)
			(xy 62.23446 -64.418348) (xy 62.190833 -64.450999) (xy 62.143003 -64.477109) (xy 62.091944 -64.496145)
			(xy 62.038695 -64.507721) (xy 61.984341 -64.5116) (xy 61.929988 -64.507704) (xy 61.876743 -64.496112)
			(xy 61.82569 -64.47706) (xy 61.777868 -64.450936) (xy 61.755782 -64.434974) (xy 61.73677 -64.421378)
			(xy 61.694887 -64.400646) (xy 61.649919 -64.38792) (xy 61.603382 -64.38363) (xy 61.556845 -64.38792)
			(xy 61.511877 -64.400646) (xy 61.469994 -64.421378) (xy 61.450982 -64.434974) (xy 61.428926 -64.450978)
			(xy 61.3811 -64.477101) (xy 61.330043 -64.49615) (xy 61.276794 -64.50774) (xy 61.222438 -64.511633)
			(xy 61.168081 -64.507751) (xy 61.114831 -64.496172) (xy 61.06377 -64.477132) (xy 61.015938 -64.45102)
			(xy 60.97231 -64.418365) (xy 60.933773 -64.379834) (xy 60.901112 -64.336211) (xy 60.874992 -64.288384)
			(xy 60.855945 -64.237326) (xy 60.844358 -64.184077) (xy 60.840467 -64.12972) (xy 60.462291 -64.12972)
			(xy 60.4584 -64.184072) (xy 60.446814 -64.237316) (xy 60.427768 -64.288369) (xy 60.40165 -64.336192)
			(xy 60.368992 -64.379811) (xy 60.330458 -64.418337) (xy 60.286833 -64.450988) (xy 60.239005 -64.477097)
			(xy 60.187949 -64.496134) (xy 60.134702 -64.50771) (xy 60.08035 -64.511591) (xy 60.026 -64.507696)
			(xy 59.972756 -64.496106) (xy 59.921705 -64.477056) (xy 59.873884 -64.450934) (xy 59.851798 -64.434974)
			(xy 59.832786 -64.421378) (xy 59.790903 -64.400646) (xy 59.745935 -64.38792) (xy 59.699398 -64.38363)
			(xy 59.652861 -64.38792) (xy 59.607893 -64.400646) (xy 59.56601 -64.421378) (xy 59.546998 -64.434974)
			(xy 59.524942 -64.45098) (xy 59.477114 -64.477104) (xy 59.426056 -64.496156) (xy 59.372805 -64.507748)
			(xy 59.318447 -64.511643) (xy 59.264088 -64.507761) (xy 59.210835 -64.496183) (xy 59.159772 -64.477144)
			(xy 59.111938 -64.451031) (xy 59.068307 -64.418376) (xy 59.029768 -64.379844) (xy 58.997106 -64.336219)
			(xy 58.970984 -64.28839) (xy 58.951936 -64.23733) (xy 58.940348 -64.184079) (xy 58.936457 -64.12972)
			(xy 58.221316 -64.12972) (xy 58.217425 -64.184077) (xy 58.205837 -64.237327) (xy 58.186788 -64.288385)
			(xy 58.160666 -64.336213) (xy 58.128003 -64.379835) (xy 58.089464 -64.418365) (xy 58.045834 -64.451017)
			(xy 57.998 -64.477127) (xy 57.946937 -64.496163) (xy 57.893684 -64.507738) (xy 57.839327 -64.511616)
			(xy 57.78497 -64.507717) (xy 57.731722 -64.496122) (xy 57.680666 -64.477066) (xy 57.632843 -64.450938)
			(xy 57.610756 -64.434974) (xy 57.591744 -64.421378) (xy 57.549861 -64.400646) (xy 57.504893 -64.38792)
			(xy 57.458356 -64.38363) (xy 57.411819 -64.38792) (xy 57.366851 -64.400646) (xy 57.324968 -64.421378)
			(xy 57.305956 -64.434974) (xy 57.283901 -64.450976) (xy 57.236076 -64.477094) (xy 57.185022 -64.49614)
			(xy 57.131776 -64.507727) (xy 57.077423 -64.511617) (xy 57.02307 -64.507733) (xy 56.969823 -64.496153)
			(xy 56.918766 -64.477114) (xy 56.870939 -64.451001) (xy 56.827314 -64.418348) (xy 56.78878 -64.379819)
			(xy 56.756122 -64.336198) (xy 56.730005 -64.288374) (xy 56.710959 -64.237319) (xy 56.699373 -64.184073)
			(xy 56.695483 -64.12972) (xy 29.24048 -64.12972) (xy 29.24048 -65.804802) (xy 56.695507 -65.804802)
			(xy 56.699393 -65.750453) (xy 56.710975 -65.69721) (xy 56.730017 -65.646157) (xy 56.75613 -65.598334)
			(xy 56.788784 -65.554714) (xy 56.827312 -65.516185) (xy 56.870932 -65.483531) (xy 56.918756 -65.457418)
			(xy 56.969808 -65.438376) (xy 57.023051 -65.426794) (xy 57.077401 -65.422907) (xy 57.13175 -65.426794)
			(xy 57.184993 -65.438376) (xy 57.236046 -65.457418) (xy 57.283869 -65.483532) (xy 57.305956 -65.499488)
			(xy 57.324968 -65.513084) (xy 57.366851 -65.533816) (xy 57.411819 -65.546542) (xy 57.458356 -65.550832)
			(xy 57.504893 -65.546542) (xy 57.549861 -65.533816) (xy 57.591744 -65.513084) (xy 57.610756 -65.499488)
			(xy 57.632849 -65.48353) (xy 57.680677 -65.457403) (xy 57.731737 -65.438349) (xy 57.784989 -65.426756)
			(xy 57.839349 -65.42286) (xy 57.89371 -65.426741) (xy 57.946965 -65.43832) (xy 57.998031 -65.45736)
			(xy 58.045866 -65.483475) (xy 58.089497 -65.516132) (xy 58.128037 -65.554666) (xy 58.160699 -65.598294)
			(xy 58.18682 -65.646126) (xy 58.205866 -65.697188) (xy 58.217452 -65.750442) (xy 58.22134 -65.804802)
			(xy 58.936481 -65.804802) (xy 58.940369 -65.750447) (xy 58.951953 -65.697199) (xy 58.970997 -65.646141)
			(xy 58.997114 -65.598313) (xy 59.029772 -65.554689) (xy 59.068306 -65.516157) (xy 59.111932 -65.483502)
			(xy 59.159761 -65.457388) (xy 59.21082 -65.438346) (xy 59.264069 -65.426766) (xy 59.318425 -65.422881)
			(xy 59.372779 -65.426773) (xy 59.426027 -65.43836) (xy 59.477084 -65.457408) (xy 59.52491 -65.483528)
			(xy 59.546998 -65.499488) (xy 59.56601 -65.513084) (xy 59.607893 -65.533816) (xy 59.652861 -65.546542)
			(xy 59.699398 -65.550832) (xy 59.745935 -65.546542) (xy 59.790903 -65.533816) (xy 59.832786 -65.513084)
			(xy 59.851798 -65.499488) (xy 59.87389 -65.483533) (xy 59.921715 -65.457413) (xy 59.972771 -65.438365)
			(xy 60.026019 -65.426777) (xy 60.080373 -65.422885) (xy 60.134728 -65.426769) (xy 60.187977 -65.43835)
			(xy 60.239036 -65.457391) (xy 60.286865 -65.483504) (xy 60.330491 -65.516159) (xy 60.369025 -65.554691)
			(xy 60.401682 -65.598315) (xy 60.427799 -65.646142) (xy 60.446843 -65.697199) (xy 60.458427 -65.750448)
			(xy 60.462315 -65.804802) (xy 60.840491 -65.804802) (xy 60.844378 -65.750449) (xy 60.855961 -65.697203)
			(xy 60.875004 -65.646147) (xy 60.90112 -65.598321) (xy 60.933776 -65.554699) (xy 60.972308 -65.516168)
			(xy 61.015932 -65.483513) (xy 61.063759 -65.457399) (xy 61.114815 -65.438358) (xy 61.168062 -65.426776)
			(xy 61.222415 -65.422891) (xy 61.276768 -65.426781) (xy 61.330014 -65.438366) (xy 61.381069 -65.457412)
			(xy 61.428894 -65.48353) (xy 61.450982 -65.499488) (xy 61.469994 -65.513084) (xy 61.511877 -65.533816)
			(xy 61.556845 -65.546542) (xy 61.603382 -65.550832) (xy 61.649919 -65.546542) (xy 61.694887 -65.533816)
			(xy 61.73677 -65.513084) (xy 61.755782 -65.499488) (xy 61.777874 -65.483532) (xy 61.825701 -65.457409)
			(xy 61.876758 -65.438359) (xy 61.930008 -65.426769) (xy 61.984364 -65.422876) (xy 62.038721 -65.426759)
			(xy 62.091973 -65.438338) (xy 62.143034 -65.457379) (xy 62.190865 -65.483493) (xy 62.234493 -65.516149)
			(xy 62.273029 -65.554682) (xy 62.305689 -65.598307) (xy 62.331807 -65.646136) (xy 62.350852 -65.697195)
			(xy 62.362437 -65.750445) (xy 62.366324 -65.804802) (xy 62.362436 -65.859159) (xy 62.350851 -65.912409)
			(xy 62.331805 -65.963469) (xy 62.305686 -66.011297) (xy 62.273026 -66.054922) (xy 62.23449 -66.093454)
			(xy 62.190861 -66.126109) (xy 62.184353 -66.129662) (xy 68.464684 -66.129662) (xy 68.464684 -65.218056)
			(xy 68.465306 -65.181998) (xy 68.475511 -65.110608) (xy 68.485004 -65.075816) (xy 68.490084 -65.05829)
			(xy 68.490084 -64.684148) (xy 69.455792 -64.684148) (xy 69.455792 -65.05829) (xy 69.460872 -65.075816)
			(xy 69.470354 -65.11061) (xy 69.472497 -65.1256) (xy 69.752464 -65.1256) (xy 69.752464 -64.373506)
			(xy 69.752969 -64.34078) (xy 69.761362 -64.275868) (xy 69.778012 -64.212569) (xy 69.802642 -64.151928)
			(xy 69.834846 -64.094946) (xy 69.854064 -64.068452) (xy 69.879464 -64.03467) (xy 69.879464 -64.017652)
			(xy 69.894704 -64.017652) (xy 69.930518 -63.987172) (xy 69.955695 -63.966319) (xy 70.010427 -63.930568)
			(xy 70.069292 -63.902129) (xy 70.131317 -63.881474) (xy 70.195479 -63.868943) (xy 70.260718 -63.864743)
			(xy 70.325957 -63.868943) (xy 70.390119 -63.881474) (xy 70.452144 -63.902129) (xy 70.511009 -63.930568)
			(xy 70.565741 -63.966319) (xy 70.590918 -63.987172) (xy 70.626732 -64.017652) (xy 70.641972 -64.017652)
			(xy 70.641972 -64.03467) (xy 70.667372 -64.068452) (xy 70.684433 -64.091821) (xy 70.713711 -64.141729)
			(xy 70.725792 -64.16802) (xy 70.732842 -64.182733) (xy 70.753165 -64.20824) (xy 70.779296 -64.227754)
			(xy 70.809524 -64.239999) (xy 70.84187 -64.244171) (xy 70.874216 -64.239999) (xy 70.904444 -64.227754)
			(xy 70.930575 -64.20824) (xy 70.950898 -64.182733) (xy 70.957948 -64.16802) (xy 70.970039 -64.141734)
			(xy 70.999319 -64.091828) (xy 71.016368 -64.068452) (xy 71.041768 -64.03467) (xy 71.041768 -64.017652)
			(xy 71.057008 -64.017652) (xy 71.092822 -63.987172) (xy 71.117999 -63.966319) (xy 71.172731 -63.930568)
			(xy 71.231596 -63.902129) (xy 71.293621 -63.881474) (xy 71.357783 -63.868943) (xy 71.423022 -63.864743)
			(xy 71.488261 -63.868943) (xy 71.552423 -63.881474) (xy 71.614448 -63.902129) (xy 71.673313 -63.930568)
			(xy 71.728045 -63.966319) (xy 71.753222 -63.987172) (xy 71.789036 -64.017652) (xy 71.804276 -64.017652)
			(xy 71.804276 -64.029082) (xy 79.612742 -64.029082) (xy 79.616813 -63.97346) (xy 79.628939 -63.919023)
			(xy 79.648862 -63.866932) (xy 79.676158 -63.818297) (xy 79.710244 -63.774154) (xy 79.750393 -63.735445)
			(xy 79.795751 -63.702994) (xy 79.845351 -63.677493) (xy 79.898135 -63.659486) (xy 79.952978 -63.649356)
			(xy 80.008712 -63.647319) (xy 80.064149 -63.653419) (xy 80.118106 -63.667525) (xy 80.169435 -63.689337)
			(xy 80.217041 -63.718391) (xy 80.259909 -63.754066) (xy 80.297126 -63.795603) (xy 80.327899 -63.842116)
			(xy 80.351571 -63.892613) (xy 80.367639 -63.94602) (xy 80.375759 -64.001196) (xy 80.376268 -64.029082)
			(xy 80.375759 -64.056968) (xy 80.367639 -64.112144) (xy 80.351571 -64.165551) (xy 80.327899 -64.216048)
			(xy 80.297126 -64.262561) (xy 80.259909 -64.304098) (xy 80.217041 -64.339773) (xy 80.169435 -64.368827)
			(xy 80.118106 -64.390639) (xy 80.064149 -64.404745) (xy 80.008712 -64.410845) (xy 79.952978 -64.408808)
			(xy 79.898135 -64.398678) (xy 79.845351 -64.380671) (xy 79.795751 -64.35517) (xy 79.750393 -64.322719)
			(xy 79.710244 -64.28401) (xy 79.676158 -64.239867) (xy 79.648862 -64.191232) (xy 79.628939 -64.139141)
			(xy 79.616813 -64.084704) (xy 79.612742 -64.029082) (xy 71.804276 -64.029082) (xy 71.804276 -64.03467)
			(xy 71.829676 -64.068452) (xy 71.848899 -64.094945) (xy 71.881128 -64.151916) (xy 71.905769 -64.212556)
			(xy 71.922414 -64.27586) (xy 71.930786 -64.340778) (xy 71.931276 -64.373506) (xy 71.931276 -64.46012)
			(xy 86.39887 -64.46012) (xy 86.402874 -64.260022) (xy 86.414881 -64.060244) (xy 86.434872 -63.861107)
			(xy 86.462814 -63.662929) (xy 86.498662 -63.466027) (xy 86.54236 -63.270718) (xy 86.593837 -63.077313)
			(xy 86.653011 -62.886123) (xy 86.719787 -62.697453) (xy 86.794059 -62.511606) (xy 86.875706 -62.328879)
			(xy 86.964599 -62.149566) (xy 87.060595 -61.973952) (xy 87.16354 -61.80232) (xy 87.27327 -61.634944)
			(xy 87.389608 -61.472093) (xy 87.512369 -61.314026) (xy 87.641356 -61.160998) (xy 87.776363 -61.013253)
			(xy 87.917172 -60.871027) (xy 88.063559 -60.73455) (xy 88.215289 -60.604038) (xy 88.37212 -60.479702)
			(xy 88.533799 -60.36174) (xy 88.700069 -60.250341) (xy 88.870662 -60.145684) (xy 89.045306 -60.047936)
			(xy 89.223722 -59.957253) (xy 89.405622 -59.873782) (xy 89.590717 -59.797655) (xy 89.778709 -59.728995)
			(xy 89.969298 -59.667911) (xy 90.162178 -59.614501) (xy 90.35704 -59.568852) (xy 90.553573 -59.531035)
			(xy 90.751462 -59.501111) (xy 90.950389 -59.479129) (xy 91.150037 -59.465124) (xy 91.350085 -59.459118)
			(xy 91.550213 -59.46112) (xy 91.750101 -59.471128) (xy 91.949428 -59.489125) (xy 92.147876 -59.515083)
			(xy 92.345126 -59.54896) (xy 92.540863 -59.590702) (xy 92.734773 -59.640241) (xy 92.926546 -59.697499)
			(xy 93.115875 -59.762384) (xy 93.302455 -59.834792) (xy 93.48599 -59.914608) (xy 93.666184 -60.001702)
			(xy 93.842749 -60.095936) (xy 94.015402 -60.197159) (xy 94.183867 -60.305209) (xy 94.347875 -60.419912)
			(xy 94.507162 -60.541086) (xy 94.661473 -60.668535) (xy 94.810561 -60.802056) (xy 94.954188 -60.941436)
			(xy 95.092124 -61.08645) (xy 95.224147 -61.236867) (xy 95.350046 -61.392445) (xy 95.46962 -61.552937)
			(xy 95.582676 -61.718083) (xy 95.689035 -61.887621) (xy 95.788526 -62.061279) (xy 95.880989 -62.238778)
			(xy 95.966276 -62.419834) (xy 96.044251 -62.604158) (xy 96.114788 -62.791454) (xy 96.177776 -62.981422)
			(xy 96.233113 -63.173758) (xy 96.28071 -63.368154) (xy 96.320491 -63.564299) (xy 96.352393 -63.761878)
			(xy 96.376364 -63.960575) (xy 96.392366 -64.160073) (xy 96.400373 -64.360051) (xy 96.400874 -64.46012)
			(xy 96.400373 -64.560189) (xy 96.392366 -64.760167) (xy 96.376364 -64.959665) (xy 96.352393 -65.158362)
			(xy 96.320491 -65.355941) (xy 96.28071 -65.552086) (xy 96.233113 -65.746482) (xy 96.177776 -65.938818)
			(xy 96.114788 -66.128786) (xy 96.044251 -66.316082) (xy 95.966276 -66.500406) (xy 95.880989 -66.681462)
			(xy 95.788526 -66.858961) (xy 95.689035 -67.032619) (xy 95.582676 -67.202157) (xy 95.46962 -67.367303)
			(xy 95.350046 -67.527795) (xy 95.224147 -67.683373) (xy 95.092124 -67.83379) (xy 94.954188 -67.978804)
			(xy 94.810561 -68.118184) (xy 94.661473 -68.251705) (xy 94.507162 -68.379154) (xy 94.347875 -68.500328)
			(xy 94.183867 -68.615031) (xy 94.015402 -68.723081) (xy 93.842749 -68.824304) (xy 93.666184 -68.918538)
			(xy 93.48599 -69.005632) (xy 93.302455 -69.085448) (xy 93.115875 -69.157856) (xy 92.926546 -69.222741)
			(xy 92.734773 -69.279999) (xy 92.540863 -69.329538) (xy 92.345126 -69.37128) (xy 92.147876 -69.405157)
			(xy 91.949428 -69.431115) (xy 91.750101 -69.449112) (xy 91.550213 -69.45912) (xy 91.350085 -69.461122)
			(xy 91.150037 -69.455116) (xy 90.950389 -69.441111) (xy 90.751462 -69.419129) (xy 90.553573 -69.389205)
			(xy 90.35704 -69.351388) (xy 90.162178 -69.305739) (xy 89.969298 -69.252329) (xy 89.778709 -69.191245)
			(xy 89.590717 -69.122585) (xy 89.405622 -69.046458) (xy 89.223722 -68.962987) (xy 89.045306 -68.872304)
			(xy 88.870662 -68.774556) (xy 88.700069 -68.669899) (xy 88.533799 -68.5585) (xy 88.37212 -68.440538)
			(xy 88.215289 -68.316202) (xy 88.063559 -68.18569) (xy 87.917172 -68.049213) (xy 87.776363 -67.906987)
			(xy 87.641356 -67.759242) (xy 87.512369 -67.606214) (xy 87.389608 -67.448147) (xy 87.27327 -67.285296)
			(xy 87.16354 -67.11792) (xy 87.060595 -66.946288) (xy 86.964599 -66.770674) (xy 86.875706 -66.591361)
			(xy 86.794059 -66.408634) (xy 86.719787 -66.222787) (xy 86.653011 -66.034117) (xy 86.593837 -65.842927)
			(xy 86.54236 -65.649522) (xy 86.498662 -65.454213) (xy 86.462814 -65.257311) (xy 86.434872 -65.059133)
			(xy 86.414881 -64.859996) (xy 86.402874 -64.660218) (xy 86.39887 -64.46012) (xy 71.931276 -64.46012)
			(xy 71.931276 -65.182496) (xy 71.930826 -65.214128) (xy 71.922988 -65.276903) (xy 71.90742 -65.338221)
			(xy 71.884364 -65.397133) (xy 71.854175 -65.452728) (xy 71.81732 -65.504147) (xy 71.774369 -65.550595)
			(xy 71.725987 -65.591354) (xy 71.67292 -65.625794) (xy 71.615989 -65.653382) (xy 71.556075 -65.673693)
			(xy 71.494104 -65.686411) (xy 71.431033 -65.69134) (xy 71.367838 -65.688404) (xy 71.305496 -65.677649)
			(xy 71.244971 -65.659241) (xy 71.187198 -65.633464) (xy 71.13307 -65.600716) (xy 71.083424 -65.561505)
			(xy 71.039028 -65.516436) (xy 71.019416 -65.491614) (xy 71.005644 -65.474351) (xy 70.973158 -65.444443)
			(xy 70.93599 -65.420601) (xy 70.89526 -65.403544) (xy 70.852195 -65.393785) (xy 70.808091 -65.391617)
			(xy 70.764276 -65.397107) (xy 70.72207 -65.410089) (xy 70.682744 -65.430172) (xy 70.647481 -65.456751)
			(xy 70.632066 -65.472564) (xy 70.609886 -65.495606) (xy 70.560704 -65.536494) (xy 70.50678 -65.570887)
			(xy 70.448967 -65.598243) (xy 70.388179 -65.618129) (xy 70.325376 -65.630231) (xy 70.261551 -65.634358)
			(xy 70.197712 -65.630445) (xy 70.134869 -65.618553) (xy 70.074015 -65.59887) (xy 70.016111 -65.571707)
			(xy 69.962072 -65.537494) (xy 69.912753 -65.496772) (xy 69.868933 -65.450183) (xy 69.831305 -65.398465)
			(xy 69.800463 -65.342435) (xy 69.776894 -65.282977) (xy 69.760972 -65.221032) (xy 69.752947 -65.157579)
			(xy 69.752464 -65.1256) (xy 69.472497 -65.1256) (xy 69.480558 -65.181999) (xy 69.481192 -65.218056)
			(xy 69.481192 -66.129662) (xy 69.480691 -66.161607) (xy 69.472683 -66.224993) (xy 69.456794 -66.286876)
			(xy 69.433275 -66.34628) (xy 69.402495 -66.402267) (xy 69.364942 -66.453956) (xy 69.321206 -66.50053)
			(xy 69.271978 -66.541255) (xy 69.218033 -66.575489) (xy 69.160224 -66.602692) (xy 69.099461 -66.622435)
			(xy 69.036702 -66.634407) (xy 68.972938 -66.638419) (xy 68.909174 -66.634407) (xy 68.846415 -66.622435)
			(xy 68.785652 -66.602692) (xy 68.727843 -66.575489) (xy 68.673898 -66.541255) (xy 68.62467 -66.50053)
			(xy 68.580934 -66.453956) (xy 68.543381 -66.402267) (xy 68.512601 -66.34628) (xy 68.489082 -66.286876)
			(xy 68.473193 -66.224993) (xy 68.465185 -66.161607) (xy 68.464684 -66.129662) (xy 62.184353 -66.129662)
			(xy 62.143029 -66.152223) (xy 62.091968 -66.171263) (xy 62.038717 -66.182842) (xy 61.984359 -66.186724)
			(xy 61.930003 -66.18283) (xy 61.876754 -66.17124) (xy 61.825696 -66.152189) (xy 61.77787 -66.126065)
			(xy 61.755782 -66.110104) (xy 61.73677 -66.096508) (xy 61.694887 -66.075776) (xy 61.649919 -66.06305)
			(xy 61.603382 -66.05876) (xy 61.556845 -66.06305) (xy 61.511877 -66.075776) (xy 61.469994 -66.096508)
			(xy 61.450982 -66.110104) (xy 61.428898 -66.126068) (xy 61.381073 -66.152186) (xy 61.330019 -66.171232)
			(xy 61.276773 -66.182819) (xy 61.22242 -66.186709) (xy 61.168067 -66.182824) (xy 61.11482 -66.171244)
			(xy 61.063763 -66.152203) (xy 61.015936 -66.12609) (xy 60.972312 -66.093435) (xy 60.933779 -66.054905)
			(xy 60.901123 -66.011283) (xy 60.875006 -65.963457) (xy 60.855963 -65.912402) (xy 60.844379 -65.859155)
			(xy 60.840491 -65.804802) (xy 60.462315 -65.804802) (xy 60.458426 -65.859157) (xy 60.446842 -65.912405)
			(xy 60.427797 -65.963462) (xy 60.40168 -66.01129) (xy 60.369021 -66.054913) (xy 60.330487 -66.093444)
			(xy 60.286861 -66.126098) (xy 60.239032 -66.152211) (xy 60.187973 -66.171252) (xy 60.134723 -66.182831)
			(xy 60.080368 -66.186715) (xy 60.026014 -66.182822) (xy 59.972767 -66.171234) (xy 59.921711 -66.152185)
			(xy 59.873886 -66.126064) (xy 59.851798 -66.110104) (xy 59.832786 -66.096508) (xy 59.790903 -66.075776)
			(xy 59.745935 -66.06305) (xy 59.699398 -66.05876) (xy 59.652861 -66.06305) (xy 59.607893 -66.075776)
			(xy 59.56601 -66.096508) (xy 59.546998 -66.110104) (xy 59.524914 -66.126069) (xy 59.477088 -66.15219)
			(xy 59.426032 -66.171239) (xy 59.372784 -66.182827) (xy 59.318429 -66.186719) (xy 59.264074 -66.182835)
			(xy 59.210825 -66.171255) (xy 59.159765 -66.152214) (xy 59.111936 -66.126101) (xy 59.068309 -66.093446)
			(xy 59.029775 -66.054915) (xy 58.997116 -66.011291) (xy 58.970999 -65.963464) (xy 58.951954 -65.912406)
			(xy 58.94037 -65.859157) (xy 58.936481 -65.804802) (xy 58.22134 -65.804802) (xy 58.217451 -65.859163)
			(xy 58.205865 -65.912416) (xy 58.186818 -65.963479) (xy 58.160696 -66.01131) (xy 58.128033 -66.054937)
			(xy 58.089494 -66.093471) (xy 58.045862 -66.126128) (xy 57.998026 -66.152242) (xy 57.946961 -66.171281)
			(xy 57.893706 -66.182859) (xy 57.839345 -66.18674) (xy 57.784985 -66.182844) (xy 57.731733 -66.17125)
			(xy 57.680673 -66.152196) (xy 57.632845 -66.126068) (xy 57.610756 -66.110104) (xy 57.591744 -66.096508)
			(xy 57.549861 -66.075776) (xy 57.504893 -66.06305) (xy 57.458356 -66.05876) (xy 57.411819 -66.06305)
			(xy 57.366851 -66.075776) (xy 57.324968 -66.096508) (xy 57.305956 -66.110104) (xy 57.283873 -66.126066)
			(xy 57.23605 -66.15218) (xy 57.184998 -66.171222) (xy 57.131755 -66.182805) (xy 57.077405 -66.186693)
			(xy 57.023056 -66.182807) (xy 56.969813 -66.171225) (xy 56.91876 -66.152184) (xy 56.870936 -66.126071)
			(xy 56.827316 -66.093418) (xy 56.788787 -66.05489) (xy 56.756133 -66.01127) (xy 56.730019 -65.963447)
			(xy 56.710977 -65.912395) (xy 56.699394 -65.859152) (xy 56.695507 -65.804802) (xy 29.24048 -65.804802)
			(xy 29.24048 -66.444914) (xy 44.076475 -66.444914) (xy 44.080361 -66.390559) (xy 44.091943 -66.33731)
			(xy 44.110985 -66.286251) (xy 44.1371 -66.238422) (xy 44.169756 -66.194797) (xy 44.208289 -66.156263)
			(xy 44.251913 -66.123606) (xy 44.299741 -66.097489) (xy 44.350799 -66.078446) (xy 44.404048 -66.066862)
			(xy 44.458403 -66.062975) (xy 44.512759 -66.066863) (xy 44.566007 -66.078448) (xy 44.617065 -66.097492)
			(xy 44.664893 -66.12361) (xy 44.686982 -66.139568) (xy 44.705994 -66.153164) (xy 44.747877 -66.173896)
			(xy 44.792845 -66.186622) (xy 44.839382 -66.190912) (xy 44.885919 -66.186622) (xy 44.930887 -66.173896)
			(xy 44.97277 -66.153164) (xy 44.991782 -66.139568) (xy 45.013893 -66.123639) (xy 45.061718 -66.097518)
			(xy 45.112774 -66.078471) (xy 45.166022 -66.066883) (xy 45.220376 -66.062992) (xy 45.274731 -66.066876)
			(xy 45.32798 -66.078457) (xy 45.379038 -66.097499) (xy 45.426867 -66.123613) (xy 45.470492 -66.156269)
			(xy 45.509025 -66.194801) (xy 45.541682 -66.238425) (xy 45.567797 -66.286253) (xy 45.58684 -66.337311)
			(xy 45.598422 -66.39056) (xy 45.602308 -66.444914) (xy 45.598418 -66.499269) (xy 45.586832 -66.552516)
			(xy 45.567786 -66.603573) (xy 45.541666 -66.651399) (xy 45.509006 -66.695021) (xy 45.47047 -66.73355)
			(xy 45.426842 -66.766202) (xy 45.379012 -66.792313) (xy 45.327952 -66.811351) (xy 45.274702 -66.822928)
			(xy 45.220347 -66.826808) (xy 45.165993 -66.822913) (xy 45.112747 -66.811321) (xy 45.061692 -66.79227)
			(xy 45.013869 -66.766146) (xy 44.991782 -66.750184) (xy 44.97277 -66.736588) (xy 44.930887 -66.715856)
			(xy 44.885919 -66.70313) (xy 44.839382 -66.69884) (xy 44.792845 -66.70313) (xy 44.747877 -66.715856)
			(xy 44.705994 -66.736588) (xy 44.686982 -66.750184) (xy 44.664917 -66.766175) (xy 44.617091 -66.792296)
			(xy 44.566035 -66.811344) (xy 44.512787 -66.822933) (xy 44.458432 -66.826825) (xy 44.404077 -66.822942)
			(xy 44.350827 -66.811362) (xy 44.299768 -66.792323) (xy 44.251937 -66.76621) (xy 44.208311 -66.733555)
			(xy 44.169775 -66.695025) (xy 44.137116 -66.651402) (xy 44.110997 -66.603575) (xy 44.091951 -66.552518)
			(xy 44.080365 -66.499269) (xy 44.076475 -66.444914) (xy 29.24048 -66.444914) (xy 29.24048 -67.816019)
			(xy 56.651945 -67.816019) (xy 56.65583 -67.761657) (xy 56.667413 -67.708402) (xy 56.686458 -67.657337)
			(xy 56.712576 -67.609503) (xy 56.745237 -67.565873) (xy 56.783775 -67.527336) (xy 56.827405 -67.494675)
			(xy 56.875239 -67.468557) (xy 56.926304 -67.449513) (xy 56.97956 -67.43793) (xy 57.033921 -67.434045)
			(xy 57.088283 -67.437936) (xy 57.141537 -67.449525) (xy 57.192599 -67.468575) (xy 57.240431 -67.494698)
			(xy 57.262522 -67.51066) (xy 57.281534 -67.524256) (xy 57.323417 -67.544988) (xy 57.368385 -67.557714)
			(xy 57.414922 -67.562004) (xy 57.461459 -67.557714) (xy 57.506427 -67.544988) (xy 57.54831 -67.524256)
			(xy 57.567322 -67.51066) (xy 57.58944 -67.494745) (xy 57.637262 -67.468632) (xy 57.688313 -67.449591)
			(xy 57.741555 -67.438009) (xy 57.795904 -67.434122) (xy 57.850252 -67.43801) (xy 57.903494 -67.449593)
			(xy 57.954545 -67.468635) (xy 58.002367 -67.494749) (xy 58.045985 -67.527403) (xy 58.084512 -67.565932)
			(xy 58.117163 -67.609553) (xy 58.143274 -67.657376) (xy 58.162314 -67.708428) (xy 58.173893 -67.761671)
			(xy 58.177778 -67.816019) (xy 58.893079 -67.816019) (xy 58.896964 -67.761665) (xy 58.908545 -67.708418)
			(xy 58.927586 -67.65736) (xy 58.953699 -67.609532) (xy 58.986353 -67.565907) (xy 59.024884 -67.527374)
			(xy 59.068506 -67.494716) (xy 59.116332 -67.468599) (xy 59.167388 -67.449554) (xy 59.220635 -67.437969)
			(xy 59.274988 -67.434079) (xy 59.329342 -67.437965) (xy 59.38259 -67.449547) (xy 59.433647 -67.468589)
			(xy 59.481474 -67.494703) (xy 59.503564 -67.51066) (xy 59.522576 -67.524256) (xy 59.564459 -67.544988)
			(xy 59.609427 -67.557714) (xy 59.655964 -67.562004) (xy 59.702501 -67.557714) (xy 59.747469 -67.544988)
			(xy 59.789352 -67.524256) (xy 59.808364 -67.51066) (xy 59.830483 -67.49474) (xy 59.878309 -67.468618)
			(xy 59.929366 -67.449568) (xy 59.982615 -67.43798) (xy 60.036971 -67.434088) (xy 60.091327 -67.437971)
			(xy 60.144578 -67.449552) (xy 60.195638 -67.468594) (xy 60.243468 -67.494708) (xy 60.287094 -67.527365)
			(xy 60.325628 -67.565898) (xy 60.358286 -67.609524) (xy 60.384402 -67.657353) (xy 60.403445 -67.708413)
			(xy 60.415027 -67.761663) (xy 60.418912 -67.816019) (xy 60.796929 -67.816019) (xy 60.800815 -67.761654)
			(xy 60.812399 -67.708395) (xy 60.831445 -67.657327) (xy 60.857566 -67.60949) (xy 60.89023 -67.565858)
			(xy 60.928771 -67.527318) (xy 60.972404 -67.494657) (xy 61.020243 -67.468538) (xy 61.071311 -67.449494)
			(xy 61.124571 -67.437913) (xy 61.178936 -67.434029) (xy 61.233301 -67.437923) (xy 61.286558 -67.449515)
			(xy 61.337623 -67.468568) (xy 61.385456 -67.494696) (xy 61.407548 -67.51066) (xy 61.42656 -67.524256)
			(xy 61.468443 -67.544988) (xy 61.513411 -67.557714) (xy 61.559948 -67.562004) (xy 61.606485 -67.557714)
			(xy 61.651453 -67.544988) (xy 61.693336 -67.524256) (xy 61.712348 -67.51066) (xy 61.734465 -67.494747)
			(xy 61.782285 -67.468638) (xy 61.833335 -67.449601) (xy 61.886574 -67.438022) (xy 61.940918 -67.434138)
			(xy 61.995263 -67.438027) (xy 62.048501 -67.449611) (xy 62.099548 -67.468654) (xy 62.147366 -67.494767)
			(xy 62.190981 -67.52742) (xy 62.229505 -67.565948) (xy 62.262153 -67.609566) (xy 62.288262 -67.657386)
			(xy 62.307299 -67.708435) (xy 62.318878 -67.761674) (xy 62.322762 -67.816019) (xy 62.318873 -67.870364)
			(xy 62.307289 -67.923602) (xy 62.288246 -67.974649) (xy 62.262132 -68.022467) (xy 62.229479 -68.066081)
			(xy 62.190952 -68.104605) (xy 62.147334 -68.137254) (xy 62.099513 -68.163362) (xy 62.048464 -68.1824)
			(xy 61.995225 -68.193978) (xy 61.94088 -68.197862) (xy 61.886536 -68.193972) (xy 61.833298 -68.182388)
			(xy 61.78225 -68.163346) (xy 61.734433 -68.137232) (xy 61.712348 -68.121276) (xy 61.693336 -68.10768)
			(xy 61.651453 -68.086948) (xy 61.606485 -68.074222) (xy 61.559948 -68.069932) (xy 61.513411 -68.074222)
			(xy 61.468443 -68.086948) (xy 61.42656 -68.10768) (xy 61.407548 -68.121276) (xy 61.385489 -68.137283)
			(xy 61.337658 -68.163416) (xy 61.286595 -68.182475) (xy 61.233339 -68.194072) (xy 61.178975 -68.197971)
			(xy 61.124609 -68.194093) (xy 61.071348 -68.182517) (xy 61.020278 -68.163478) (xy 60.972437 -68.137364)
			(xy 60.9288 -68.104707) (xy 60.890255 -68.066171) (xy 60.857587 -68.022542) (xy 60.831461 -67.974708)
			(xy 60.81241 -67.923642) (xy 60.80082 -67.870384) (xy 60.796929 -67.816019) (xy 60.418912 -67.816019)
			(xy 60.415022 -67.870375) (xy 60.403434 -67.923624) (xy 60.384386 -67.974682) (xy 60.358265 -68.022508)
			(xy 60.325603 -68.066131) (xy 60.287065 -68.10466) (xy 60.243435 -68.137312) (xy 60.195603 -68.163422)
			(xy 60.144541 -68.182459) (xy 60.091289 -68.194034) (xy 60.036932 -68.197912) (xy 59.982577 -68.194015)
			(xy 59.929329 -68.182421) (xy 59.878274 -68.163366) (xy 59.830451 -68.137239) (xy 59.808364 -68.121276)
			(xy 59.789352 -68.10768) (xy 59.747469 -68.086948) (xy 59.702501 -68.074222) (xy 59.655964 -68.069932)
			(xy 59.609427 -68.074222) (xy 59.564459 -68.086948) (xy 59.522576 -68.10768) (xy 59.503564 -68.121276)
			(xy 59.481507 -68.137276) (xy 59.433682 -68.163395) (xy 59.382626 -68.182442) (xy 59.32938 -68.194029)
			(xy 59.275027 -68.197921) (xy 59.220673 -68.194037) (xy 59.167425 -68.182457) (xy 59.116367 -68.163417)
			(xy 59.068538 -68.137305) (xy 59.024913 -68.104652) (xy 58.986379 -68.066122) (xy 58.95372 -68.0225)
			(xy 58.927602 -67.974675) (xy 58.908556 -67.923619) (xy 58.89697 -67.870373) (xy 58.893079 -67.816019)
			(xy 58.177778 -67.816019) (xy 58.173888 -67.870367) (xy 58.162303 -67.923609) (xy 58.143258 -67.974659)
			(xy 58.117143 -68.02248) (xy 58.084487 -68.066097) (xy 58.045956 -68.104622) (xy 58.002334 -68.137272)
			(xy 57.95451 -68.163381) (xy 57.903457 -68.182418) (xy 57.850214 -68.193995) (xy 57.795865 -68.197878)
			(xy 57.741517 -68.193986) (xy 57.688277 -68.182398) (xy 57.637227 -68.163352) (xy 57.589407 -68.137234)
			(xy 57.567322 -68.121276) (xy 57.54831 -68.10768) (xy 57.506427 -68.086948) (xy 57.461459 -68.074222)
			(xy 57.414922 -68.069932) (xy 57.368385 -68.074222) (xy 57.323417 -68.086948) (xy 57.281534 -68.10768)
			(xy 57.262522 -68.121276) (xy 57.240463 -68.137281) (xy 57.192634 -68.163409) (xy 57.141574 -68.182465)
			(xy 57.088321 -68.194059) (xy 57.03396 -68.197955) (xy 56.979598 -68.194076) (xy 56.926341 -68.182498)
			(xy 56.875274 -68.163459) (xy 56.827437 -68.137346) (xy 56.783804 -68.10469) (xy 56.745262 -68.066156)
			(xy 56.712597 -68.022529) (xy 56.686474 -67.974698) (xy 56.667424 -67.923635) (xy 56.655836 -67.870381)
			(xy 56.651945 -67.816019) (xy 29.24048 -67.816019) (xy 29.24048 -68.278499) (xy 44.076496 -68.278499)
			(xy 44.080384 -68.224147) (xy 44.091967 -68.170901) (xy 44.11101 -68.119846) (xy 44.137126 -68.072021)
			(xy 44.169782 -68.028399) (xy 44.208314 -67.989869) (xy 44.251938 -67.957215) (xy 44.299764 -67.931102)
			(xy 44.35082 -67.912061) (xy 44.404067 -67.900481) (xy 44.458419 -67.896596) (xy 44.512771 -67.900486)
			(xy 44.566016 -67.912072) (xy 44.61707 -67.931118) (xy 44.664894 -67.957236) (xy 44.686982 -67.973194)
			(xy 44.705994 -67.98679) (xy 44.747877 -68.007522) (xy 44.792845 -68.020248) (xy 44.839382 -68.024538)
			(xy 44.885919 -68.020248) (xy 44.930887 -68.007522) (xy 44.97277 -67.98679) (xy 44.991782 -67.973194)
			(xy 45.013869 -67.95723) (xy 45.061696 -67.931106) (xy 45.112754 -67.912055) (xy 45.166003 -67.900465)
			(xy 45.220361 -67.896571) (xy 45.274719 -67.900453) (xy 45.327971 -67.912033) (xy 45.379033 -67.931073)
			(xy 45.426865 -67.957187) (xy 45.470494 -67.989843) (xy 45.50903 -68.028376) (xy 45.541691 -68.072001)
			(xy 45.56781 -68.11983) (xy 45.586856 -68.17089) (xy 45.598441 -68.224141) (xy 45.602329 -68.278499)
			(xy 45.598441 -68.332856) (xy 45.586856 -68.386107) (xy 45.567811 -68.437167) (xy 45.541692 -68.484997)
			(xy 45.509032 -68.528622) (xy 45.470495 -68.567156) (xy 45.426867 -68.599812) (xy 45.379035 -68.625926)
			(xy 45.327973 -68.644967) (xy 45.274721 -68.656546) (xy 45.220363 -68.660429) (xy 45.166006 -68.656536)
			(xy 45.112756 -68.644946) (xy 45.061698 -68.625895) (xy 45.013871 -68.599771) (xy 44.991782 -68.58381)
			(xy 44.97277 -68.570214) (xy 44.930887 -68.549482) (xy 44.885919 -68.536756) (xy 44.839382 -68.532466)
			(xy 44.792845 -68.536756) (xy 44.747877 -68.549482) (xy 44.705994 -68.570214) (xy 44.686982 -68.58381)
			(xy 44.664892 -68.599766) (xy 44.617068 -68.625883) (xy 44.566014 -68.644929) (xy 44.512769 -68.656514)
			(xy 44.458417 -68.660404) (xy 44.404064 -68.656519) (xy 44.350818 -68.644938) (xy 44.299762 -68.625897)
			(xy 44.251936 -68.599784) (xy 44.208312 -68.567129) (xy 44.169781 -68.528599) (xy 44.137125 -68.484977)
			(xy 44.111009 -68.437152) (xy 44.091966 -68.386097) (xy 44.080383 -68.332851) (xy 44.076496 -68.278499)
			(xy 29.24048 -68.278499) (xy 29.24048 -69.706506) (xy 56.651962 -69.706506) (xy 56.65585 -69.652147)
			(xy 56.667434 -69.598894) (xy 56.686479 -69.547833) (xy 56.712598 -69.500002) (xy 56.745259 -69.456375)
			(xy 56.783796 -69.41784) (xy 56.827426 -69.385183) (xy 56.875259 -69.359067) (xy 56.926322 -69.340026)
			(xy 56.979575 -69.328445) (xy 57.033935 -69.324562) (xy 57.088293 -69.328455) (xy 57.141545 -69.340045)
			(xy 57.192604 -69.359096) (xy 57.240433 -69.38522) (xy 57.262522 -69.401182) (xy 57.281534 -69.414778)
			(xy 57.323417 -69.43551) (xy 57.368385 -69.448236) (xy 57.414922 -69.452526) (xy 57.461459 -69.448236)
			(xy 57.506427 -69.43551) (xy 57.54831 -69.414778) (xy 57.567322 -69.401182) (xy 57.589419 -69.385237)
			(xy 57.637242 -69.359122) (xy 57.688296 -69.340078) (xy 57.74154 -69.328493) (xy 57.79589 -69.324605)
			(xy 57.850241 -69.328491) (xy 57.903486 -69.340072) (xy 57.95454 -69.359114) (xy 58.002365 -69.385227)
			(xy 58.045986 -69.417881) (xy 58.084517 -69.456411) (xy 58.117171 -69.500032) (xy 58.143285 -69.547857)
			(xy 58.162327 -69.598911) (xy 58.173909 -69.652155) (xy 58.177795 -69.706506) (xy 58.893097 -69.706506)
			(xy 58.896984 -69.652155) (xy 58.908565 -69.59891) (xy 58.927607 -69.547855) (xy 58.953721 -69.50003)
			(xy 58.986375 -69.456409) (xy 59.024905 -69.417878) (xy 59.068527 -69.385223) (xy 59.116351 -69.359109)
			(xy 59.167406 -69.340067) (xy 59.22065 -69.328484) (xy 59.275002 -69.324597) (xy 59.329353 -69.328485)
			(xy 59.382597 -69.340068) (xy 59.433652 -69.35911) (xy 59.481476 -69.385225) (xy 59.503564 -69.401182)
			(xy 59.522576 -69.414778) (xy 59.564459 -69.43551) (xy 59.609427 -69.448236) (xy 59.655964 -69.452526)
			(xy 59.702501 -69.448236) (xy 59.747469 -69.43551) (xy 59.789352 -69.414778) (xy 59.808364 -69.401182)
			(xy 59.830462 -69.385232) (xy 59.87829 -69.359107) (xy 59.929349 -69.340055) (xy 59.982599 -69.328464)
			(xy 60.036957 -69.32457) (xy 60.091317 -69.328452) (xy 60.14457 -69.340031) (xy 60.195633 -69.359072)
			(xy 60.243466 -69.385187) (xy 60.287096 -69.417843) (xy 60.325633 -69.456377) (xy 60.358294 -69.500003)
			(xy 60.384413 -69.547834) (xy 60.403458 -69.598895) (xy 60.415043 -69.652147) (xy 60.41893 -69.706506)
			(xy 60.796947 -69.706506) (xy 60.800834 -69.652143) (xy 60.81242 -69.598887) (xy 60.831467 -69.547823)
			(xy 60.857588 -69.499989) (xy 60.890252 -69.456359) (xy 60.928792 -69.417823) (xy 60.972425 -69.385165)
			(xy 61.020262 -69.359049) (xy 61.071329 -69.340007) (xy 61.124586 -69.328428) (xy 61.178949 -69.324547)
			(xy 61.233311 -69.328442) (xy 61.286566 -69.340035) (xy 61.337628 -69.35909) (xy 61.385458 -69.385218)
			(xy 61.407548 -69.401182) (xy 61.42656 -69.414778) (xy 61.468443 -69.43551) (xy 61.513411 -69.448236)
			(xy 61.559948 -69.452526) (xy 61.606485 -69.448236) (xy 61.651453 -69.43551) (xy 61.693336 -69.414778)
			(xy 61.712348 -69.401182) (xy 61.734444 -69.38524) (xy 61.782266 -69.359128) (xy 61.833317 -69.340088)
			(xy 61.886558 -69.328506) (xy 61.940905 -69.32462) (xy 61.995252 -69.328508) (xy 62.048493 -69.340091)
			(xy 62.099544 -69.359132) (xy 62.147364 -69.385245) (xy 62.190982 -69.417898) (xy 62.229509 -69.456426)
			(xy 62.262161 -69.500045) (xy 62.288272 -69.547867) (xy 62.307313 -69.598918) (xy 62.318894 -69.652159)
			(xy 62.32278 -69.706506) (xy 62.318892 -69.760853) (xy 62.307309 -69.814094) (xy 62.288267 -69.865144)
			(xy 62.262154 -69.912965) (xy 62.229501 -69.956583) (xy 62.190973 -69.99511) (xy 62.147354 -70.027761)
			(xy 62.099533 -70.053873) (xy 62.048482 -70.072913) (xy 61.995241 -70.084494) (xy 61.940893 -70.08838)
			(xy 61.886546 -70.084492) (xy 61.833305 -70.072909) (xy 61.782255 -70.053867) (xy 61.734434 -70.027754)
			(xy 61.712348 -70.011798) (xy 61.693336 -69.998202) (xy 61.651453 -69.97747) (xy 61.606485 -69.964744)
			(xy 61.559948 -69.960454) (xy 61.513411 -69.964744) (xy 61.468443 -69.97747) (xy 61.42656 -69.998202)
			(xy 61.407548 -70.011798) (xy 61.385468 -70.027776) (xy 61.337639 -70.053905) (xy 61.286577 -70.072961)
			(xy 61.233323 -70.084556) (xy 61.178961 -70.088453) (xy 61.124598 -70.084574) (xy 61.071341 -70.072996)
			(xy 61.020273 -70.053956) (xy 60.972435 -70.027842) (xy 60.928801 -69.995185) (xy 60.890259 -69.95665)
			(xy 60.857595 -69.913022) (xy 60.831472 -69.865188) (xy 60.812423 -69.814124) (xy 60.800836 -69.760869)
			(xy 60.796947 -69.706506) (xy 60.41893 -69.706506) (xy 60.415041 -69.760865) (xy 60.403455 -69.814116)
			(xy 60.384408 -69.865177) (xy 60.358287 -69.913007) (xy 60.325625 -69.956632) (xy 60.287086 -69.995165)
			(xy 60.243456 -70.02782) (xy 60.195622 -70.053933) (xy 60.144558 -70.072972) (xy 60.091305 -70.08455)
			(xy 60.036945 -70.08843) (xy 59.982587 -70.084534) (xy 59.929337 -70.072941) (xy 59.878279 -70.053888)
			(xy 59.830452 -70.027761) (xy 59.808364 -70.011798) (xy 59.789352 -69.998202) (xy 59.747469 -69.97747)
			(xy 59.702501 -69.964744) (xy 59.655964 -69.960454) (xy 59.609427 -69.964744) (xy 59.564459 -69.97747)
			(xy 59.522576 -69.998202) (xy 59.503564 -70.011798) (xy 59.481486 -70.027768) (xy 59.433662 -70.053885)
			(xy 59.382609 -70.072929) (xy 59.329365 -70.084514) (xy 59.275014 -70.088403) (xy 59.220662 -70.084518)
			(xy 59.167417 -70.072937) (xy 59.116362 -70.053896) (xy 59.068537 -70.027783) (xy 59.024914 -69.99513)
			(xy 58.986383 -69.9566) (xy 58.953728 -69.91298) (xy 58.927612 -69.865156) (xy 58.908569 -69.814102)
			(xy 58.896985 -69.760857) (xy 58.893097 -69.706506) (xy 58.177795 -69.706506) (xy 58.173907 -69.760857)
			(xy 58.162323 -69.814101) (xy 58.14328 -69.865154) (xy 58.117164 -69.912978) (xy 58.084509 -69.956598)
			(xy 58.045977 -69.995127) (xy 58.002355 -70.027779) (xy 57.954529 -70.053891) (xy 57.903474 -70.072931)
			(xy 57.850229 -70.084511) (xy 57.795878 -70.088395) (xy 57.741528 -70.084505) (xy 57.688284 -70.072919)
			(xy 57.637232 -70.053874) (xy 57.589409 -70.027756) (xy 57.567322 -70.011798) (xy 57.54831 -69.998202)
			(xy 57.506427 -69.97747) (xy 57.461459 -69.964744) (xy 57.414922 -69.960454) (xy 57.368385 -69.964744)
			(xy 57.323417 -69.97747) (xy 57.281534 -69.998202) (xy 57.262522 -70.011798) (xy 57.240443 -70.027773)
			(xy 57.192615 -70.053899) (xy 57.141556 -70.072951) (xy 57.088305 -70.084543) (xy 57.033947 -70.088438)
			(xy 56.979587 -70.084556) (xy 56.926333 -70.072978) (xy 56.87527 -70.053938) (xy 56.827436 -70.027824)
			(xy 56.783805 -69.995168) (xy 56.745267 -69.956634) (xy 56.712605 -69.913009) (xy 56.686484 -69.865178)
			(xy 56.667437 -69.814117) (xy 56.655851 -69.760865) (xy 56.651962 -69.706506) (xy 29.24048 -69.706506)
			(xy 29.24048 -70.179377) (xy 44.076525 -70.179377) (xy 44.080415 -70.125029) (xy 44.092001 -70.071788)
			(xy 44.111045 -70.020738) (xy 44.137162 -69.972918) (xy 44.169818 -69.929302) (xy 44.208349 -69.890777)
			(xy 44.251971 -69.858128) (xy 44.299796 -69.832019) (xy 44.350849 -69.812983) (xy 44.404092 -69.801406)
			(xy 44.458441 -69.797525) (xy 44.512788 -69.801418) (xy 44.566029 -69.813006) (xy 44.617078 -69.832053)
			(xy 44.664897 -69.858171) (xy 44.686982 -69.87413) (xy 44.705994 -69.887726) (xy 44.747877 -69.908458)
			(xy 44.792845 -69.921184) (xy 44.839382 -69.925474) (xy 44.885919 -69.921184) (xy 44.930887 -69.908458)
			(xy 44.97277 -69.887726) (xy 44.991782 -69.87413) (xy 45.013835 -69.858117) (xy 45.061664 -69.831989)
			(xy 45.112725 -69.812933) (xy 45.165978 -69.801339) (xy 45.220339 -69.797442) (xy 45.274701 -69.801322)
			(xy 45.327958 -69.812899) (xy 45.379025 -69.831938) (xy 45.426862 -69.858051) (xy 45.470496 -69.890707)
			(xy 45.509038 -69.92924) (xy 45.541703 -69.972867) (xy 45.567827 -70.020699) (xy 45.586877 -70.071762)
			(xy 45.598466 -70.125016) (xy 45.602358 -70.179377) (xy 45.598473 -70.233739) (xy 45.58689 -70.286995)
			(xy 45.567846 -70.33806) (xy 45.541728 -70.385894) (xy 45.509068 -70.429525) (xy 45.470531 -70.468063)
			(xy 45.426901 -70.500724) (xy 45.379066 -70.526843) (xy 45.328002 -70.545888) (xy 45.274746 -70.557472)
			(xy 45.220385 -70.561358) (xy 45.166023 -70.557467) (xy 45.112769 -70.545879) (xy 45.061705 -70.52683)
			(xy 45.013873 -70.500707) (xy 44.991782 -70.484746) (xy 44.97277 -70.47115) (xy 44.930887 -70.450418)
			(xy 44.885919 -70.437692) (xy 44.839382 -70.433402) (xy 44.792845 -70.437692) (xy 44.747877 -70.450418)
			(xy 44.705994 -70.47115) (xy 44.686982 -70.484746) (xy 44.664859 -70.500653) (xy 44.617037 -70.526766)
			(xy 44.565985 -70.545807) (xy 44.512743 -70.557389) (xy 44.458395 -70.561275) (xy 44.404047 -70.557387)
			(xy 44.350805 -70.545804) (xy 44.299754 -70.526762) (xy 44.251933 -70.500648) (xy 44.208315 -70.467994)
			(xy 44.169788 -70.429464) (xy 44.137137 -70.385844) (xy 44.111027 -70.33802) (xy 44.091988 -70.286968)
			(xy 44.080409 -70.233726) (xy 44.076525 -70.179377) (xy 29.24048 -70.179377) (xy 29.24048 -71.854619)
			(xy 44.076469 -71.854619) (xy 44.080354 -71.800263) (xy 44.091935 -71.747013) (xy 44.110977 -71.695953)
			(xy 44.137092 -71.648123) (xy 44.169748 -71.604497) (xy 44.208281 -71.565962) (xy 44.251906 -71.533303)
			(xy 44.299734 -71.507186) (xy 44.350793 -71.488141) (xy 44.404043 -71.476557) (xy 44.458399 -71.472669)
			(xy 44.512755 -71.476556) (xy 44.566004 -71.48814) (xy 44.617063 -71.507184) (xy 44.664892 -71.533302)
			(xy 44.686982 -71.54926) (xy 44.705994 -71.562856) (xy 44.747877 -71.583588) (xy 44.792845 -71.596314)
			(xy 44.839382 -71.600604) (xy 44.885919 -71.596314) (xy 44.930887 -71.583588) (xy 44.97277 -71.562856)
			(xy 44.991782 -71.54926) (xy 45.013901 -71.533342) (xy 45.061725 -71.507222) (xy 45.112781 -71.488175)
			(xy 45.166027 -71.476589) (xy 45.220381 -71.472698) (xy 45.274735 -71.476583) (xy 45.327983 -71.488165)
			(xy 45.37904 -71.507206) (xy 45.426867 -71.533321) (xy 45.470491 -71.565977) (xy 45.509023 -71.604509)
			(xy 45.541679 -71.648133) (xy 45.567794 -71.69596) (xy 45.586835 -71.747018) (xy 45.586957 -71.74758)
			(xy 56.651998 -71.74758) (xy 56.655888 -71.693226) (xy 56.667475 -71.639979) (xy 56.686522 -71.588923)
			(xy 56.712642 -71.541098) (xy 56.745303 -71.497478) (xy 56.783839 -71.45895) (xy 56.827467 -71.426298)
			(xy 56.875297 -71.400189) (xy 56.926357 -71.381152) (xy 56.979606 -71.369577) (xy 57.033961 -71.365698)
			(xy 57.088314 -71.369594) (xy 57.14156 -71.381186) (xy 57.192614 -71.400239) (xy 57.240436 -71.426364)
			(xy 57.262522 -71.442326) (xy 57.281534 -71.455922) (xy 57.323417 -71.476654) (xy 57.368385 -71.48938)
			(xy 57.414922 -71.49367) (xy 57.461459 -71.48938) (xy 57.506427 -71.476654) (xy 57.54831 -71.455922)
			(xy 57.567322 -71.442326) (xy 57.589378 -71.426322) (xy 57.637204 -71.4002) (xy 57.688261 -71.381151)
			(xy 57.741509 -71.369562) (xy 57.795864 -71.365669) (xy 57.85022 -71.369552) (xy 57.903471 -71.381131)
			(xy 57.954531 -71.400171) (xy 58.002362 -71.426283) (xy 58.045989 -71.458937) (xy 58.084526 -71.497468)
			(xy 58.117186 -71.541091) (xy 58.143306 -71.588918) (xy 58.162353 -71.639975) (xy 58.17394 -71.693224)
			(xy 58.177831 -71.74758) (xy 58.893132 -71.74758) (xy 58.897022 -71.693234) (xy 58.908607 -71.639995)
			(xy 58.92765 -71.588946) (xy 58.953765 -71.541127) (xy 58.986419 -71.497512) (xy 59.024948 -71.458988)
			(xy 59.068568 -71.426339) (xy 59.11639 -71.40023) (xy 59.167441 -71.381193) (xy 59.220682 -71.369615)
			(xy 59.275028 -71.365732) (xy 59.329374 -71.369623) (xy 59.382613 -71.381209) (xy 59.433661 -71.400253)
			(xy 59.481479 -71.426369) (xy 59.503564 -71.442326) (xy 59.522576 -71.455922) (xy 59.564459 -71.476654)
			(xy 59.609427 -71.48938) (xy 59.655964 -71.49367) (xy 59.702501 -71.48938) (xy 59.747469 -71.476654)
			(xy 59.789352 -71.455922) (xy 59.808364 -71.442326) (xy 59.830421 -71.426317) (xy 59.878251 -71.400186)
			(xy 59.929313 -71.381129) (xy 59.982568 -71.369533) (xy 60.036931 -71.365635) (xy 60.091295 -71.369513)
			(xy 60.144554 -71.38109) (xy 60.195623 -71.400129) (xy 60.243463 -71.426243) (xy 60.287099 -71.458899)
			(xy 60.325642 -71.497434) (xy 60.358309 -71.541062) (xy 60.384434 -71.588895) (xy 60.403485 -71.63996)
			(xy 60.415074 -71.693216) (xy 60.418965 -71.74758) (xy 60.796982 -71.74758) (xy 60.800873 -71.693222)
			(xy 60.812461 -71.639972) (xy 60.83151 -71.588913) (xy 60.857632 -71.541085) (xy 60.890295 -71.497462)
			(xy 60.928835 -71.458932) (xy 60.972466 -71.42628) (xy 61.020301 -71.40017) (xy 61.071364 -71.381134)
			(xy 61.124617 -71.369559) (xy 61.178976 -71.365682) (xy 61.233333 -71.369581) (xy 61.286581 -71.381176)
			(xy 61.337637 -71.400233) (xy 61.385461 -71.426362) (xy 61.407548 -71.442326) (xy 61.42656 -71.455922)
			(xy 61.468443 -71.476654) (xy 61.513411 -71.48938) (xy 61.559948 -71.49367) (xy 61.606485 -71.48938)
			(xy 61.651453 -71.476654) (xy 61.693336 -71.455922) (xy 61.712348 -71.442326) (xy 61.734403 -71.426324)
			(xy 61.782227 -71.400207) (xy 61.833282 -71.381161) (xy 61.886527 -71.369575) (xy 61.940879 -71.365685)
			(xy 61.995231 -71.369569) (xy 62.048478 -71.381149) (xy 62.099534 -71.400189) (xy 62.147361 -71.426301)
			(xy 62.190985 -71.458954) (xy 62.229518 -71.497483) (xy 62.262176 -71.541104) (xy 62.288294 -71.588928)
			(xy 62.307339 -71.639982) (xy 62.318925 -71.693228) (xy 62.322815 -71.74758) (xy 62.318931 -71.801932)
			(xy 62.30735 -71.855178) (xy 62.28831 -71.906235) (xy 62.262198 -71.954062) (xy 62.229545 -71.997686)
			(xy 62.191016 -72.036219) (xy 62.147396 -72.068877) (xy 62.099571 -72.094994) (xy 62.048517 -72.114039)
			(xy 61.995272 -72.125625) (xy 61.94092 -72.129515) (xy 61.886567 -72.12563) (xy 61.833321 -72.11405)
			(xy 61.782264 -72.09501) (xy 61.734437 -72.068898) (xy 61.712348 -72.052942) (xy 61.693336 -72.039346)
			(xy 61.651453 -72.018614) (xy 61.606485 -72.005888) (xy 61.559948 -72.001598) (xy 61.513411 -72.005888)
			(xy 61.468443 -72.018614) (xy 61.42656 -72.039346) (xy 61.407548 -72.052942) (xy 61.385427 -72.06886)
			(xy 61.3376 -72.094984) (xy 61.286542 -72.114035) (xy 61.233292 -72.125625) (xy 61.178935 -72.129518)
			(xy 61.124577 -72.125635) (xy 61.071325 -72.114055) (xy 61.020264 -72.095013) (xy 60.972432 -72.068898)
			(xy 60.928804 -72.036241) (xy 60.890269 -71.997707) (xy 60.85761 -71.95408) (xy 60.831493 -71.90625)
			(xy 60.812449 -71.855189) (xy 60.800867 -71.801937) (xy 60.796982 -71.74758) (xy 60.418965 -71.74758)
			(xy 60.41508 -71.801943) (xy 60.403496 -71.855201) (xy 60.384451 -71.906268) (xy 60.358331 -71.954104)
			(xy 60.325669 -71.997735) (xy 60.28713 -72.036274) (xy 60.243497 -72.068935) (xy 60.195661 -72.095054)
			(xy 60.144594 -72.114098) (xy 60.091336 -72.125681) (xy 60.036972 -72.129565) (xy 59.982608 -72.125673)
			(xy 59.929352 -72.114083) (xy 59.878288 -72.095031) (xy 59.830455 -72.068905) (xy 59.808364 -72.052942)
			(xy 59.789352 -72.039346) (xy 59.747469 -72.018614) (xy 59.702501 -72.005888) (xy 59.655964 -72.001598)
			(xy 59.609427 -72.005888) (xy 59.564459 -72.018614) (xy 59.522576 -72.039346) (xy 59.503564 -72.052942)
			(xy 59.481445 -72.068853) (xy 59.433624 -72.094964) (xy 59.382574 -72.114003) (xy 59.329333 -72.125583)
			(xy 59.274987 -72.129468) (xy 59.220641 -72.125579) (xy 59.167402 -72.113995) (xy 59.116353 -72.094953)
			(xy 59.068534 -72.068839) (xy 59.024918 -72.036186) (xy 58.986393 -71.997657) (xy 58.953743 -71.954038)
			(xy 58.927633 -71.906217) (xy 58.908595 -71.855166) (xy 58.897016 -71.801926) (xy 58.893132 -71.74758)
			(xy 58.177831 -71.74758) (xy 58.173946 -71.801936) (xy 58.162365 -71.855185) (xy 58.143323 -71.906245)
			(xy 58.117208 -71.954075) (xy 58.084553 -71.997701) (xy 58.04602 -72.036236) (xy 58.002396 -72.068895)
			(xy 57.954568 -72.095012) (xy 57.90351 -72.114058) (xy 57.850261 -72.125642) (xy 57.795905 -72.129531)
			(xy 57.741549 -72.125644) (xy 57.6883 -72.11406) (xy 57.637241 -72.095017) (xy 57.589412 -72.0689)
			(xy 57.567322 -72.052942) (xy 57.54831 -72.039346) (xy 57.506427 -72.018614) (xy 57.461459 -72.005888)
			(xy 57.414922 -72.001598) (xy 57.368385 -72.005888) (xy 57.323417 -72.018614) (xy 57.281534 -72.039346)
			(xy 57.262522 -72.052942) (xy 57.240401 -72.068858) (xy 57.192576 -72.094978) (xy 57.141521 -72.114025)
			(xy 57.088274 -72.125612) (xy 57.03392 -72.129502) (xy 56.979566 -72.125618) (xy 56.926318 -72.114036)
			(xy 56.87526 -72.094995) (xy 56.827432 -72.06888) (xy 56.783808 -72.036224) (xy 56.745276 -71.997691)
			(xy 56.71262 -71.954067) (xy 56.686505 -71.90624) (xy 56.667464 -71.855182) (xy 56.655882 -71.801934)
			(xy 56.651998 -71.74758) (xy 45.586957 -71.74758) (xy 45.598417 -71.800265) (xy 45.602302 -71.854619)
			(xy 45.598411 -71.908973) (xy 45.586825 -71.962219) (xy 45.567778 -72.013275) (xy 45.541658 -72.0611)
			(xy 45.508998 -72.10472) (xy 45.470462 -72.143248) (xy 45.426835 -72.1759) (xy 45.379005 -72.20201)
			(xy 45.327946 -72.221046) (xy 45.274697 -72.232622) (xy 45.220343 -72.236502) (xy 45.165989 -72.232606)
			(xy 45.112744 -72.221014) (xy 45.061691 -72.201962) (xy 45.013868 -72.175838) (xy 44.991782 -72.159876)
			(xy 44.97277 -72.14628) (xy 44.930887 -72.125548) (xy 44.885919 -72.112822) (xy 44.839382 -72.108532)
			(xy 44.792845 -72.112822) (xy 44.747877 -72.125548) (xy 44.705994 -72.14628) (xy 44.686982 -72.159876)
			(xy 44.664924 -72.175878) (xy 44.617098 -72.202) (xy 44.566041 -72.221049) (xy 44.512793 -72.232638)
			(xy 44.458437 -72.236531) (xy 44.404081 -72.232649) (xy 44.35083 -72.22107) (xy 44.299769 -72.20203)
			(xy 44.251938 -72.175918) (xy 44.20831 -72.143263) (xy 44.169773 -72.104732) (xy 44.137113 -72.061109)
			(xy 44.110993 -72.013282) (xy 44.091946 -71.962224) (xy 44.080359 -71.908975) (xy 44.076469 -71.854619)
			(xy 29.24048 -71.854619) (xy 29.24048 -73.865676) (xy 44.032987 -73.865676) (xy 44.036878 -73.811319)
			(xy 44.048466 -73.75807) (xy 44.067516 -73.707012) (xy 44.093638 -73.659185) (xy 44.126301 -73.615563)
			(xy 44.164841 -73.577034) (xy 44.208472 -73.544382) (xy 44.256306 -73.518273) (xy 44.307369 -73.499237)
			(xy 44.360622 -73.487663) (xy 44.414979 -73.483787) (xy 44.469335 -73.487686) (xy 44.522583 -73.499282)
			(xy 44.573638 -73.518339) (xy 44.621462 -73.544468) (xy 44.643548 -73.560432) (xy 44.66256 -73.574028)
			(xy 44.704443 -73.59476) (xy 44.749411 -73.607486) (xy 44.795948 -73.611776) (xy 44.842485 -73.607486)
			(xy 44.887453 -73.59476) (xy 44.929336 -73.574028) (xy 44.948348 -73.560432) (xy 44.970398 -73.544422)
			(xy 45.018222 -73.518304) (xy 45.069277 -73.499258) (xy 45.122523 -73.487671) (xy 45.176875 -73.48378)
			(xy 45.231228 -73.487664) (xy 45.284476 -73.499244) (xy 45.335533 -73.518283) (xy 45.383361 -73.544395)
			(xy 45.426986 -73.577048) (xy 45.46552 -73.615577) (xy 45.496925 -73.657524) (xy 56.651938 -73.657524)
			(xy 56.655823 -73.603161) (xy 56.667406 -73.549905) (xy 56.68645 -73.498839) (xy 56.712568 -73.451004)
			(xy 56.745229 -73.407372) (xy 56.783767 -73.368834) (xy 56.827397 -73.336172) (xy 56.875232 -73.310053)
			(xy 56.926298 -73.291008) (xy 56.979554 -73.279424) (xy 57.033917 -73.275538) (xy 57.088279 -73.279429)
			(xy 57.141534 -73.291017) (xy 57.192598 -73.310067) (xy 57.24043 -73.33619) (xy 57.262522 -73.352152)
			(xy 57.281534 -73.365748) (xy 57.323417 -73.38648) (xy 57.368385 -73.399206) (xy 57.414922 -73.403496)
			(xy 57.461459 -73.399206) (xy 57.506427 -73.38648) (xy 57.54831 -73.365748) (xy 57.567322 -73.352152)
			(xy 57.589447 -73.336248) (xy 57.637269 -73.310136) (xy 57.68832 -73.291096) (xy 57.741561 -73.279515)
			(xy 57.795908 -73.275629) (xy 57.850256 -73.279517) (xy 57.903496 -73.2911) (xy 57.954547 -73.310143)
			(xy 58.002367 -73.336257) (xy 58.045984 -73.368911) (xy 58.08451 -73.40744) (xy 58.117161 -73.45106)
			(xy 58.143271 -73.498883) (xy 58.162309 -73.549935) (xy 58.173888 -73.603176) (xy 58.177771 -73.657524)
			(xy 58.893073 -73.657524) (xy 58.896957 -73.603169) (xy 58.908537 -73.54992) (xy 58.927578 -73.498862)
			(xy 58.953691 -73.451033) (xy 58.986345 -73.407407) (xy 59.024876 -73.368872) (xy 59.068499 -73.336213)
			(xy 59.116325 -73.310095) (xy 59.167382 -73.291049) (xy 59.220629 -73.279463) (xy 59.274984 -73.275573)
			(xy 59.329338 -73.279458) (xy 59.382587 -73.29104) (xy 59.433645 -73.310081) (xy 59.481474 -73.336195)
			(xy 59.503564 -73.352152) (xy 59.522576 -73.365748) (xy 59.564459 -73.38648) (xy 59.609427 -73.399206)
			(xy 59.655964 -73.403496) (xy 59.702501 -73.399206) (xy 59.747469 -73.38648) (xy 59.789352 -73.365748)
			(xy 59.808364 -73.352152) (xy 59.830491 -73.336243) (xy 59.878316 -73.310122) (xy 59.929373 -73.291073)
			(xy 59.98262 -73.279485) (xy 60.036975 -73.275594) (xy 60.091331 -73.279478) (xy 60.14458 -73.291059)
			(xy 60.195639 -73.310101) (xy 60.243468 -73.336216) (xy 60.287093 -73.368873) (xy 60.325627 -73.407406)
			(xy 60.358283 -73.451031) (xy 60.384398 -73.49886) (xy 60.40344 -73.549919) (xy 60.415022 -73.603168)
			(xy 60.418906 -73.657524) (xy 60.796923 -73.657524) (xy 60.800808 -73.603158) (xy 60.812392 -73.549898)
			(xy 60.831438 -73.498829) (xy 60.857558 -73.450991) (xy 60.890222 -73.407357) (xy 60.928763 -73.368817)
			(xy 60.972397 -73.336154) (xy 61.020236 -73.310034) (xy 61.071305 -73.290989) (xy 61.124565 -73.279407)
			(xy 61.178931 -73.275523) (xy 61.233297 -73.279416) (xy 61.286555 -73.291007) (xy 61.337621 -73.310061)
			(xy 61.385456 -73.336188) (xy 61.407548 -73.352152) (xy 61.42656 -73.365748) (xy 61.468443 -73.38648)
			(xy 61.513411 -73.399206) (xy 61.559948 -73.403496) (xy 61.606485 -73.399206) (xy 61.651453 -73.38648)
			(xy 61.693336 -73.365748) (xy 61.712348 -73.352152) (xy 61.734473 -73.33625) (xy 61.782292 -73.310142)
			(xy 61.833341 -73.291106) (xy 61.886579 -73.279528) (xy 61.940923 -73.275644) (xy 61.995267 -73.279534)
			(xy 62.048504 -73.291119) (xy 62.09955 -73.310162) (xy 62.147367 -73.336275) (xy 62.19098 -73.368928)
			(xy 62.229503 -73.407456) (xy 62.26215 -73.451073) (xy 62.288258 -73.498893) (xy 62.307295 -73.549942)
			(xy 62.318872 -73.60318) (xy 62.322756 -73.657524) (xy 62.318866 -73.711868) (xy 62.307281 -73.765104)
			(xy 62.288238 -73.816151) (xy 62.262124 -73.863967) (xy 62.229471 -73.907581) (xy 62.190944 -73.946103)
			(xy 62.147326 -73.978751) (xy 62.099506 -74.004858) (xy 62.048458 -74.023895) (xy 61.995219 -74.035473)
			(xy 61.940875 -74.039356) (xy 61.886532 -74.035465) (xy 61.833295 -74.023881) (xy 61.782249 -74.004838)
			(xy 61.734432 -73.978724) (xy 61.712348 -73.962768) (xy 61.693336 -73.949172) (xy 61.651453 -73.92844)
			(xy 61.606485 -73.915714) (xy 61.559948 -73.911424) (xy 61.513411 -73.915714) (xy 61.468443 -73.92844)
			(xy 61.42656 -73.949172) (xy 61.407548 -73.962768) (xy 61.385496 -73.978786) (xy 61.337665 -74.00492)
			(xy 61.286601 -74.023979) (xy 61.233345 -74.035577) (xy 61.178979 -74.039477) (xy 61.124613 -74.0356)
			(xy 61.071351 -74.024024) (xy 61.020279 -74.004985) (xy 60.972437 -73.978872) (xy 60.928799 -73.946215)
			(xy 60.890253 -73.907679) (xy 60.857584 -73.86405) (xy 60.831457 -73.816215) (xy 60.812405 -73.765148)
			(xy 60.800815 -73.71189) (xy 60.796923 -73.657524) (xy 60.418906 -73.657524) (xy 60.415015 -73.711879)
			(xy 60.403427 -73.765127) (xy 60.384379 -73.816183) (xy 60.358257 -73.864009) (xy 60.325595 -73.90763)
			(xy 60.287057 -73.946158) (xy 60.243428 -73.97881) (xy 60.195596 -74.004919) (xy 60.144534 -74.023954)
			(xy 60.091283 -74.035529) (xy 60.036927 -74.039406) (xy 59.982573 -74.035508) (xy 59.929327 -74.023913)
			(xy 59.878272 -74.004858) (xy 59.83045 -73.978731) (xy 59.808364 -73.962768) (xy 59.789352 -73.949172)
			(xy 59.747469 -73.92844) (xy 59.702501 -73.915714) (xy 59.655964 -73.911424) (xy 59.609427 -73.915714)
			(xy 59.564459 -73.92844) (xy 59.522576 -73.949172) (xy 59.503564 -73.962768) (xy 59.481514 -73.978779)
			(xy 59.433689 -74.004899) (xy 59.382633 -74.023947) (xy 59.329386 -74.035535) (xy 59.275032 -74.039427)
			(xy 59.220677 -74.035544) (xy 59.167428 -74.023965) (xy 59.116369 -74.004925) (xy 59.068539 -73.978813)
			(xy 59.024912 -73.94616) (xy 58.986377 -73.90763) (xy 58.953717 -73.864008) (xy 58.927598 -73.816182)
			(xy 58.908551 -73.765126) (xy 58.896964 -73.711878) (xy 58.893073 -73.657524) (xy 58.177771 -73.657524)
			(xy 58.173881 -73.711871) (xy 58.162295 -73.765111) (xy 58.143251 -73.816161) (xy 58.117135 -73.86398)
			(xy 58.084479 -73.907596) (xy 58.045948 -73.94612) (xy 58.002327 -73.978769) (xy 57.954503 -74.004877)
			(xy 57.90345 -74.023913) (xy 57.850208 -74.03549) (xy 57.79586 -74.039371) (xy 57.741514 -74.035479)
			(xy 57.688274 -74.023891) (xy 57.637225 -74.004844) (xy 57.589407 -73.978726) (xy 57.567322 -73.962768)
			(xy 57.54831 -73.949172) (xy 57.506427 -73.92844) (xy 57.461459 -73.915714) (xy 57.414922 -73.911424)
			(xy 57.368385 -73.915714) (xy 57.323417 -73.92844) (xy 57.281534 -73.949172) (xy 57.262522 -73.962768)
			(xy 57.240471 -73.978784) (xy 57.192641 -74.004913) (xy 57.14158 -74.023969) (xy 57.088326 -74.035564)
			(xy 57.033965 -74.039462) (xy 56.979601 -74.035583) (xy 56.926344 -74.024006) (xy 56.875276 -74.004967)
			(xy 56.827438 -73.978854) (xy 56.783803 -73.946198) (xy 56.74526 -73.907664) (xy 56.712594 -73.864037)
			(xy 56.68647 -73.816205) (xy 56.667419 -73.765141) (xy 56.65583 -73.711886) (xy 56.651938 -73.657524)
			(xy 45.496925 -73.657524) (xy 45.498178 -73.659198) (xy 45.524296 -73.707023) (xy 45.543343 -73.758078)
			(xy 45.554929 -73.811323) (xy 45.55882 -73.865676) (xy 45.554936 -73.920029) (xy 45.543356 -73.973276)
			(xy 45.524316 -74.024334) (xy 45.498204 -74.072161) (xy 45.465551 -74.115786) (xy 45.427022 -74.15432)
			(xy 45.383401 -74.186979) (xy 45.335577 -74.213097) (xy 45.284522 -74.232143) (xy 45.231276 -74.243729)
			(xy 45.176923 -74.24762) (xy 45.12257 -74.243736) (xy 45.069323 -74.232156) (xy 45.018266 -74.213116)
			(xy 44.970438 -74.187004) (xy 44.948348 -74.171048) (xy 44.929336 -74.157452) (xy 44.887453 -74.13672)
			(xy 44.842485 -74.123994) (xy 44.795948 -74.119704) (xy 44.749411 -74.123994) (xy 44.704443 -74.13672)
			(xy 44.66256 -74.157452) (xy 44.643548 -74.171048) (xy 44.621421 -74.186958) (xy 44.573595 -74.213081)
			(xy 44.522537 -74.232131) (xy 44.469288 -74.243721) (xy 44.414931 -74.247613) (xy 44.360574 -74.24373)
			(xy 44.307323 -74.232149) (xy 44.256262 -74.213107) (xy 44.208432 -74.186992) (xy 44.164805 -74.154335)
			(xy 44.12627 -74.115801) (xy 44.093612 -74.072175) (xy 44.067496 -74.024344) (xy 44.048453 -73.973284)
			(xy 44.036871 -73.920033) (xy 44.032987 -73.865676) (xy 29.24048 -73.865676) (xy 29.24048 -75.756323)
			(xy 44.032924 -75.756323) (xy 44.03681 -75.701957) (xy 44.048393 -75.648697) (xy 44.067439 -75.597629)
			(xy 44.09356 -75.549791) (xy 44.126224 -75.506157) (xy 44.164765 -75.467617) (xy 44.208399 -75.434955)
			(xy 44.256237 -75.408835) (xy 44.307307 -75.389791) (xy 44.360566 -75.378208) (xy 44.414933 -75.374324)
			(xy 44.469298 -75.378218) (xy 44.522556 -75.389809) (xy 44.573622 -75.408862) (xy 44.621456 -75.43499)
			(xy 44.643548 -75.450954) (xy 44.66256 -75.46455) (xy 44.704443 -75.485282) (xy 44.749411 -75.498008)
			(xy 44.795948 -75.502298) (xy 44.842485 -75.498008) (xy 44.887453 -75.485282) (xy 44.929336 -75.46455)
			(xy 44.948348 -75.450954) (xy 44.970471 -75.435049) (xy 45.018291 -75.408941) (xy 45.069339 -75.389904)
			(xy 45.122578 -75.378326) (xy 45.176922 -75.374443) (xy 45.231266 -75.378333) (xy 45.284503 -75.389917)
			(xy 45.33555 -75.40896) (xy 45.383366 -75.435073) (xy 45.42698 -75.467726) (xy 45.465503 -75.506254)
			(xy 45.498151 -75.549871) (xy 45.524259 -75.597691) (xy 45.543296 -75.64874) (xy 45.554874 -75.701979)
			(xy 45.558757 -75.756323) (xy 45.554867 -75.810667) (xy 45.543283 -75.863904) (xy 45.52424 -75.91495)
			(xy 45.498126 -75.962767) (xy 45.465473 -76.006381) (xy 45.426946 -76.044904) (xy 45.383328 -76.077551)
			(xy 45.335508 -76.103659) (xy 45.284459 -76.122696) (xy 45.231221 -76.134274) (xy 45.176876 -76.138157)
			(xy 45.122533 -76.134267) (xy 45.069296 -76.122683) (xy 45.018249 -76.10364) (xy 44.970432 -76.077526)
			(xy 44.948348 -76.06157) (xy 44.929336 -76.047974) (xy 44.887453 -76.027242) (xy 44.842485 -76.014516)
			(xy 44.795948 -76.010226) (xy 44.749411 -76.014516) (xy 44.704443 -76.027242) (xy 44.66256 -76.047974)
			(xy 44.643548 -76.06157) (xy 44.621494 -76.077585) (xy 44.573663 -76.103719) (xy 44.5226 -76.122778)
			(xy 44.469343 -76.134376) (xy 44.414978 -76.138276) (xy 44.360612 -76.134398) (xy 44.30735 -76.122822)
			(xy 44.256279 -76.103784) (xy 44.208437 -76.07767) (xy 44.164799 -76.045013) (xy 44.126253 -76.006477)
			(xy 44.093585 -75.962848) (xy 44.067458 -75.915013) (xy 44.048406 -75.863947) (xy 44.036816 -75.810688)
			(xy 44.032924 -75.756323) (xy 29.24048 -75.756323) (xy 29.24048 -77.797396) (xy 44.03296 -77.797396)
			(xy 44.036848 -77.743036) (xy 44.048435 -77.689782) (xy 44.067482 -77.638719) (xy 44.093604 -77.590887)
			(xy 44.126267 -77.54726) (xy 44.164808 -77.508727) (xy 44.20844 -77.47607) (xy 44.256276 -77.449956)
			(xy 44.307342 -77.430917) (xy 44.360598 -77.419339) (xy 44.414959 -77.41546) (xy 44.469319 -77.419356)
			(xy 44.522571 -77.43095) (xy 44.573631 -77.450005) (xy 44.621459 -77.476134) (xy 44.643548 -77.492098)
			(xy 44.66256 -77.505694) (xy 44.704443 -77.526426) (xy 44.749411 -77.539152) (xy 44.795948 -77.543442)
			(xy 44.842485 -77.539152) (xy 44.887453 -77.526426) (xy 44.929336 -77.505694) (xy 44.948348 -77.492098)
			(xy 44.970429 -77.476134) (xy 45.018252 -77.45002) (xy 45.069304 -77.430978) (xy 45.122547 -77.419395)
			(xy 45.176896 -77.415507) (xy 45.231245 -77.419394) (xy 45.284488 -77.430976) (xy 45.33554 -77.450017)
			(xy 45.383363 -77.476129) (xy 45.426983 -77.508782) (xy 45.465513 -77.547311) (xy 45.498166 -77.59093)
			(xy 45.52428 -77.638753) (xy 45.543322 -77.689805) (xy 45.554905 -77.743047) (xy 45.558793 -77.797396)
			(xy 45.554906 -77.851745) (xy 45.543324 -77.904988) (xy 45.524283 -77.956041) (xy 45.49817 -78.003864)
			(xy 45.465517 -78.047484) (xy 45.426989 -78.086013) (xy 45.383369 -78.118667) (xy 45.335547 -78.14478)
			(xy 45.284494 -78.163822) (xy 45.231252 -78.175405) (xy 45.176903 -78.179293) (xy 45.122554 -78.175406)
			(xy 45.069311 -78.163824) (xy 45.018259 -78.144783) (xy 44.970435 -78.11867) (xy 44.948348 -78.102714)
			(xy 44.929336 -78.089118) (xy 44.887453 -78.068386) (xy 44.842485 -78.05566) (xy 44.795948 -78.05137)
			(xy 44.749411 -78.05566) (xy 44.704443 -78.068386) (xy 44.66256 -78.089118) (xy 44.643548 -78.102714)
			(xy 44.621453 -78.11867) (xy 44.573625 -78.144798) (xy 44.522564 -78.163852) (xy 44.469312 -78.175445)
			(xy 44.414952 -78.17934) (xy 44.36059 -78.17546) (xy 44.307335 -78.163881) (xy 44.25627 -78.144841)
			(xy 44.208434 -78.118726) (xy 44.164802 -78.086069) (xy 44.126263 -78.047534) (xy 44.0936 -78.003907)
			(xy 44.067479 -77.956074) (xy 44.048433 -77.905011) (xy 44.036847 -77.851757) (xy 44.03296 -77.797396)
			(xy 29.24048 -77.797396) (xy 29.24048 -78.300072) (xy 74.398638 -78.300072) (xy 74.402655 -78.130007)
			(xy 74.4147 -77.960322) (xy 74.434744 -77.791394) (xy 74.462744 -77.623602) (xy 74.498636 -77.457319)
			(xy 74.542341 -77.292917) (xy 74.593761 -77.130762) (xy 74.652781 -76.971216) (xy 74.71927 -76.814636)
			(xy 74.793079 -76.66137) (xy 74.874043 -76.511761) (xy 74.961983 -76.366142) (xy 75.056701 -76.224838)
			(xy 75.157986 -76.088165) (xy 75.265613 -75.956428) (xy 75.379341 -75.82992) (xy 75.498916 -75.708924)
			(xy 75.624071 -75.59371) (xy 75.754528 -75.484535) (xy 75.889996 -75.381643) (xy 76.030171 -75.285263)
			(xy 76.174741 -75.19561) (xy 76.323384 -75.112884) (xy 76.475767 -75.03727) (xy 76.631552 -74.968936)
			(xy 76.790389 -74.908036) (xy 76.951925 -74.854705) (xy 77.1158 -74.809061) (xy 77.281647 -74.771208)
			(xy 77.449097 -74.741229) (xy 77.617776 -74.719191) (xy 77.787307 -74.705143) (xy 77.957313 -74.699117)
			(xy 78.127413 -74.701126) (xy 78.297229 -74.711165) (xy 78.466382 -74.729213) (xy 78.634493 -74.755229)
			(xy 78.801188 -74.789155) (xy 78.966095 -74.830915) (xy 79.128846 -74.880417) (xy 79.289077 -74.937548)
			(xy 79.446432 -75.002183) (xy 79.600559 -75.074177) (xy 79.751114 -75.153369) (xy 79.897762 -75.239582)
			(xy 80.040174 -75.332625) (xy 80.178034 -75.432289) (xy 80.311033 -75.538352) (xy 80.438875 -75.650578)
			(xy 80.561274 -75.768716) (xy 80.677958 -75.892502) (xy 80.788667 -76.021661) (xy 80.893152 -76.155904)
			(xy 80.991181 -76.294931) (xy 81.082535 -76.438432) (xy 81.167011 -76.586087) (xy 81.244419 -76.737567)
			(xy 81.314587 -76.892534) (xy 81.377359 -77.050641) (xy 81.432595 -77.211536) (xy 81.48017 -77.37486)
			(xy 81.51998 -77.540249) (xy 81.551935 -77.707333) (xy 81.575963 -77.87574) (xy 81.592012 -78.045093)
			(xy 81.600046 -78.215016) (xy 81.600548 -78.300072) (xy 81.600046 -78.385128) (xy 81.592012 -78.555051)
			(xy 81.575963 -78.724404) (xy 81.551935 -78.892811) (xy 81.51998 -79.059895) (xy 81.48017 -79.225284)
			(xy 81.47814 -79.232252) (xy 91.514928 -79.232252) (xy 91.518999 -79.17663) (xy 91.531125 -79.122193)
			(xy 91.551048 -79.070102) (xy 91.578344 -79.021467) (xy 91.61243 -78.977324) (xy 91.652579 -78.938615)
			(xy 91.697937 -78.906164) (xy 91.747537 -78.880663) (xy 91.800321 -78.862656) (xy 91.855164 -78.852526)
			(xy 91.910898 -78.850489) (xy 91.966335 -78.856589) (xy 92.020292 -78.870695) (xy 92.071621 -78.892507)
			(xy 92.119227 -78.921561) (xy 92.162095 -78.957236) (xy 92.199312 -78.998773) (xy 92.230085 -79.045286)
			(xy 92.253757 -79.095783) (xy 92.269825 -79.14919) (xy 92.277945 -79.204366) (xy 92.278454 -79.232252)
			(xy 92.277945 -79.260138) (xy 92.269825 -79.315314) (xy 92.253757 -79.368721) (xy 92.230085 -79.419218)
			(xy 92.199312 -79.465731) (xy 92.162095 -79.507268) (xy 92.119227 -79.542943) (xy 92.071621 -79.571997)
			(xy 92.020292 -79.593809) (xy 91.966335 -79.607915) (xy 91.910898 -79.614015) (xy 91.855164 -79.611978)
			(xy 91.800321 -79.601848) (xy 91.747537 -79.583841) (xy 91.697937 -79.55834) (xy 91.652579 -79.525889)
			(xy 91.61243 -79.48718) (xy 91.578344 -79.443037) (xy 91.551048 -79.394402) (xy 91.531125 -79.342311)
			(xy 91.518999 -79.287874) (xy 91.514928 -79.232252) (xy 81.47814 -79.232252) (xy 81.432595 -79.388608)
			(xy 81.377359 -79.549503) (xy 81.314587 -79.70761) (xy 81.244419 -79.862577) (xy 81.167011 -80.014057)
			(xy 81.082535 -80.161712) (xy 80.991181 -80.305213) (xy 80.893152 -80.44424) (xy 80.788667 -80.578483)
			(xy 80.677958 -80.707642) (xy 80.561274 -80.831428) (xy 80.438875 -80.949566) (xy 80.311033 -81.061792)
			(xy 80.178034 -81.167855) (xy 80.040174 -81.267519) (xy 79.897762 -81.360562) (xy 79.751114 -81.446775)
			(xy 79.600559 -81.525967) (xy 79.446432 -81.597961) (xy 79.289077 -81.662596) (xy 79.128846 -81.719727)
			(xy 78.966095 -81.769229) (xy 78.801188 -81.810989) (xy 78.634493 -81.844915) (xy 78.466382 -81.870931)
			(xy 78.297229 -81.888979) (xy 78.127413 -81.899018) (xy 77.957313 -81.901027) (xy 77.787307 -81.895001)
			(xy 77.617776 -81.880953) (xy 77.449097 -81.858915) (xy 77.281647 -81.828936) (xy 77.1158 -81.791083)
			(xy 76.951925 -81.745439) (xy 76.790389 -81.692108) (xy 76.631552 -81.631208) (xy 76.475767 -81.562874)
			(xy 76.323384 -81.48726) (xy 76.174741 -81.404534) (xy 76.030171 -81.314881) (xy 75.889996 -81.218501)
			(xy 75.754528 -81.115609) (xy 75.624071 -81.006434) (xy 75.498916 -80.89122) (xy 75.379341 -80.770224)
			(xy 75.265613 -80.643716) (xy 75.157986 -80.511979) (xy 75.056701 -80.375306) (xy 74.961983 -80.234002)
			(xy 74.874043 -80.088383) (xy 74.793079 -79.938774) (xy 74.71927 -79.785508) (xy 74.652781 -79.628928)
			(xy 74.593761 -79.469382) (xy 74.542341 -79.307227) (xy 74.498636 -79.142825) (xy 74.462744 -78.976542)
			(xy 74.434744 -78.80875) (xy 74.4147 -78.639822) (xy 74.402655 -78.470137) (xy 74.398638 -78.300072)
			(xy 29.24048 -78.300072) (xy 29.24048 -79.707181) (xy 44.03298 -79.707181) (xy 44.036871 -79.652823)
			(xy 44.048459 -79.599573) (xy 44.067508 -79.548514) (xy 44.09363 -79.500686) (xy 44.126293 -79.457062)
			(xy 44.164833 -79.418532) (xy 44.208464 -79.385879) (xy 44.256299 -79.359769) (xy 44.307363 -79.340733)
			(xy 44.360616 -79.329158) (xy 44.414975 -79.32528) (xy 44.469332 -79.329179) (xy 44.52258 -79.340775)
			(xy 44.573637 -79.359831) (xy 44.621461 -79.38596) (xy 44.643548 -79.401924) (xy 44.66256 -79.41552)
			(xy 44.704443 -79.436252) (xy 44.749411 -79.448978) (xy 44.795948 -79.453268) (xy 44.842485 -79.448978)
			(xy 44.887453 -79.436252) (xy 44.929336 -79.41552) (xy 44.948348 -79.401924) (xy 44.970405 -79.385925)
			(xy 45.018229 -79.359808) (xy 45.069283 -79.340762) (xy 45.122528 -79.329177) (xy 45.17688 -79.325287)
			(xy 45.231232 -79.329171) (xy 45.284478 -79.340751) (xy 45.335535 -79.359791) (xy 45.383361 -79.385903)
			(xy 45.426985 -79.418556) (xy 45.465518 -79.457085) (xy 45.498175 -79.500706) (xy 45.524293 -79.54853)
			(xy 45.543338 -79.599584) (xy 45.554923 -79.652829) (xy 45.558813 -79.707181) (xy 45.554929 -79.761533)
			(xy 45.543349 -79.814779) (xy 45.524309 -79.865835) (xy 45.498196 -79.913662) (xy 45.465543 -79.957286)
			(xy 45.427014 -79.995819) (xy 45.383394 -80.028476) (xy 45.33557 -80.054593) (xy 45.284515 -80.073638)
			(xy 45.23127 -80.085223) (xy 45.176918 -80.089113) (xy 45.122566 -80.085229) (xy 45.06932 -80.073648)
			(xy 45.018264 -80.054608) (xy 44.970437 -80.028496) (xy 44.948348 -80.01254) (xy 44.929336 -79.998944)
			(xy 44.887453 -79.978212) (xy 44.842485 -79.965486) (xy 44.795948 -79.961196) (xy 44.749411 -79.965486)
			(xy 44.704443 -79.978212) (xy 44.66256 -79.998944) (xy 44.643548 -80.01254) (xy 44.621429 -80.028461)
			(xy 44.573602 -80.054585) (xy 44.522544 -80.073636) (xy 44.469294 -80.085226) (xy 44.414936 -80.08912)
			(xy 44.360578 -80.085237) (xy 44.307326 -80.073657) (xy 44.256264 -80.054615) (xy 44.208432 -80.0285)
			(xy 44.164804 -79.995843) (xy 44.126268 -79.957309) (xy 44.093609 -79.913682) (xy 44.067492 -79.865851)
			(xy 44.048448 -79.81479) (xy 44.036866 -79.761539) (xy 44.03298 -79.707181) (xy 29.24048 -79.707181)
			(xy 29.24048 -82.935318) (xy 70.884288 -82.935318) (xy 70.884288 -81.962752) (xy 70.884901 -81.930595)
			(xy 70.893031 -81.866796) (xy 70.909142 -81.804532) (xy 70.932978 -81.744798) (xy 70.964157 -81.688546)
			(xy 71.002181 -81.636676) (xy 71.046444 -81.590016) (xy 71.096238 -81.54931) (xy 71.150769 -81.51521)
			(xy 71.209164 -81.48826) (xy 71.270493 -81.46889) (xy 71.333774 -81.457409) (xy 71.397998 -81.454001)
			(xy 71.46214 -81.45872) (xy 71.525174 -81.471491) (xy 71.586093 -81.49211) (xy 71.643926 -81.520248)
			(xy 71.697749 -81.555455) (xy 71.746701 -81.597169) (xy 71.768716 -81.620614) (xy 71.784958 -81.637603)
			(xy 71.822476 -81.665901) (xy 71.864552 -81.686831) (xy 71.909755 -81.699681) (xy 71.956549 -81.704013)
			(xy 72.003343 -81.699681) (xy 72.048546 -81.686831) (xy 72.090622 -81.665901) (xy 72.12814 -81.637603)
			(xy 72.144382 -81.620614) (xy 72.16653 -81.597118) (xy 72.215675 -81.555238) (xy 72.269729 -81.519921)
			(xy 72.327821 -81.491734) (xy 72.389015 -81.471134) (xy 72.452326 -81.45845) (xy 72.516734 -81.453888)
			(xy 72.5812 -81.457521) (xy 72.644687 -81.469291) (xy 72.706172 -81.489008) (xy 72.764664 -81.516353)
			(xy 72.819222 -81.550888) (xy 72.868965 -81.592055) (xy 72.891396 -81.61528) (xy 72.907559 -81.631812)
			(xy 72.94473 -81.659298) (xy 72.986259 -81.679606) (xy 73.030778 -81.692065) (xy 73.076816 -81.696264)
			(xy 73.122854 -81.692065) (xy 73.167373 -81.679606) (xy 73.208902 -81.659298) (xy 73.246073 -81.631812)
			(xy 73.262236 -81.61528) (xy 73.283564 -81.593104) (xy 73.330738 -81.553598) (xy 73.382334 -81.520074)
			(xy 73.437599 -81.493022) (xy 73.495725 -81.472837) (xy 73.555862 -81.459815) (xy 73.617131 -81.454146)
			(xy 73.678636 -81.455913) (xy 73.739479 -81.465089) (xy 73.798769 -81.481541) (xy 73.855641 -81.505028)
			(xy 73.909262 -81.535208) (xy 73.958849 -81.571638) (xy 74.003677 -81.613786) (xy 74.023728 -81.637124)
			(xy 74.03835 -81.653931) (xy 74.072408 -81.682644) (xy 74.110947 -81.704984) (xy 74.152789 -81.720268)
			(xy 74.196654 -81.728029) (xy 74.2412 -81.728029) (xy 74.285065 -81.720268) (xy 74.326907 -81.704984)
			(xy 74.365446 -81.682644) (xy 74.399504 -81.653931) (xy 74.414126 -81.637124) (xy 74.434383 -81.61351)
			(xy 74.479761 -81.570942) (xy 74.529995 -81.53423) (xy 74.584333 -81.503922) (xy 74.641964 -81.480472)
			(xy 74.702025 -81.46423) (xy 74.763619 -81.455438) (xy 74.825827 -81.454228) (xy 74.887716 -81.460618)
			(xy 74.948364 -81.474513) (xy 75.006863 -81.495705) (xy 75.062338 -81.523877) (xy 75.113961 -81.558608)
			(xy 75.16096 -81.599379) (xy 75.202633 -81.645581) (xy 75.238356 -81.696522) (xy 75.267595 -81.751443)
			(xy 75.289915 -81.80952) (xy 75.30498 -81.869888) (xy 75.312566 -81.931643) (xy 75.313032 -81.962752)
			(xy 75.313032 -82.545682) (xy 91.625926 -82.545682) (xy 91.629997 -82.49006) (xy 91.642123 -82.435623)
			(xy 91.662046 -82.383532) (xy 91.689342 -82.334897) (xy 91.723428 -82.290754) (xy 91.763577 -82.252045)
			(xy 91.808935 -82.219594) (xy 91.858535 -82.194093) (xy 91.911319 -82.176086) (xy 91.966162 -82.165956)
			(xy 92.021896 -82.163919) (xy 92.077333 -82.170019) (xy 92.13129 -82.184125) (xy 92.182619 -82.205937)
			(xy 92.230225 -82.234991) (xy 92.273093 -82.270666) (xy 92.31031 -82.312203) (xy 92.341083 -82.358716)
			(xy 92.364755 -82.409213) (xy 92.380823 -82.46262) (xy 92.388943 -82.517796) (xy 92.389452 -82.545682)
			(xy 92.388943 -82.573568) (xy 92.380823 -82.628744) (xy 92.364755 -82.682151) (xy 92.341083 -82.732648)
			(xy 92.31031 -82.779161) (xy 92.273093 -82.820698) (xy 92.230225 -82.856373) (xy 92.182619 -82.885427)
			(xy 92.13129 -82.907239) (xy 92.077333 -82.921345) (xy 92.021896 -82.927445) (xy 91.966162 -82.925408)
			(xy 91.911319 -82.915278) (xy 91.858535 -82.897271) (xy 91.808935 -82.87177) (xy 91.763577 -82.839319)
			(xy 91.723428 -82.80061) (xy 91.689342 -82.756467) (xy 91.662046 -82.707832) (xy 91.642123 -82.655741)
			(xy 91.629997 -82.601304) (xy 91.625926 -82.545682) (xy 75.313032 -82.545682) (xy 75.313032 -82.935318)
			(xy 75.312483 -82.968052) (xy 75.304053 -83.032975) (xy 75.28736 -83.09628) (xy 75.262681 -83.156918)
			(xy 75.230423 -83.213888) (xy 75.211178 -83.240372) (xy 75.186032 -83.274154) (xy 75.186032 -83.291172)
			(xy 75.170538 -83.291172) (xy 75.134724 -83.321652) (xy 75.109547 -83.342505) (xy 75.054815 -83.378256)
			(xy 74.99595 -83.406695) (xy 74.933925 -83.42735) (xy 74.869763 -83.439881) (xy 74.804524 -83.444081)
			(xy 74.739285 -83.439881) (xy 74.675123 -83.42735) (xy 74.613098 -83.406695) (xy 74.554233 -83.378256)
			(xy 74.499501 -83.342505) (xy 74.474324 -83.321652) (xy 74.43851 -83.291172) (xy 74.423016 -83.291172)
			(xy 74.423016 -83.274154) (xy 74.39787 -83.240372) (xy 74.379532 -83.215185) (xy 74.348453 -83.161188)
			(xy 74.335894 -83.132676) (xy 74.328992 -83.117609) (xy 74.308731 -83.091401) (xy 74.282398 -83.071302)
			(xy 74.251773 -83.058672) (xy 74.218927 -83.054365) (xy 74.186081 -83.058672) (xy 74.155456 -83.071302)
			(xy 74.129123 -83.091401) (xy 74.108862 -83.117609) (xy 74.10196 -83.132676) (xy 74.089402 -83.161189)
			(xy 74.058328 -83.21519) (xy 74.039984 -83.240372) (xy 74.014584 -83.274154) (xy 74.014584 -83.291172)
			(xy 73.999344 -83.291172) (xy 73.96353 -83.321652) (xy 73.938353 -83.342505) (xy 73.883621 -83.378256)
			(xy 73.824756 -83.406695) (xy 73.762731 -83.42735) (xy 73.698569 -83.439881) (xy 73.63333 -83.444081)
			(xy 73.568091 -83.439881) (xy 73.503929 -83.42735) (xy 73.441904 -83.406695) (xy 73.383039 -83.378256)
			(xy 73.328307 -83.342505) (xy 73.30313 -83.321652) (xy 73.267316 -83.291172) (xy 73.252076 -83.291172)
			(xy 73.252076 -83.274154) (xy 73.226676 -83.240372) (xy 73.216123 -83.226051) (xy 73.196801 -83.196179)
			(xy 73.188068 -83.180682) (xy 73.18042 -83.167672) (xy 73.160069 -83.145399) (xy 73.135054 -83.128533)
			(xy 73.106774 -83.11802) (xy 73.076816 -83.114449) (xy 73.046858 -83.11802) (xy 73.018578 -83.128533)
			(xy 72.993563 -83.145399) (xy 72.973212 -83.167672) (xy 72.965564 -83.180682) (xy 72.956841 -83.196185)
			(xy 72.937519 -83.226058) (xy 72.926956 -83.240372) (xy 72.901556 -83.274154) (xy 72.901556 -83.291172)
			(xy 72.886316 -83.291172) (xy 72.850502 -83.321652) (xy 72.825325 -83.342505) (xy 72.770593 -83.378256)
			(xy 72.711728 -83.406695) (xy 72.649703 -83.42735) (xy 72.585541 -83.439881) (xy 72.520302 -83.444081)
			(xy 72.455063 -83.439881) (xy 72.390901 -83.42735) (xy 72.328876 -83.406695) (xy 72.270011 -83.378256)
			(xy 72.215279 -83.342505) (xy 72.190102 -83.321652) (xy 72.154288 -83.291172) (xy 72.139048 -83.291172)
			(xy 72.139048 -83.274154) (xy 72.113648 -83.240372) (xy 72.101285 -83.223537) (xy 72.079028 -83.188189)
			(xy 72.069198 -83.16976) (xy 72.061709 -83.15627) (xy 72.041337 -83.133107) (xy 72.015995 -83.11552)
			(xy 71.987169 -83.104537) (xy 71.956549 -83.100803) (xy 71.925929 -83.104537) (xy 71.897103 -83.11552)
			(xy 71.871761 -83.133107) (xy 71.851389 -83.15627) (xy 71.8439 -83.16976) (xy 71.834078 -83.188194)
			(xy 71.811822 -83.223543) (xy 71.79945 -83.240372) (xy 71.774304 -83.274154) (xy 71.774304 -83.291172)
			(xy 71.75881 -83.291172) (xy 71.722996 -83.321652) (xy 71.697819 -83.342505) (xy 71.643087 -83.378256)
			(xy 71.584222 -83.406695) (xy 71.522197 -83.42735) (xy 71.458035 -83.439881) (xy 71.392796 -83.444081)
			(xy 71.327557 -83.439881) (xy 71.263395 -83.42735) (xy 71.20137 -83.406695) (xy 71.142505 -83.378256)
			(xy 71.087773 -83.342505) (xy 71.062596 -83.321652) (xy 71.026782 -83.291172) (xy 71.011288 -83.291172)
			(xy 71.011288 -83.274154) (xy 70.986142 -83.240372) (xy 70.966878 -83.2139) (xy 70.934617 -83.156929)
			(xy 70.909935 -83.096287) (xy 70.893241 -83.03298) (xy 70.88481 -82.968054) (xy 70.884288 -82.935318)
			(xy 29.24048 -82.935318) (xy 29.24048 -83.447636) (xy 51.141884 -83.447636) (xy 52.793392 -83.447636)
			(xy 52.793392 -85.099652) (xy 51.141884 -85.099652) (xy 51.141884 -83.447636) (xy 29.24048 -83.447636)
			(xy 29.24048 -84.314199) (xy 47.642008 -84.314199) (xy 47.642008 -84.233089) (xy 47.649958 -84.15237)
			(xy 47.665781 -84.072819) (xy 47.689326 -83.995203) (xy 47.720365 -83.920267) (xy 47.7586 -83.848735)
			(xy 47.803662 -83.781295) (xy 47.855117 -83.718596) (xy 47.91247 -83.661243) (xy 47.975169 -83.609788)
			(xy 48.042609 -83.564726) (xy 48.114141 -83.526491) (xy 48.189077 -83.495452) (xy 48.266693 -83.471907)
			(xy 48.346244 -83.456084) (xy 48.426963 -83.448134) (xy 48.508073 -83.448134) (xy 48.588792 -83.456084)
			(xy 48.668343 -83.471907) (xy 48.745959 -83.495452) (xy 48.820895 -83.526491) (xy 48.892427 -83.564726)
			(xy 48.959867 -83.609788) (xy 49.022566 -83.661243) (xy 49.079919 -83.718596) (xy 49.131374 -83.781295)
			(xy 49.176436 -83.848735) (xy 49.214671 -83.920267) (xy 49.24571 -83.995203) (xy 49.269255 -84.072819)
			(xy 49.285078 -84.15237) (xy 49.293028 -84.233089) (xy 49.293526 -84.273644) (xy 49.293028 -84.314199)
			(xy 49.285078 -84.394918) (xy 49.269255 -84.474469) (xy 49.24571 -84.552085) (xy 49.214671 -84.627021)
			(xy 49.176436 -84.698553) (xy 49.131374 -84.765993) (xy 49.079919 -84.828692) (xy 49.022566 -84.886045)
			(xy 48.959867 -84.9375) (xy 48.892427 -84.982562) (xy 48.820895 -85.020797) (xy 48.745959 -85.051836)
			(xy 48.668343 -85.075381) (xy 48.588792 -85.091204) (xy 48.508073 -85.099154) (xy 48.426963 -85.099154)
			(xy 48.346244 -85.091204) (xy 48.266693 -85.075381) (xy 48.189077 -85.051836) (xy 48.114141 -85.020797)
			(xy 48.042609 -84.982562) (xy 47.975169 -84.9375) (xy 47.91247 -84.886045) (xy 47.855117 -84.828692)
			(xy 47.803662 -84.765993) (xy 47.7586 -84.698553) (xy 47.720365 -84.627021) (xy 47.689326 -84.552085)
			(xy 47.665781 -84.474469) (xy 47.649958 -84.394918) (xy 47.642008 -84.314199) (xy 29.24048 -84.314199)
			(xy 29.24048 -89.864184) (xy 29.99232 -90.616024) (xy 32.26943 -90.616024) (xy 33.77692 -92.123514)
			(xy 33.77692 -93.033358) (xy 34.599874 -93.033358) (xy 34.599874 -92.946458) (xy 34.607892 -92.859929)
			(xy 34.62386 -92.774509) (xy 34.647641 -92.690927) (xy 34.679033 -92.609895) (xy 34.717767 -92.532106)
			(xy 34.763514 -92.458222) (xy 34.815883 -92.388875) (xy 34.874427 -92.324655) (xy 34.938647 -92.266111)
			(xy 35.007994 -92.213742) (xy 35.081878 -92.167995) (xy 35.159667 -92.129261) (xy 35.240699 -92.097869)
			(xy 35.324281 -92.074088) (xy 35.409701 -92.05812) (xy 35.49623 -92.050102) (xy 35.58313 -92.050102)
			(xy 35.669659 -92.05812) (xy 35.755079 -92.074088) (xy 35.838661 -92.097869) (xy 35.919693 -92.129261)
			(xy 35.997482 -92.167995) (xy 36.071366 -92.213742) (xy 36.140713 -92.266111) (xy 36.204933 -92.324655)
			(xy 36.263477 -92.388875) (xy 36.315846 -92.458222) (xy 36.361593 -92.532106) (xy 36.400327 -92.609895)
			(xy 36.431719 -92.690927) (xy 36.4555 -92.774509) (xy 36.471468 -92.859929) (xy 36.479486 -92.946458)
			(xy 36.479988 -92.989908) (xy 36.479486 -93.033358) (xy 36.471468 -93.119887) (xy 36.4555 -93.205307)
			(xy 36.431719 -93.288889) (xy 36.400327 -93.369921) (xy 36.361593 -93.44771) (xy 36.315846 -93.521594)
			(xy 36.263477 -93.590941) (xy 36.204933 -93.655161) (xy 36.140713 -93.713705) (xy 36.071366 -93.766074)
			(xy 35.997482 -93.811821) (xy 35.919693 -93.850555) (xy 35.838661 -93.881947) (xy 35.755079 -93.905728)
			(xy 35.669659 -93.921696) (xy 35.58313 -93.929714) (xy 35.49623 -93.929714) (xy 35.409701 -93.921696)
			(xy 35.324281 -93.905728) (xy 35.240699 -93.881947) (xy 35.159667 -93.850555) (xy 35.081878 -93.811821)
			(xy 35.007994 -93.766074) (xy 34.938647 -93.713705) (xy 34.874427 -93.655161) (xy 34.815883 -93.590941)
			(xy 34.763514 -93.521594) (xy 34.717767 -93.44771) (xy 34.679033 -93.369921) (xy 34.647641 -93.288889)
			(xy 34.62386 -93.205307) (xy 34.607892 -93.119887) (xy 34.599874 -93.033358) (xy 33.77692 -93.033358)
			(xy 33.77692 -95.573358) (xy 34.599874 -95.573358) (xy 34.599874 -95.486458) (xy 34.607892 -95.399929)
			(xy 34.62386 -95.314509) (xy 34.647641 -95.230927) (xy 34.679033 -95.149895) (xy 34.717767 -95.072106)
			(xy 34.763514 -94.998222) (xy 34.815883 -94.928875) (xy 34.874427 -94.864655) (xy 34.938647 -94.806111)
			(xy 35.007994 -94.753742) (xy 35.081878 -94.707995) (xy 35.159667 -94.669261) (xy 35.240699 -94.637869)
			(xy 35.324281 -94.614088) (xy 35.409701 -94.59812) (xy 35.49623 -94.590102) (xy 35.58313 -94.590102)
			(xy 35.669659 -94.59812) (xy 35.755079 -94.614088) (xy 35.838661 -94.637869) (xy 35.919693 -94.669261)
			(xy 35.997482 -94.707995) (xy 36.071366 -94.753742) (xy 36.140713 -94.806111) (xy 36.204933 -94.864655)
			(xy 36.263477 -94.928875) (xy 36.315846 -94.998222) (xy 36.361593 -95.072106) (xy 36.400327 -95.149895)
			(xy 36.431719 -95.230927) (xy 36.4555 -95.314509) (xy 36.471468 -95.399929) (xy 36.479486 -95.486458)
			(xy 36.479988 -95.529908) (xy 36.479486 -95.573358) (xy 36.471468 -95.659887) (xy 36.4555 -95.745307)
			(xy 36.437073 -95.81007) (xy 39.818564 -95.81007) (xy 39.819054 -95.752663) (xy 39.826889 -95.638117)
			(xy 39.842523 -95.524372) (xy 39.865882 -95.41196) (xy 39.896859 -95.301403) (xy 39.935308 -95.193218)
			(xy 39.98105 -95.08791) (xy 40.033872 -94.985968) (xy 40.093527 -94.887869) (xy 40.159738 -94.794069)
			(xy 40.232196 -94.705007) (xy 40.310562 -94.621096) (xy 40.394473 -94.54273) (xy 40.483535 -94.470272)
			(xy 40.577335 -94.404061) (xy 40.675434 -94.344406) (xy 40.777376 -94.291584) (xy 40.882684 -94.245842)
			(xy 40.990869 -94.207393) (xy 41.101426 -94.176416) (xy 41.213838 -94.153057) (xy 41.327583 -94.137423)
			(xy 41.442129 -94.129588) (xy 41.556943 -94.129588) (xy 41.671489 -94.137423) (xy 41.785234 -94.153057)
			(xy 41.897646 -94.176416) (xy 42.008203 -94.207393) (xy 42.116388 -94.245842) (xy 42.221696 -94.291584)
			(xy 42.323638 -94.344406) (xy 42.421737 -94.404061) (xy 42.50107 -94.46006) (xy 43.327577 -94.46006)
			(xy 43.331612 -94.384356) (xy 43.343671 -94.309511) (xy 43.363617 -94.23637) (xy 43.391224 -94.165765)
			(xy 43.42618 -94.098494) (xy 43.468088 -94.035319) (xy 43.516474 -93.976957) (xy 43.57079 -93.924069)
			(xy 43.630419 -93.877254) (xy 43.694687 -93.837042) (xy 43.762864 -93.80389) (xy 43.83418 -93.778172)
			(xy 43.907825 -93.76018) (xy 43.982965 -93.750118) (xy 44.058749 -93.748099) (xy 44.134319 -93.754148)
			(xy 44.208817 -93.768195) (xy 44.2814 -93.790081) (xy 44.351246 -93.819558) (xy 44.417563 -93.856293)
			(xy 44.479599 -93.899868) (xy 44.536652 -93.94979) (xy 44.588076 -94.005494) (xy 44.633287 -94.066349)
			(xy 44.671774 -94.131664) (xy 44.7031 -94.2007) (xy 44.72691 -94.272675) (xy 44.742935 -94.346773)
			(xy 44.750994 -94.422154) (xy 44.751498 -94.46006) (xy 45.867577 -94.46006) (xy 45.871612 -94.384356)
			(xy 45.883671 -94.309511) (xy 45.903617 -94.23637) (xy 45.931224 -94.165765) (xy 45.96618 -94.098494)
			(xy 46.008088 -94.035319) (xy 46.056474 -93.976957) (xy 46.11079 -93.924069) (xy 46.170419 -93.877254)
			(xy 46.234687 -93.837042) (xy 46.302864 -93.80389) (xy 46.37418 -93.778172) (xy 46.447825 -93.76018)
			(xy 46.522965 -93.750118) (xy 46.598749 -93.748099) (xy 46.674319 -93.754148) (xy 46.748817 -93.768195)
			(xy 46.8214 -93.790081) (xy 46.891246 -93.819558) (xy 46.957563 -93.856293) (xy 47.019599 -93.899868)
			(xy 47.076652 -93.94979) (xy 47.128076 -94.005494) (xy 47.173287 -94.066349) (xy 47.211774 -94.131664)
			(xy 47.2431 -94.2007) (xy 47.26691 -94.272675) (xy 47.282935 -94.346773) (xy 47.290994 -94.422154)
			(xy 47.291498 -94.46006) (xy 48.407577 -94.46006) (xy 48.411612 -94.384356) (xy 48.423671 -94.309511)
			(xy 48.443617 -94.23637) (xy 48.471224 -94.165765) (xy 48.50618 -94.098494) (xy 48.548088 -94.035319)
			(xy 48.596474 -93.976957) (xy 48.65079 -93.924069) (xy 48.710419 -93.877254) (xy 48.774687 -93.837042)
			(xy 48.842864 -93.80389) (xy 48.91418 -93.778172) (xy 48.987825 -93.76018) (xy 49.062965 -93.750118)
			(xy 49.138749 -93.748099) (xy 49.214319 -93.754148) (xy 49.288817 -93.768195) (xy 49.3614 -93.790081)
			(xy 49.431246 -93.819558) (xy 49.497563 -93.856293) (xy 49.559599 -93.899868) (xy 49.616652 -93.94979)
			(xy 49.668076 -94.005494) (xy 49.713287 -94.066349) (xy 49.751774 -94.131664) (xy 49.7831 -94.2007)
			(xy 49.80691 -94.272675) (xy 49.822935 -94.346773) (xy 49.830994 -94.422154) (xy 49.831498 -94.46006)
			(xy 50.947577 -94.46006) (xy 50.951612 -94.384356) (xy 50.963671 -94.309511) (xy 50.983617 -94.23637)
			(xy 51.011224 -94.165765) (xy 51.04618 -94.098494) (xy 51.088088 -94.035319) (xy 51.136474 -93.976957)
			(xy 51.19079 -93.924069) (xy 51.250419 -93.877254) (xy 51.314687 -93.837042) (xy 51.382864 -93.80389)
			(xy 51.45418 -93.778172) (xy 51.527825 -93.76018) (xy 51.602965 -93.750118) (xy 51.678749 -93.748099)
			(xy 51.754319 -93.754148) (xy 51.828817 -93.768195) (xy 51.9014 -93.790081) (xy 51.971246 -93.819558)
			(xy 52.037563 -93.856293) (xy 52.099599 -93.899868) (xy 52.156652 -93.94979) (xy 52.208076 -94.005494)
			(xy 52.253287 -94.066349) (xy 52.291774 -94.131664) (xy 52.3231 -94.2007) (xy 52.34691 -94.272675)
			(xy 52.362935 -94.346773) (xy 52.370994 -94.422154) (xy 52.371498 -94.46006) (xy 53.487577 -94.46006)
			(xy 53.491612 -94.384356) (xy 53.503671 -94.309511) (xy 53.523617 -94.23637) (xy 53.551224 -94.165765)
			(xy 53.58618 -94.098494) (xy 53.628088 -94.035319) (xy 53.676474 -93.976957) (xy 53.73079 -93.924069)
			(xy 53.790419 -93.877254) (xy 53.854687 -93.837042) (xy 53.922864 -93.80389) (xy 53.99418 -93.778172)
			(xy 54.067825 -93.76018) (xy 54.142965 -93.750118) (xy 54.218749 -93.748099) (xy 54.294319 -93.754148)
			(xy 54.368817 -93.768195) (xy 54.4414 -93.790081) (xy 54.511246 -93.819558) (xy 54.577563 -93.856293)
			(xy 54.639599 -93.899868) (xy 54.696652 -93.94979) (xy 54.748076 -94.005494) (xy 54.793287 -94.066349)
			(xy 54.831774 -94.131664) (xy 54.8631 -94.2007) (xy 54.88691 -94.272675) (xy 54.902935 -94.346773)
			(xy 54.910994 -94.422154) (xy 54.911498 -94.46006) (xy 56.027577 -94.46006) (xy 56.031612 -94.384356)
			(xy 56.043671 -94.309511) (xy 56.063617 -94.23637) (xy 56.091224 -94.165765) (xy 56.12618 -94.098494)
			(xy 56.168088 -94.035319) (xy 56.216474 -93.976957) (xy 56.27079 -93.924069) (xy 56.330419 -93.877254)
			(xy 56.394687 -93.837042) (xy 56.462864 -93.80389) (xy 56.53418 -93.778172) (xy 56.607825 -93.76018)
			(xy 56.682965 -93.750118) (xy 56.758749 -93.748099) (xy 56.834319 -93.754148) (xy 56.908817 -93.768195)
			(xy 56.9814 -93.790081) (xy 57.051246 -93.819558) (xy 57.117563 -93.856293) (xy 57.179599 -93.899868)
			(xy 57.236652 -93.94979) (xy 57.288076 -94.005494) (xy 57.333287 -94.066349) (xy 57.371774 -94.131664)
			(xy 57.4031 -94.2007) (xy 57.42691 -94.272675) (xy 57.442935 -94.346773) (xy 57.450994 -94.422154)
			(xy 57.451498 -94.46006) (xy 58.567577 -94.46006) (xy 58.571612 -94.384356) (xy 58.583671 -94.309511)
			(xy 58.603617 -94.23637) (xy 58.631224 -94.165765) (xy 58.66618 -94.098494) (xy 58.708088 -94.035319)
			(xy 58.756474 -93.976957) (xy 58.81079 -93.924069) (xy 58.870419 -93.877254) (xy 58.934687 -93.837042)
			(xy 59.002864 -93.80389) (xy 59.07418 -93.778172) (xy 59.147825 -93.76018) (xy 59.222965 -93.750118)
			(xy 59.298749 -93.748099) (xy 59.374319 -93.754148) (xy 59.448817 -93.768195) (xy 59.5214 -93.790081)
			(xy 59.591246 -93.819558) (xy 59.657563 -93.856293) (xy 59.719599 -93.899868) (xy 59.776652 -93.94979)
			(xy 59.828076 -94.005494) (xy 59.873287 -94.066349) (xy 59.911774 -94.131664) (xy 59.9431 -94.2007)
			(xy 59.96691 -94.272675) (xy 59.982935 -94.346773) (xy 59.990994 -94.422154) (xy 59.991498 -94.46006)
			(xy 61.107577 -94.46006) (xy 61.111612 -94.384356) (xy 61.123671 -94.309511) (xy 61.143617 -94.23637)
			(xy 61.171224 -94.165765) (xy 61.20618 -94.098494) (xy 61.248088 -94.035319) (xy 61.296474 -93.976957)
			(xy 61.35079 -93.924069) (xy 61.410419 -93.877254) (xy 61.474687 -93.837042) (xy 61.542864 -93.80389)
			(xy 61.61418 -93.778172) (xy 61.687825 -93.76018) (xy 61.762965 -93.750118) (xy 61.838749 -93.748099)
			(xy 61.914319 -93.754148) (xy 61.988817 -93.768195) (xy 62.0614 -93.790081) (xy 62.131246 -93.819558)
			(xy 62.197563 -93.856293) (xy 62.259599 -93.899868) (xy 62.265544 -93.90507) (xy 86.197697 -93.90507)
			(xy 86.201732 -93.829366) (xy 86.213791 -93.754521) (xy 86.233737 -93.68138) (xy 86.261344 -93.610775)
			(xy 86.2963 -93.543504) (xy 86.338208 -93.480329) (xy 86.386594 -93.421967) (xy 86.44091 -93.369079)
			(xy 86.500539 -93.322264) (xy 86.564807 -93.282052) (xy 86.632984 -93.2489) (xy 86.7043 -93.223182)
			(xy 86.777945 -93.20519) (xy 86.853085 -93.195128) (xy 86.928869 -93.193109) (xy 87.004439 -93.199158)
			(xy 87.078937 -93.213205) (xy 87.15152 -93.235091) (xy 87.221366 -93.264568) (xy 87.287683 -93.301303)
			(xy 87.349719 -93.344878) (xy 87.406772 -93.3948) (xy 87.458196 -93.450504) (xy 87.503407 -93.511359)
			(xy 87.541894 -93.576674) (xy 87.57322 -93.64571) (xy 87.59703 -93.717685) (xy 87.613055 -93.791783)
			(xy 87.621114 -93.867164) (xy 87.621618 -93.90507) (xy 88.737697 -93.90507) (xy 88.741732 -93.829366)
			(xy 88.753791 -93.754521) (xy 88.773737 -93.68138) (xy 88.801344 -93.610775) (xy 88.8363 -93.543504)
			(xy 88.878208 -93.480329) (xy 88.926594 -93.421967) (xy 88.98091 -93.369079) (xy 89.040539 -93.322264)
			(xy 89.104807 -93.282052) (xy 89.172984 -93.2489) (xy 89.2443 -93.223182) (xy 89.317945 -93.20519)
			(xy 89.393085 -93.195128) (xy 89.468869 -93.193109) (xy 89.544439 -93.199158) (xy 89.618937 -93.213205)
			(xy 89.69152 -93.235091) (xy 89.761366 -93.264568) (xy 89.827683 -93.301303) (xy 89.889719 -93.344878)
			(xy 89.946772 -93.3948) (xy 89.998196 -93.450504) (xy 90.043407 -93.511359) (xy 90.081894 -93.576674)
			(xy 90.11322 -93.64571) (xy 90.13703 -93.717685) (xy 90.153055 -93.791783) (xy 90.161114 -93.867164)
			(xy 90.161618 -93.90507) (xy 91.277697 -93.90507) (xy 91.281732 -93.829366) (xy 91.293791 -93.754521)
			(xy 91.313737 -93.68138) (xy 91.341344 -93.610775) (xy 91.3763 -93.543504) (xy 91.418208 -93.480329)
			(xy 91.466594 -93.421967) (xy 91.52091 -93.369079) (xy 91.580539 -93.322264) (xy 91.644807 -93.282052)
			(xy 91.712984 -93.2489) (xy 91.7843 -93.223182) (xy 91.857945 -93.20519) (xy 91.933085 -93.195128)
			(xy 92.008869 -93.193109) (xy 92.084439 -93.199158) (xy 92.158937 -93.213205) (xy 92.23152 -93.235091)
			(xy 92.301366 -93.264568) (xy 92.367683 -93.301303) (xy 92.429719 -93.344878) (xy 92.486772 -93.3948)
			(xy 92.538196 -93.450504) (xy 92.583407 -93.511359) (xy 92.621894 -93.576674) (xy 92.65322 -93.64571)
			(xy 92.67703 -93.717685) (xy 92.693055 -93.791783) (xy 92.701114 -93.867164) (xy 92.701618 -93.90507)
			(xy 92.701114 -93.942976) (xy 92.693055 -94.018357) (xy 92.67703 -94.092455) (xy 92.65322 -94.16443)
			(xy 92.621894 -94.233466) (xy 92.583407 -94.298781) (xy 92.538196 -94.359636) (xy 92.486772 -94.41534)
			(xy 92.429719 -94.465262) (xy 92.367683 -94.508837) (xy 92.301366 -94.545572) (xy 92.23152 -94.575049)
			(xy 92.158937 -94.596935) (xy 92.084439 -94.610982) (xy 92.008869 -94.617031) (xy 91.933085 -94.615012)
			(xy 91.857945 -94.60495) (xy 91.7843 -94.586958) (xy 91.712984 -94.56124) (xy 91.644807 -94.528088)
			(xy 91.580539 -94.487876) (xy 91.52091 -94.441061) (xy 91.466594 -94.388173) (xy 91.418208 -94.329811)
			(xy 91.3763 -94.266636) (xy 91.341344 -94.199365) (xy 91.313737 -94.12876) (xy 91.293791 -94.055619)
			(xy 91.281732 -93.980774) (xy 91.277697 -93.90507) (xy 90.161618 -93.90507) (xy 90.161114 -93.942976)
			(xy 90.153055 -94.018357) (xy 90.13703 -94.092455) (xy 90.11322 -94.16443) (xy 90.081894 -94.233466)
			(xy 90.043407 -94.298781) (xy 89.998196 -94.359636) (xy 89.946772 -94.41534) (xy 89.889719 -94.465262)
			(xy 89.827683 -94.508837) (xy 89.761366 -94.545572) (xy 89.69152 -94.575049) (xy 89.618937 -94.596935)
			(xy 89.544439 -94.610982) (xy 89.468869 -94.617031) (xy 89.393085 -94.615012) (xy 89.317945 -94.60495)
			(xy 89.2443 -94.586958) (xy 89.172984 -94.56124) (xy 89.104807 -94.528088) (xy 89.040539 -94.487876)
			(xy 88.98091 -94.441061) (xy 88.926594 -94.388173) (xy 88.878208 -94.329811) (xy 88.8363 -94.266636)
			(xy 88.801344 -94.199365) (xy 88.773737 -94.12876) (xy 88.753791 -94.055619) (xy 88.741732 -93.980774)
			(xy 88.737697 -93.90507) (xy 87.621618 -93.90507) (xy 87.621114 -93.942976) (xy 87.613055 -94.018357)
			(xy 87.59703 -94.092455) (xy 87.57322 -94.16443) (xy 87.541894 -94.233466) (xy 87.503407 -94.298781)
			(xy 87.458196 -94.359636) (xy 87.406772 -94.41534) (xy 87.349719 -94.465262) (xy 87.287683 -94.508837)
			(xy 87.221366 -94.545572) (xy 87.15152 -94.575049) (xy 87.078937 -94.596935) (xy 87.004439 -94.610982)
			(xy 86.928869 -94.617031) (xy 86.853085 -94.615012) (xy 86.777945 -94.60495) (xy 86.7043 -94.586958)
			(xy 86.632984 -94.56124) (xy 86.564807 -94.528088) (xy 86.500539 -94.487876) (xy 86.44091 -94.441061)
			(xy 86.386594 -94.388173) (xy 86.338208 -94.329811) (xy 86.2963 -94.266636) (xy 86.261344 -94.199365)
			(xy 86.233737 -94.12876) (xy 86.213791 -94.055619) (xy 86.201732 -93.980774) (xy 86.197697 -93.90507)
			(xy 62.265544 -93.90507) (xy 62.316652 -93.94979) (xy 62.368076 -94.005494) (xy 62.413287 -94.066349)
			(xy 62.451774 -94.131664) (xy 62.4831 -94.2007) (xy 62.50691 -94.272675) (xy 62.522935 -94.346773)
			(xy 62.530994 -94.422154) (xy 62.531498 -94.46006) (xy 62.530994 -94.497966) (xy 62.522935 -94.573347)
			(xy 62.50691 -94.647445) (xy 62.4831 -94.71942) (xy 62.451774 -94.788456) (xy 62.413287 -94.853771)
			(xy 62.368076 -94.914626) (xy 62.316652 -94.97033) (xy 62.259599 -95.020252) (xy 62.197563 -95.063827)
			(xy 62.131246 -95.100562) (xy 62.0614 -95.130039) (xy 61.988817 -95.151925) (xy 61.914319 -95.165972)
			(xy 61.838749 -95.172021) (xy 61.762965 -95.170002) (xy 61.687825 -95.15994) (xy 61.61418 -95.141948)
			(xy 61.542864 -95.11623) (xy 61.474687 -95.083078) (xy 61.410419 -95.042866) (xy 61.35079 -94.996051)
			(xy 61.296474 -94.943163) (xy 61.248088 -94.884801) (xy 61.20618 -94.821626) (xy 61.171224 -94.754355)
			(xy 61.143617 -94.68375) (xy 61.123671 -94.610609) (xy 61.111612 -94.535764) (xy 61.107577 -94.46006)
			(xy 59.991498 -94.46006) (xy 59.990994 -94.497966) (xy 59.982935 -94.573347) (xy 59.96691 -94.647445)
			(xy 59.9431 -94.71942) (xy 59.911774 -94.788456) (xy 59.873287 -94.853771) (xy 59.828076 -94.914626)
			(xy 59.776652 -94.97033) (xy 59.719599 -95.020252) (xy 59.657563 -95.063827) (xy 59.591246 -95.100562)
			(xy 59.5214 -95.130039) (xy 59.448817 -95.151925) (xy 59.374319 -95.165972) (xy 59.298749 -95.172021)
			(xy 59.222965 -95.170002) (xy 59.147825 -95.15994) (xy 59.07418 -95.141948) (xy 59.002864 -95.11623)
			(xy 58.934687 -95.083078) (xy 58.870419 -95.042866) (xy 58.81079 -94.996051) (xy 58.756474 -94.943163)
			(xy 58.708088 -94.884801) (xy 58.66618 -94.821626) (xy 58.631224 -94.754355) (xy 58.603617 -94.68375)
			(xy 58.583671 -94.610609) (xy 58.571612 -94.535764) (xy 58.567577 -94.46006) (xy 57.451498 -94.46006)
			(xy 57.450994 -94.497966) (xy 57.442935 -94.573347) (xy 57.42691 -94.647445) (xy 57.4031 -94.71942)
			(xy 57.371774 -94.788456) (xy 57.333287 -94.853771) (xy 57.288076 -94.914626) (xy 57.236652 -94.97033)
			(xy 57.179599 -95.020252) (xy 57.117563 -95.063827) (xy 57.051246 -95.100562) (xy 56.9814 -95.130039)
			(xy 56.908817 -95.151925) (xy 56.834319 -95.165972) (xy 56.758749 -95.172021) (xy 56.682965 -95.170002)
			(xy 56.607825 -95.15994) (xy 56.53418 -95.141948) (xy 56.462864 -95.11623) (xy 56.394687 -95.083078)
			(xy 56.330419 -95.042866) (xy 56.27079 -94.996051) (xy 56.216474 -94.943163) (xy 56.168088 -94.884801)
			(xy 56.12618 -94.821626) (xy 56.091224 -94.754355) (xy 56.063617 -94.68375) (xy 56.043671 -94.610609)
			(xy 56.031612 -94.535764) (xy 56.027577 -94.46006) (xy 54.911498 -94.46006) (xy 54.910994 -94.497966)
			(xy 54.902935 -94.573347) (xy 54.88691 -94.647445) (xy 54.8631 -94.71942) (xy 54.831774 -94.788456)
			(xy 54.793287 -94.853771) (xy 54.748076 -94.914626) (xy 54.696652 -94.97033) (xy 54.639599 -95.020252)
			(xy 54.577563 -95.063827) (xy 54.511246 -95.100562) (xy 54.4414 -95.130039) (xy 54.368817 -95.151925)
			(xy 54.294319 -95.165972) (xy 54.218749 -95.172021) (xy 54.142965 -95.170002) (xy 54.067825 -95.15994)
			(xy 53.99418 -95.141948) (xy 53.922864 -95.11623) (xy 53.854687 -95.083078) (xy 53.790419 -95.042866)
			(xy 53.73079 -94.996051) (xy 53.676474 -94.943163) (xy 53.628088 -94.884801) (xy 53.58618 -94.821626)
			(xy 53.551224 -94.754355) (xy 53.523617 -94.68375) (xy 53.503671 -94.610609) (xy 53.491612 -94.535764)
			(xy 53.487577 -94.46006) (xy 52.371498 -94.46006) (xy 52.370994 -94.497966) (xy 52.362935 -94.573347)
			(xy 52.34691 -94.647445) (xy 52.3231 -94.71942) (xy 52.291774 -94.788456) (xy 52.253287 -94.853771)
			(xy 52.208076 -94.914626) (xy 52.156652 -94.97033) (xy 52.099599 -95.020252) (xy 52.037563 -95.063827)
			(xy 51.971246 -95.100562) (xy 51.9014 -95.130039) (xy 51.828817 -95.151925) (xy 51.754319 -95.165972)
			(xy 51.678749 -95.172021) (xy 51.602965 -95.170002) (xy 51.527825 -95.15994) (xy 51.45418 -95.141948)
			(xy 51.382864 -95.11623) (xy 51.314687 -95.083078) (xy 51.250419 -95.042866) (xy 51.19079 -94.996051)
			(xy 51.136474 -94.943163) (xy 51.088088 -94.884801) (xy 51.04618 -94.821626) (xy 51.011224 -94.754355)
			(xy 50.983617 -94.68375) (xy 50.963671 -94.610609) (xy 50.951612 -94.535764) (xy 50.947577 -94.46006)
			(xy 49.831498 -94.46006) (xy 49.830994 -94.497966) (xy 49.822935 -94.573347) (xy 49.80691 -94.647445)
			(xy 49.7831 -94.71942) (xy 49.751774 -94.788456) (xy 49.713287 -94.853771) (xy 49.668076 -94.914626)
			(xy 49.616652 -94.97033) (xy 49.559599 -95.020252) (xy 49.497563 -95.063827) (xy 49.431246 -95.100562)
			(xy 49.3614 -95.130039) (xy 49.288817 -95.151925) (xy 49.214319 -95.165972) (xy 49.138749 -95.172021)
			(xy 49.062965 -95.170002) (xy 48.987825 -95.15994) (xy 48.91418 -95.141948) (xy 48.842864 -95.11623)
			(xy 48.774687 -95.083078) (xy 48.710419 -95.042866) (xy 48.65079 -94.996051) (xy 48.596474 -94.943163)
			(xy 48.548088 -94.884801) (xy 48.50618 -94.821626) (xy 48.471224 -94.754355) (xy 48.443617 -94.68375)
			(xy 48.423671 -94.610609) (xy 48.411612 -94.535764) (xy 48.407577 -94.46006) (xy 47.291498 -94.46006)
			(xy 47.290994 -94.497966) (xy 47.282935 -94.573347) (xy 47.26691 -94.647445) (xy 47.2431 -94.71942)
			(xy 47.211774 -94.788456) (xy 47.173287 -94.853771) (xy 47.128076 -94.914626) (xy 47.076652 -94.97033)
			(xy 47.019599 -95.020252) (xy 46.957563 -95.063827) (xy 46.891246 -95.100562) (xy 46.8214 -95.130039)
			(xy 46.748817 -95.151925) (xy 46.674319 -95.165972) (xy 46.598749 -95.172021) (xy 46.522965 -95.170002)
			(xy 46.447825 -95.15994) (xy 46.37418 -95.141948) (xy 46.302864 -95.11623) (xy 46.234687 -95.083078)
			(xy 46.170419 -95.042866) (xy 46.11079 -94.996051) (xy 46.056474 -94.943163) (xy 46.008088 -94.884801)
			(xy 45.96618 -94.821626) (xy 45.931224 -94.754355) (xy 45.903617 -94.68375) (xy 45.883671 -94.610609)
			(xy 45.871612 -94.535764) (xy 45.867577 -94.46006) (xy 44.751498 -94.46006) (xy 44.750994 -94.497966)
			(xy 44.742935 -94.573347) (xy 44.72691 -94.647445) (xy 44.7031 -94.71942) (xy 44.671774 -94.788456)
			(xy 44.633287 -94.853771) (xy 44.588076 -94.914626) (xy 44.536652 -94.97033) (xy 44.479599 -95.020252)
			(xy 44.417563 -95.063827) (xy 44.351246 -95.100562) (xy 44.2814 -95.130039) (xy 44.208817 -95.151925)
			(xy 44.134319 -95.165972) (xy 44.058749 -95.172021) (xy 43.982965 -95.170002) (xy 43.907825 -95.15994)
			(xy 43.83418 -95.141948) (xy 43.762864 -95.11623) (xy 43.694687 -95.083078) (xy 43.630419 -95.042866)
			(xy 43.57079 -94.996051) (xy 43.516474 -94.943163) (xy 43.468088 -94.884801) (xy 43.42618 -94.821626)
			(xy 43.391224 -94.754355) (xy 43.363617 -94.68375) (xy 43.343671 -94.610609) (xy 43.331612 -94.535764)
			(xy 43.327577 -94.46006) (xy 42.50107 -94.46006) (xy 42.515537 -94.470272) (xy 42.604599 -94.54273)
			(xy 42.68851 -94.621096) (xy 42.766876 -94.705007) (xy 42.839334 -94.794069) (xy 42.905545 -94.887869)
			(xy 42.9652 -94.985968) (xy 43.018022 -95.08791) (xy 43.055881 -95.17507) (xy 84.927697 -95.17507)
			(xy 84.931732 -95.099366) (xy 84.943791 -95.024521) (xy 84.963737 -94.95138) (xy 84.991344 -94.880775)
			(xy 85.0263 -94.813504) (xy 85.068208 -94.750329) (xy 85.116594 -94.691967) (xy 85.17091 -94.639079)
			(xy 85.230539 -94.592264) (xy 85.294807 -94.552052) (xy 85.362984 -94.5189) (xy 85.4343 -94.493182)
			(xy 85.507945 -94.47519) (xy 85.583085 -94.465128) (xy 85.658869 -94.463109) (xy 85.734439 -94.469158)
			(xy 85.808937 -94.483205) (xy 85.88152 -94.505091) (xy 85.951366 -94.534568) (xy 86.017683 -94.571303)
			(xy 86.079719 -94.614878) (xy 86.136772 -94.6648) (xy 86.188196 -94.720504) (xy 86.233407 -94.781359)
			(xy 86.271894 -94.846674) (xy 86.30322 -94.91571) (xy 86.32703 -94.987685) (xy 86.343055 -95.061783)
			(xy 86.351114 -95.137164) (xy 86.351618 -95.17507) (xy 87.467697 -95.17507) (xy 87.471732 -95.099366)
			(xy 87.483791 -95.024521) (xy 87.503737 -94.95138) (xy 87.531344 -94.880775) (xy 87.5663 -94.813504)
			(xy 87.608208 -94.750329) (xy 87.656594 -94.691967) (xy 87.71091 -94.639079) (xy 87.770539 -94.592264)
			(xy 87.834807 -94.552052) (xy 87.902984 -94.5189) (xy 87.9743 -94.493182) (xy 88.047945 -94.47519)
			(xy 88.123085 -94.465128) (xy 88.198869 -94.463109) (xy 88.274439 -94.469158) (xy 88.348937 -94.483205)
			(xy 88.42152 -94.505091) (xy 88.491366 -94.534568) (xy 88.557683 -94.571303) (xy 88.619719 -94.614878)
			(xy 88.676772 -94.6648) (xy 88.728196 -94.720504) (xy 88.773407 -94.781359) (xy 88.811894 -94.846674)
			(xy 88.84322 -94.91571) (xy 88.86703 -94.987685) (xy 88.883055 -95.061783) (xy 88.891114 -95.137164)
			(xy 88.891618 -95.17507) (xy 90.007697 -95.17507) (xy 90.011732 -95.099366) (xy 90.023791 -95.024521)
			(xy 90.043737 -94.95138) (xy 90.071344 -94.880775) (xy 90.1063 -94.813504) (xy 90.148208 -94.750329)
			(xy 90.196594 -94.691967) (xy 90.25091 -94.639079) (xy 90.310539 -94.592264) (xy 90.374807 -94.552052)
			(xy 90.442984 -94.5189) (xy 90.5143 -94.493182) (xy 90.587945 -94.47519) (xy 90.663085 -94.465128)
			(xy 90.738869 -94.463109) (xy 90.814439 -94.469158) (xy 90.888937 -94.483205) (xy 90.96152 -94.505091)
			(xy 91.031366 -94.534568) (xy 91.097683 -94.571303) (xy 91.159719 -94.614878) (xy 91.216772 -94.6648)
			(xy 91.268196 -94.720504) (xy 91.313407 -94.781359) (xy 91.351894 -94.846674) (xy 91.38322 -94.91571)
			(xy 91.40703 -94.987685) (xy 91.423055 -95.061783) (xy 91.431114 -95.137164) (xy 91.431618 -95.17507)
			(xy 91.431114 -95.212976) (xy 91.423055 -95.288357) (xy 91.40703 -95.362455) (xy 91.38322 -95.43443)
			(xy 91.351894 -95.503466) (xy 91.313407 -95.568781) (xy 91.268196 -95.629636) (xy 91.216772 -95.68534)
			(xy 91.159719 -95.735262) (xy 91.097683 -95.778837) (xy 91.031366 -95.815572) (xy 90.96152 -95.845049)
			(xy 90.888937 -95.866935) (xy 90.814439 -95.880982) (xy 90.738869 -95.887031) (xy 90.663085 -95.885012)
			(xy 90.587945 -95.87495) (xy 90.5143 -95.856958) (xy 90.442984 -95.83124) (xy 90.374807 -95.798088)
			(xy 90.310539 -95.757876) (xy 90.25091 -95.711061) (xy 90.196594 -95.658173) (xy 90.148208 -95.599811)
			(xy 90.1063 -95.536636) (xy 90.071344 -95.469365) (xy 90.043737 -95.39876) (xy 90.023791 -95.325619)
			(xy 90.011732 -95.250774) (xy 90.007697 -95.17507) (xy 88.891618 -95.17507) (xy 88.891114 -95.212976)
			(xy 88.883055 -95.288357) (xy 88.86703 -95.362455) (xy 88.84322 -95.43443) (xy 88.811894 -95.503466)
			(xy 88.773407 -95.568781) (xy 88.728196 -95.629636) (xy 88.676772 -95.68534) (xy 88.619719 -95.735262)
			(xy 88.557683 -95.778837) (xy 88.491366 -95.815572) (xy 88.42152 -95.845049) (xy 88.348937 -95.866935)
			(xy 88.274439 -95.880982) (xy 88.198869 -95.887031) (xy 88.123085 -95.885012) (xy 88.047945 -95.87495)
			(xy 87.9743 -95.856958) (xy 87.902984 -95.83124) (xy 87.834807 -95.798088) (xy 87.770539 -95.757876)
			(xy 87.71091 -95.711061) (xy 87.656594 -95.658173) (xy 87.608208 -95.599811) (xy 87.5663 -95.536636)
			(xy 87.531344 -95.469365) (xy 87.503737 -95.39876) (xy 87.483791 -95.325619) (xy 87.471732 -95.250774)
			(xy 87.467697 -95.17507) (xy 86.351618 -95.17507) (xy 86.351114 -95.212976) (xy 86.343055 -95.288357)
			(xy 86.32703 -95.362455) (xy 86.30322 -95.43443) (xy 86.271894 -95.503466) (xy 86.233407 -95.568781)
			(xy 86.188196 -95.629636) (xy 86.136772 -95.68534) (xy 86.079719 -95.735262) (xy 86.017683 -95.778837)
			(xy 85.951366 -95.815572) (xy 85.88152 -95.845049) (xy 85.808937 -95.866935) (xy 85.734439 -95.880982)
			(xy 85.658869 -95.887031) (xy 85.583085 -95.885012) (xy 85.507945 -95.87495) (xy 85.4343 -95.856958)
			(xy 85.362984 -95.83124) (xy 85.294807 -95.798088) (xy 85.230539 -95.757876) (xy 85.17091 -95.711061)
			(xy 85.116594 -95.658173) (xy 85.068208 -95.599811) (xy 85.0263 -95.536636) (xy 84.991344 -95.469365)
			(xy 84.963737 -95.39876) (xy 84.943791 -95.325619) (xy 84.931732 -95.250774) (xy 84.927697 -95.17507)
			(xy 43.055881 -95.17507) (xy 43.063764 -95.193218) (xy 43.102213 -95.301403) (xy 43.13319 -95.41196)
			(xy 43.156549 -95.524372) (xy 43.172183 -95.638117) (xy 43.180018 -95.752663) (xy 43.180508 -95.81007)
			(xy 43.180381 -95.843251) (xy 43.177842 -95.909565) (xy 43.175428 -95.942658) (xy 43.170272 -96.000942)
			(xy 43.152948 -96.116671) (xy 43.127616 -96.230914) (xy 43.094401 -96.343119) (xy 43.056327 -96.44507)
			(xy 86.197697 -96.44507) (xy 86.201732 -96.369366) (xy 86.213791 -96.294521) (xy 86.233737 -96.22138)
			(xy 86.261344 -96.150775) (xy 86.2963 -96.083504) (xy 86.338208 -96.020329) (xy 86.386594 -95.961967)
			(xy 86.44091 -95.909079) (xy 86.500539 -95.862264) (xy 86.564807 -95.822052) (xy 86.632984 -95.7889)
			(xy 86.7043 -95.763182) (xy 86.777945 -95.74519) (xy 86.853085 -95.735128) (xy 86.928869 -95.733109)
			(xy 87.004439 -95.739158) (xy 87.078937 -95.753205) (xy 87.15152 -95.775091) (xy 87.221366 -95.804568)
			(xy 87.287683 -95.841303) (xy 87.349719 -95.884878) (xy 87.406772 -95.9348) (xy 87.458196 -95.990504)
			(xy 87.503407 -96.051359) (xy 87.541894 -96.116674) (xy 87.57322 -96.18571) (xy 87.59703 -96.257685)
			(xy 87.613055 -96.331783) (xy 87.621114 -96.407164) (xy 87.621618 -96.44507) (xy 88.737697 -96.44507)
			(xy 88.741732 -96.369366) (xy 88.753791 -96.294521) (xy 88.773737 -96.22138) (xy 88.801344 -96.150775)
			(xy 88.8363 -96.083504) (xy 88.878208 -96.020329) (xy 88.926594 -95.961967) (xy 88.98091 -95.909079)
			(xy 89.040539 -95.862264) (xy 89.104807 -95.822052) (xy 89.172984 -95.7889) (xy 89.2443 -95.763182)
			(xy 89.317945 -95.74519) (xy 89.393085 -95.735128) (xy 89.468869 -95.733109) (xy 89.544439 -95.739158)
			(xy 89.618937 -95.753205) (xy 89.69152 -95.775091) (xy 89.761366 -95.804568) (xy 89.827683 -95.841303)
			(xy 89.889719 -95.884878) (xy 89.946772 -95.9348) (xy 89.998196 -95.990504) (xy 90.043407 -96.051359)
			(xy 90.081894 -96.116674) (xy 90.11322 -96.18571) (xy 90.13703 -96.257685) (xy 90.153055 -96.331783)
			(xy 90.161114 -96.407164) (xy 90.161618 -96.44507) (xy 91.277697 -96.44507) (xy 91.281732 -96.369366)
			(xy 91.293791 -96.294521) (xy 91.313737 -96.22138) (xy 91.341344 -96.150775) (xy 91.3763 -96.083504)
			(xy 91.418208 -96.020329) (xy 91.466594 -95.961967) (xy 91.52091 -95.909079) (xy 91.580539 -95.862264)
			(xy 91.644807 -95.822052) (xy 91.712984 -95.7889) (xy 91.7843 -95.763182) (xy 91.857945 -95.74519)
			(xy 91.933085 -95.735128) (xy 92.008869 -95.733109) (xy 92.084439 -95.739158) (xy 92.158937 -95.753205)
			(xy 92.23152 -95.775091) (xy 92.301366 -95.804568) (xy 92.367683 -95.841303) (xy 92.429719 -95.884878)
			(xy 92.486772 -95.9348) (xy 92.538196 -95.990504) (xy 92.583407 -96.051359) (xy 92.621894 -96.116674)
			(xy 92.65322 -96.18571) (xy 92.67703 -96.257685) (xy 92.693055 -96.331783) (xy 92.701114 -96.407164)
			(xy 92.701618 -96.44507) (xy 92.701114 -96.482976) (xy 92.693055 -96.558357) (xy 92.67703 -96.632455)
			(xy 92.65322 -96.70443) (xy 92.621894 -96.773466) (xy 92.583407 -96.838781) (xy 92.538196 -96.899636)
			(xy 92.486772 -96.95534) (xy 92.429719 -97.005262) (xy 92.367683 -97.048837) (xy 92.301366 -97.085572)
			(xy 92.23152 -97.115049) (xy 92.158937 -97.136935) (xy 92.084439 -97.150982) (xy 92.008869 -97.157031)
			(xy 91.933085 -97.155012) (xy 91.857945 -97.14495) (xy 91.7843 -97.126958) (xy 91.712984 -97.10124)
			(xy 91.644807 -97.068088) (xy 91.580539 -97.027876) (xy 91.52091 -96.981061) (xy 91.466594 -96.928173)
			(xy 91.418208 -96.869811) (xy 91.3763 -96.806636) (xy 91.341344 -96.739365) (xy 91.313737 -96.66876)
			(xy 91.293791 -96.595619) (xy 91.281732 -96.520774) (xy 91.277697 -96.44507) (xy 90.161618 -96.44507)
			(xy 90.161114 -96.482976) (xy 90.153055 -96.558357) (xy 90.13703 -96.632455) (xy 90.11322 -96.70443)
			(xy 90.081894 -96.773466) (xy 90.043407 -96.838781) (xy 89.998196 -96.899636) (xy 89.946772 -96.95534)
			(xy 89.889719 -97.005262) (xy 89.827683 -97.048837) (xy 89.761366 -97.085572) (xy 89.69152 -97.115049)
			(xy 89.618937 -97.136935) (xy 89.544439 -97.150982) (xy 89.468869 -97.157031) (xy 89.393085 -97.155012)
			(xy 89.317945 -97.14495) (xy 89.2443 -97.126958) (xy 89.172984 -97.10124) (xy 89.104807 -97.068088)
			(xy 89.040539 -97.027876) (xy 88.98091 -96.981061) (xy 88.926594 -96.928173) (xy 88.878208 -96.869811)
			(xy 88.8363 -96.806636) (xy 88.801344 -96.739365) (xy 88.773737 -96.66876) (xy 88.753791 -96.595619)
			(xy 88.741732 -96.520774) (xy 88.737697 -96.44507) (xy 87.621618 -96.44507) (xy 87.621114 -96.482976)
			(xy 87.613055 -96.558357) (xy 87.59703 -96.632455) (xy 87.57322 -96.70443) (xy 87.541894 -96.773466)
			(xy 87.503407 -96.838781) (xy 87.458196 -96.899636) (xy 87.406772 -96.95534) (xy 87.349719 -97.005262)
			(xy 87.287683 -97.048837) (xy 87.221366 -97.085572) (xy 87.15152 -97.115049) (xy 87.078937 -97.136935)
			(xy 87.004439 -97.150982) (xy 86.928869 -97.157031) (xy 86.853085 -97.155012) (xy 86.777945 -97.14495)
			(xy 86.7043 -97.126958) (xy 86.632984 -97.10124) (xy 86.564807 -97.068088) (xy 86.500539 -97.027876)
			(xy 86.44091 -96.981061) (xy 86.386594 -96.928173) (xy 86.338208 -96.869811) (xy 86.2963 -96.806636)
			(xy 86.261344 -96.739365) (xy 86.233737 -96.66876) (xy 86.213791 -96.595619) (xy 86.201732 -96.520774)
			(xy 86.197697 -96.44507) (xy 43.056327 -96.44507) (xy 43.055094 -96.448372) (xy 43.328336 -96.448372)
			(xy 44.751244 -96.448372) (xy 44.751244 -97.16008) (xy 45.867577 -97.16008) (xy 45.871612 -97.084376)
			(xy 45.883671 -97.009531) (xy 45.903617 -96.93639) (xy 45.931224 -96.865785) (xy 45.96618 -96.798514)
			(xy 46.008088 -96.735339) (xy 46.056474 -96.676977) (xy 46.11079 -96.624089) (xy 46.170419 -96.577274)
			(xy 46.234687 -96.537062) (xy 46.302864 -96.50391) (xy 46.37418 -96.478192) (xy 46.447825 -96.4602)
			(xy 46.522965 -96.450138) (xy 46.598749 -96.448119) (xy 46.674319 -96.454168) (xy 46.748817 -96.468215)
			(xy 46.8214 -96.490101) (xy 46.891246 -96.519578) (xy 46.957563 -96.556313) (xy 47.019599 -96.599888)
			(xy 47.076652 -96.64981) (xy 47.128076 -96.705514) (xy 47.173287 -96.766369) (xy 47.211774 -96.831684)
			(xy 47.2431 -96.90072) (xy 47.26691 -96.972695) (xy 47.282935 -97.046793) (xy 47.290994 -97.122174)
			(xy 47.291498 -97.16008) (xy 48.407577 -97.16008) (xy 48.411612 -97.084376) (xy 48.423671 -97.009531)
			(xy 48.443617 -96.93639) (xy 48.471224 -96.865785) (xy 48.50618 -96.798514) (xy 48.548088 -96.735339)
			(xy 48.596474 -96.676977) (xy 48.65079 -96.624089) (xy 48.710419 -96.577274) (xy 48.774687 -96.537062)
			(xy 48.842864 -96.50391) (xy 48.91418 -96.478192) (xy 48.987825 -96.4602) (xy 49.062965 -96.450138)
			(xy 49.138749 -96.448119) (xy 49.214319 -96.454168) (xy 49.288817 -96.468215) (xy 49.3614 -96.490101)
			(xy 49.431246 -96.519578) (xy 49.497563 -96.556313) (xy 49.559599 -96.599888) (xy 49.616652 -96.64981)
			(xy 49.668076 -96.705514) (xy 49.713287 -96.766369) (xy 49.751774 -96.831684) (xy 49.7831 -96.90072)
			(xy 49.80691 -96.972695) (xy 49.822935 -97.046793) (xy 49.830994 -97.122174) (xy 49.831498 -97.16008)
			(xy 50.947577 -97.16008) (xy 50.951612 -97.084376) (xy 50.963671 -97.009531) (xy 50.983617 -96.93639)
			(xy 51.011224 -96.865785) (xy 51.04618 -96.798514) (xy 51.088088 -96.735339) (xy 51.136474 -96.676977)
			(xy 51.19079 -96.624089) (xy 51.250419 -96.577274) (xy 51.314687 -96.537062) (xy 51.382864 -96.50391)
			(xy 51.45418 -96.478192) (xy 51.527825 -96.4602) (xy 51.602965 -96.450138) (xy 51.678749 -96.448119)
			(xy 51.754319 -96.454168) (xy 51.828817 -96.468215) (xy 51.9014 -96.490101) (xy 51.971246 -96.519578)
			(xy 52.037563 -96.556313) (xy 52.099599 -96.599888) (xy 52.156652 -96.64981) (xy 52.208076 -96.705514)
			(xy 52.253287 -96.766369) (xy 52.291774 -96.831684) (xy 52.3231 -96.90072) (xy 52.34691 -96.972695)
			(xy 52.362935 -97.046793) (xy 52.370994 -97.122174) (xy 52.371498 -97.16008) (xy 53.487577 -97.16008)
			(xy 53.491612 -97.084376) (xy 53.503671 -97.009531) (xy 53.523617 -96.93639) (xy 53.551224 -96.865785)
			(xy 53.58618 -96.798514) (xy 53.628088 -96.735339) (xy 53.676474 -96.676977) (xy 53.73079 -96.624089)
			(xy 53.790419 -96.577274) (xy 53.854687 -96.537062) (xy 53.922864 -96.50391) (xy 53.99418 -96.478192)
			(xy 54.067825 -96.4602) (xy 54.142965 -96.450138) (xy 54.218749 -96.448119) (xy 54.294319 -96.454168)
			(xy 54.368817 -96.468215) (xy 54.4414 -96.490101) (xy 54.511246 -96.519578) (xy 54.577563 -96.556313)
			(xy 54.639599 -96.599888) (xy 54.696652 -96.64981) (xy 54.748076 -96.705514) (xy 54.793287 -96.766369)
			(xy 54.831774 -96.831684) (xy 54.8631 -96.90072) (xy 54.88691 -96.972695) (xy 54.902935 -97.046793)
			(xy 54.910994 -97.122174) (xy 54.911498 -97.16008) (xy 56.027577 -97.16008) (xy 56.031612 -97.084376)
			(xy 56.043671 -97.009531) (xy 56.063617 -96.93639) (xy 56.091224 -96.865785) (xy 56.12618 -96.798514)
			(xy 56.168088 -96.735339) (xy 56.216474 -96.676977) (xy 56.27079 -96.624089) (xy 56.330419 -96.577274)
			(xy 56.394687 -96.537062) (xy 56.462864 -96.50391) (xy 56.53418 -96.478192) (xy 56.607825 -96.4602)
			(xy 56.682965 -96.450138) (xy 56.758749 -96.448119) (xy 56.834319 -96.454168) (xy 56.908817 -96.468215)
			(xy 56.9814 -96.490101) (xy 57.051246 -96.519578) (xy 57.117563 -96.556313) (xy 57.179599 -96.599888)
			(xy 57.236652 -96.64981) (xy 57.288076 -96.705514) (xy 57.333287 -96.766369) (xy 57.371774 -96.831684)
			(xy 57.4031 -96.90072) (xy 57.42691 -96.972695) (xy 57.442935 -97.046793) (xy 57.450994 -97.122174)
			(xy 57.451498 -97.16008) (xy 58.567577 -97.16008) (xy 58.571612 -97.084376) (xy 58.583671 -97.009531)
			(xy 58.603617 -96.93639) (xy 58.631224 -96.865785) (xy 58.66618 -96.798514) (xy 58.708088 -96.735339)
			(xy 58.756474 -96.676977) (xy 58.81079 -96.624089) (xy 58.870419 -96.577274) (xy 58.934687 -96.537062)
			(xy 59.002864 -96.50391) (xy 59.07418 -96.478192) (xy 59.147825 -96.4602) (xy 59.222965 -96.450138)
			(xy 59.298749 -96.448119) (xy 59.374319 -96.454168) (xy 59.448817 -96.468215) (xy 59.5214 -96.490101)
			(xy 59.591246 -96.519578) (xy 59.657563 -96.556313) (xy 59.719599 -96.599888) (xy 59.776652 -96.64981)
			(xy 59.828076 -96.705514) (xy 59.873287 -96.766369) (xy 59.911774 -96.831684) (xy 59.9431 -96.90072)
			(xy 59.96691 -96.972695) (xy 59.982935 -97.046793) (xy 59.990994 -97.122174) (xy 59.991498 -97.16008)
			(xy 61.107577 -97.16008) (xy 61.111612 -97.084376) (xy 61.123671 -97.009531) (xy 61.143617 -96.93639)
			(xy 61.171224 -96.865785) (xy 61.20618 -96.798514) (xy 61.248088 -96.735339) (xy 61.296474 -96.676977)
			(xy 61.35079 -96.624089) (xy 61.410419 -96.577274) (xy 61.474687 -96.537062) (xy 61.542864 -96.50391)
			(xy 61.61418 -96.478192) (xy 61.687825 -96.4602) (xy 61.762965 -96.450138) (xy 61.838749 -96.448119)
			(xy 61.914319 -96.454168) (xy 61.988817 -96.468215) (xy 62.0614 -96.490101) (xy 62.131246 -96.519578)
			(xy 62.197563 -96.556313) (xy 62.259599 -96.599888) (xy 62.316652 -96.64981) (xy 62.368076 -96.705514)
			(xy 62.413287 -96.766369) (xy 62.451774 -96.831684) (xy 62.4831 -96.90072) (xy 62.50691 -96.972695)
			(xy 62.522935 -97.046793) (xy 62.530994 -97.122174) (xy 62.531498 -97.16008) (xy 62.530994 -97.197986)
			(xy 62.522935 -97.273367) (xy 62.50691 -97.347465) (xy 62.4831 -97.41944) (xy 62.451774 -97.488476)
			(xy 62.413287 -97.553791) (xy 62.368076 -97.614646) (xy 62.316652 -97.67035) (xy 62.265544 -97.71507)
			(xy 84.927697 -97.71507) (xy 84.931732 -97.639366) (xy 84.943791 -97.564521) (xy 84.963737 -97.49138)
			(xy 84.991344 -97.420775) (xy 85.0263 -97.353504) (xy 85.068208 -97.290329) (xy 85.116594 -97.231967)
			(xy 85.17091 -97.179079) (xy 85.230539 -97.132264) (xy 85.294807 -97.092052) (xy 85.362984 -97.0589)
			(xy 85.4343 -97.033182) (xy 85.507945 -97.01519) (xy 85.583085 -97.005128) (xy 85.658869 -97.003109)
			(xy 85.734439 -97.009158) (xy 85.808937 -97.023205) (xy 85.88152 -97.045091) (xy 85.951366 -97.074568)
			(xy 86.017683 -97.111303) (xy 86.079719 -97.154878) (xy 86.136772 -97.2048) (xy 86.188196 -97.260504)
			(xy 86.233407 -97.321359) (xy 86.271894 -97.386674) (xy 86.30322 -97.45571) (xy 86.32703 -97.527685)
			(xy 86.343055 -97.601783) (xy 86.351114 -97.677164) (xy 86.351618 -97.71507) (xy 87.467697 -97.71507)
			(xy 87.471732 -97.639366) (xy 87.483791 -97.564521) (xy 87.503737 -97.49138) (xy 87.531344 -97.420775)
			(xy 87.5663 -97.353504) (xy 87.608208 -97.290329) (xy 87.656594 -97.231967) (xy 87.71091 -97.179079)
			(xy 87.770539 -97.132264) (xy 87.834807 -97.092052) (xy 87.902984 -97.0589) (xy 87.9743 -97.033182)
			(xy 88.047945 -97.01519) (xy 88.123085 -97.005128) (xy 88.198869 -97.003109) (xy 88.274439 -97.009158)
			(xy 88.348937 -97.023205) (xy 88.42152 -97.045091) (xy 88.491366 -97.074568) (xy 88.557683 -97.111303)
			(xy 88.619719 -97.154878) (xy 88.676772 -97.2048) (xy 88.728196 -97.260504) (xy 88.773407 -97.321359)
			(xy 88.811894 -97.386674) (xy 88.84322 -97.45571) (xy 88.86703 -97.527685) (xy 88.883055 -97.601783)
			(xy 88.891114 -97.677164) (xy 88.891618 -97.71507) (xy 90.007697 -97.71507) (xy 90.011732 -97.639366)
			(xy 90.023791 -97.564521) (xy 90.043737 -97.49138) (xy 90.071344 -97.420775) (xy 90.1063 -97.353504)
			(xy 90.148208 -97.290329) (xy 90.196594 -97.231967) (xy 90.25091 -97.179079) (xy 90.310539 -97.132264)
			(xy 90.374807 -97.092052) (xy 90.442984 -97.0589) (xy 90.5143 -97.033182) (xy 90.587945 -97.01519)
			(xy 90.663085 -97.005128) (xy 90.738869 -97.003109) (xy 90.814439 -97.009158) (xy 90.888937 -97.023205)
			(xy 90.96152 -97.045091) (xy 91.031366 -97.074568) (xy 91.097683 -97.111303) (xy 91.159719 -97.154878)
			(xy 91.165664 -97.16008) (xy 93.154506 -97.16008) (xy 93.158522 -97.04381) (xy 93.170549 -96.928095)
			(xy 93.190531 -96.813485) (xy 93.218373 -96.700526) (xy 93.253942 -96.589758) (xy 93.297068 -96.481707)
			(xy 93.347545 -96.376889) (xy 93.405134 -96.275804) (xy 93.46956 -96.178932) (xy 93.540515 -96.086736)
			(xy 93.617662 -95.999655) (xy 93.700633 -95.918104) (xy 93.789033 -95.842472) (xy 93.88244 -95.773118)
			(xy 93.980409 -95.710375) (xy 94.082473 -95.654539) (xy 94.188147 -95.605878) (xy 94.296926 -95.564624)
			(xy 94.408291 -95.530973) (xy 94.521714 -95.505085) (xy 94.636651 -95.487084) (xy 94.752557 -95.477055)
			(xy 94.868879 -95.475047) (xy 94.985062 -95.481069) (xy 95.100553 -95.495092) (xy 95.214801 -95.51705)
			(xy 95.327262 -95.546837) (xy 95.4374 -95.584312) (xy 95.54469 -95.629297) (xy 95.648621 -95.681576)
			(xy 95.748697 -95.740901) (xy 95.844443 -95.806989) (xy 95.9354 -95.879525) (xy 96.021136 -95.958164)
			(xy 96.101243 -96.04253) (xy 96.175339 -96.132222) (xy 96.243069 -96.226812) (xy 96.304113 -96.32585)
			(xy 96.358178 -96.428863) (xy 96.405008 -96.53536) (xy 96.444379 -96.644835) (xy 96.476103 -96.756765)
			(xy 96.500029 -96.870617) (xy 96.516043 -96.985849) (xy 96.52407 -97.101911) (xy 96.524572 -97.16008)
			(xy 96.52407 -97.218249) (xy 96.516043 -97.334311) (xy 96.500029 -97.449543) (xy 96.476103 -97.563395)
			(xy 96.444379 -97.675325) (xy 96.405008 -97.7848) (xy 96.358178 -97.891297) (xy 96.304113 -97.99431)
			(xy 96.243069 -98.093348) (xy 96.175339 -98.187938) (xy 96.101243 -98.27763) (xy 96.021136 -98.361996)
			(xy 95.9354 -98.440635) (xy 95.844443 -98.513171) (xy 95.748697 -98.579259) (xy 95.648621 -98.638584)
			(xy 95.54469 -98.690863) (xy 95.4374 -98.735848) (xy 95.327262 -98.773323) (xy 95.214801 -98.80311)
			(xy 95.100553 -98.825068) (xy 94.985062 -98.839091) (xy 94.868879 -98.845113) (xy 94.752557 -98.843105)
			(xy 94.636651 -98.833076) (xy 94.521714 -98.815075) (xy 94.408291 -98.789187) (xy 94.296926 -98.755536)
			(xy 94.188147 -98.714282) (xy 94.082473 -98.665621) (xy 93.980409 -98.609785) (xy 93.88244 -98.547042)
			(xy 93.789033 -98.477688) (xy 93.700633 -98.402056) (xy 93.617662 -98.320505) (xy 93.540515 -98.233424)
			(xy 93.46956 -98.141228) (xy 93.405134 -98.044356) (xy 93.347545 -97.943271) (xy 93.297068 -97.838453)
			(xy 93.253942 -97.730402) (xy 93.218373 -97.619634) (xy 93.190531 -97.506675) (xy 93.170549 -97.392065)
			(xy 93.158522 -97.27635) (xy 93.154506 -97.16008) (xy 91.165664 -97.16008) (xy 91.216772 -97.2048)
			(xy 91.268196 -97.260504) (xy 91.313407 -97.321359) (xy 91.351894 -97.386674) (xy 91.38322 -97.45571)
			(xy 91.40703 -97.527685) (xy 91.423055 -97.601783) (xy 91.431114 -97.677164) (xy 91.431618 -97.71507)
			(xy 91.431114 -97.752976) (xy 91.423055 -97.828357) (xy 91.40703 -97.902455) (xy 91.38322 -97.97443)
			(xy 91.351894 -98.043466) (xy 91.313407 -98.108781) (xy 91.268196 -98.169636) (xy 91.216772 -98.22534)
			(xy 91.159719 -98.275262) (xy 91.097683 -98.318837) (xy 91.031366 -98.355572) (xy 90.96152 -98.385049)
			(xy 90.888937 -98.406935) (xy 90.814439 -98.420982) (xy 90.738869 -98.427031) (xy 90.663085 -98.425012)
			(xy 90.587945 -98.41495) (xy 90.5143 -98.396958) (xy 90.442984 -98.37124) (xy 90.374807 -98.338088)
			(xy 90.310539 -98.297876) (xy 90.25091 -98.251061) (xy 90.196594 -98.198173) (xy 90.148208 -98.139811)
			(xy 90.1063 -98.076636) (xy 90.071344 -98.009365) (xy 90.043737 -97.93876) (xy 90.023791 -97.865619)
			(xy 90.011732 -97.790774) (xy 90.007697 -97.71507) (xy 88.891618 -97.71507) (xy 88.891114 -97.752976)
			(xy 88.883055 -97.828357) (xy 88.86703 -97.902455) (xy 88.84322 -97.97443) (xy 88.811894 -98.043466)
			(xy 88.773407 -98.108781) (xy 88.728196 -98.169636) (xy 88.676772 -98.22534) (xy 88.619719 -98.275262)
			(xy 88.557683 -98.318837) (xy 88.491366 -98.355572) (xy 88.42152 -98.385049) (xy 88.348937 -98.406935)
			(xy 88.274439 -98.420982) (xy 88.198869 -98.427031) (xy 88.123085 -98.425012) (xy 88.047945 -98.41495)
			(xy 87.9743 -98.396958) (xy 87.902984 -98.37124) (xy 87.834807 -98.338088) (xy 87.770539 -98.297876)
			(xy 87.71091 -98.251061) (xy 87.656594 -98.198173) (xy 87.608208 -98.139811) (xy 87.5663 -98.076636)
			(xy 87.531344 -98.009365) (xy 87.503737 -97.93876) (xy 87.483791 -97.865619) (xy 87.471732 -97.790774)
			(xy 87.467697 -97.71507) (xy 86.351618 -97.71507) (xy 86.351114 -97.752976) (xy 86.343055 -97.828357)
			(xy 86.32703 -97.902455) (xy 86.30322 -97.97443) (xy 86.271894 -98.043466) (xy 86.233407 -98.108781)
			(xy 86.188196 -98.169636) (xy 86.136772 -98.22534) (xy 86.079719 -98.275262) (xy 86.017683 -98.318837)
			(xy 85.951366 -98.355572) (xy 85.88152 -98.385049) (xy 85.808937 -98.406935) (xy 85.734439 -98.420982)
			(xy 85.658869 -98.427031) (xy 85.583085 -98.425012) (xy 85.507945 -98.41495) (xy 85.4343 -98.396958)
			(xy 85.362984 -98.37124) (xy 85.294807 -98.338088) (xy 85.230539 -98.297876) (xy 85.17091 -98.251061)
			(xy 85.116594 -98.198173) (xy 85.068208 -98.139811) (xy 85.0263 -98.076636) (xy 84.991344 -98.009365)
			(xy 84.963737 -97.93876) (xy 84.943791 -97.865619) (xy 84.931732 -97.790774) (xy 84.927697 -97.71507)
			(xy 62.265544 -97.71507) (xy 62.259599 -97.720272) (xy 62.197563 -97.763847) (xy 62.131246 -97.800582)
			(xy 62.0614 -97.830059) (xy 61.988817 -97.851945) (xy 61.914319 -97.865992) (xy 61.838749 -97.872041)
			(xy 61.762965 -97.870022) (xy 61.687825 -97.85996) (xy 61.61418 -97.841968) (xy 61.542864 -97.81625)
			(xy 61.474687 -97.783098) (xy 61.410419 -97.742886) (xy 61.35079 -97.696071) (xy 61.296474 -97.643183)
			(xy 61.248088 -97.584821) (xy 61.20618 -97.521646) (xy 61.171224 -97.454375) (xy 61.143617 -97.38377)
			(xy 61.123671 -97.310629) (xy 61.111612 -97.235784) (xy 61.107577 -97.16008) (xy 59.991498 -97.16008)
			(xy 59.990994 -97.197986) (xy 59.982935 -97.273367) (xy 59.96691 -97.347465) (xy 59.9431 -97.41944)
			(xy 59.911774 -97.488476) (xy 59.873287 -97.553791) (xy 59.828076 -97.614646) (xy 59.776652 -97.67035)
			(xy 59.719599 -97.720272) (xy 59.657563 -97.763847) (xy 59.591246 -97.800582) (xy 59.5214 -97.830059)
			(xy 59.448817 -97.851945) (xy 59.374319 -97.865992) (xy 59.298749 -97.872041) (xy 59.222965 -97.870022)
			(xy 59.147825 -97.85996) (xy 59.07418 -97.841968) (xy 59.002864 -97.81625) (xy 58.934687 -97.783098)
			(xy 58.870419 -97.742886) (xy 58.81079 -97.696071) (xy 58.756474 -97.643183) (xy 58.708088 -97.584821)
			(xy 58.66618 -97.521646) (xy 58.631224 -97.454375) (xy 58.603617 -97.38377) (xy 58.583671 -97.310629)
			(xy 58.571612 -97.235784) (xy 58.567577 -97.16008) (xy 57.451498 -97.16008) (xy 57.450994 -97.197986)
			(xy 57.442935 -97.273367) (xy 57.42691 -97.347465) (xy 57.4031 -97.41944) (xy 57.371774 -97.488476)
			(xy 57.333287 -97.553791) (xy 57.288076 -97.614646) (xy 57.236652 -97.67035) (xy 57.179599 -97.720272)
			(xy 57.117563 -97.763847) (xy 57.051246 -97.800582) (xy 56.9814 -97.830059) (xy 56.908817 -97.851945)
			(xy 56.834319 -97.865992) (xy 56.758749 -97.872041) (xy 56.682965 -97.870022) (xy 56.607825 -97.85996)
			(xy 56.53418 -97.841968) (xy 56.462864 -97.81625) (xy 56.394687 -97.783098) (xy 56.330419 -97.742886)
			(xy 56.27079 -97.696071) (xy 56.216474 -97.643183) (xy 56.168088 -97.584821) (xy 56.12618 -97.521646)
			(xy 56.091224 -97.454375) (xy 56.063617 -97.38377) (xy 56.043671 -97.310629) (xy 56.031612 -97.235784)
			(xy 56.027577 -97.16008) (xy 54.911498 -97.16008) (xy 54.910994 -97.197986) (xy 54.902935 -97.273367)
			(xy 54.88691 -97.347465) (xy 54.8631 -97.41944) (xy 54.831774 -97.488476) (xy 54.793287 -97.553791)
			(xy 54.748076 -97.614646) (xy 54.696652 -97.67035) (xy 54.639599 -97.720272) (xy 54.577563 -97.763847)
			(xy 54.511246 -97.800582) (xy 54.4414 -97.830059) (xy 54.368817 -97.851945) (xy 54.294319 -97.865992)
			(xy 54.218749 -97.872041) (xy 54.142965 -97.870022) (xy 54.067825 -97.85996) (xy 53.99418 -97.841968)
			(xy 53.922864 -97.81625) (xy 53.854687 -97.783098) (xy 53.790419 -97.742886) (xy 53.73079 -97.696071)
			(xy 53.676474 -97.643183) (xy 53.628088 -97.584821) (xy 53.58618 -97.521646) (xy 53.551224 -97.454375)
			(xy 53.523617 -97.38377) (xy 53.503671 -97.310629) (xy 53.491612 -97.235784) (xy 53.487577 -97.16008)
			(xy 52.371498 -97.16008) (xy 52.370994 -97.197986) (xy 52.362935 -97.273367) (xy 52.34691 -97.347465)
			(xy 52.3231 -97.41944) (xy 52.291774 -97.488476) (xy 52.253287 -97.553791) (xy 52.208076 -97.614646)
			(xy 52.156652 -97.67035) (xy 52.099599 -97.720272) (xy 52.037563 -97.763847) (xy 51.971246 -97.800582)
			(xy 51.9014 -97.830059) (xy 51.828817 -97.851945) (xy 51.754319 -97.865992) (xy 51.678749 -97.872041)
			(xy 51.602965 -97.870022) (xy 51.527825 -97.85996) (xy 51.45418 -97.841968) (xy 51.382864 -97.81625)
			(xy 51.314687 -97.783098) (xy 51.250419 -97.742886) (xy 51.19079 -97.696071) (xy 51.136474 -97.643183)
			(xy 51.088088 -97.584821) (xy 51.04618 -97.521646) (xy 51.011224 -97.454375) (xy 50.983617 -97.38377)
			(xy 50.963671 -97.310629) (xy 50.951612 -97.235784) (xy 50.947577 -97.16008) (xy 49.831498 -97.16008)
			(xy 49.830994 -97.197986) (xy 49.822935 -97.273367) (xy 49.80691 -97.347465) (xy 49.7831 -97.41944)
			(xy 49.751774 -97.488476) (xy 49.713287 -97.553791) (xy 49.668076 -97.614646) (xy 49.616652 -97.67035)
			(xy 49.559599 -97.720272) (xy 49.497563 -97.763847) (xy 49.431246 -97.800582) (xy 49.3614 -97.830059)
			(xy 49.288817 -97.851945) (xy 49.214319 -97.865992) (xy 49.138749 -97.872041) (xy 49.062965 -97.870022)
			(xy 48.987825 -97.85996) (xy 48.91418 -97.841968) (xy 48.842864 -97.81625) (xy 48.774687 -97.783098)
			(xy 48.710419 -97.742886) (xy 48.65079 -97.696071) (xy 48.596474 -97.643183) (xy 48.548088 -97.584821)
			(xy 48.50618 -97.521646) (xy 48.471224 -97.454375) (xy 48.443617 -97.38377) (xy 48.423671 -97.310629)
			(xy 48.411612 -97.235784) (xy 48.407577 -97.16008) (xy 47.291498 -97.16008) (xy 47.290994 -97.197986)
			(xy 47.282935 -97.273367) (xy 47.26691 -97.347465) (xy 47.2431 -97.41944) (xy 47.211774 -97.488476)
			(xy 47.173287 -97.553791) (xy 47.128076 -97.614646) (xy 47.076652 -97.67035) (xy 47.019599 -97.720272)
			(xy 46.957563 -97.763847) (xy 46.891246 -97.800582) (xy 46.8214 -97.830059) (xy 46.748817 -97.851945)
			(xy 46.674319 -97.865992) (xy 46.598749 -97.872041) (xy 46.522965 -97.870022) (xy 46.447825 -97.85996)
			(xy 46.37418 -97.841968) (xy 46.302864 -97.81625) (xy 46.234687 -97.783098) (xy 46.170419 -97.742886)
			(xy 46.11079 -97.696071) (xy 46.056474 -97.643183) (xy 46.008088 -97.584821) (xy 45.96618 -97.521646)
			(xy 45.931224 -97.454375) (xy 45.903617 -97.38377) (xy 45.883671 -97.310629) (xy 45.871612 -97.235784)
			(xy 45.867577 -97.16008) (xy 44.751244 -97.16008) (xy 44.751244 -97.871788) (xy 43.328336 -97.871788)
			(xy 43.328336 -96.448372) (xy 43.055094 -96.448372) (xy 43.053462 -96.452742) (xy 43.004999 -96.559253)
			(xy 42.949245 -96.662135) (xy 42.886471 -96.760891) (xy 42.816981 -96.855042) (xy 42.741111 -96.944132)
			(xy 42.659229 -97.027729) (xy 42.571732 -97.10543) (xy 42.479042 -97.176857) (xy 42.381609 -97.241665)
			(xy 42.279905 -97.29954) (xy 42.174422 -97.350202) (xy 42.065671 -97.393404) (xy 41.954179 -97.428939)
			(xy 41.840485 -97.456634) (xy 41.725141 -97.476354) (xy 41.608704 -97.488005) (xy 41.491739 -97.49153)
			(xy 41.374812 -97.486912) (xy 41.258489 -97.474173) (xy 41.143334 -97.453375) (xy 41.029905 -97.424618)
			(xy 40.91875 -97.388042) (xy 40.810407 -97.343825) (xy 40.705403 -97.292179) (xy 40.604244 -97.233356)
			(xy 40.507421 -97.16764) (xy 40.415403 -97.095349) (xy 40.328636 -97.016834) (xy 40.247539 -96.932474)
			(xy 40.172506 -96.842679) (xy 40.103899 -96.747883) (xy 40.042051 -96.648544) (xy 39.987262 -96.545145)
			(xy 39.939796 -96.438186) (xy 39.899884 -96.328185) (xy 39.86772 -96.215674) (xy 39.843457 -96.101199)
			(xy 39.827215 -95.985313) (xy 39.819072 -95.868579) (xy 39.818564 -95.81007) (xy 36.437073 -95.81007)
			(xy 36.431719 -95.828889) (xy 36.400327 -95.909921) (xy 36.361593 -95.98771) (xy 36.315846 -96.061594)
			(xy 36.263477 -96.130941) (xy 36.204933 -96.195161) (xy 36.140713 -96.253705) (xy 36.071366 -96.306074)
			(xy 35.997482 -96.351821) (xy 35.919693 -96.390555) (xy 35.838661 -96.421947) (xy 35.755079 -96.445728)
			(xy 35.669659 -96.461696) (xy 35.58313 -96.469714) (xy 35.49623 -96.469714) (xy 35.409701 -96.461696)
			(xy 35.324281 -96.445728) (xy 35.240699 -96.421947) (xy 35.159667 -96.390555) (xy 35.081878 -96.351821)
			(xy 35.007994 -96.306074) (xy 34.938647 -96.253705) (xy 34.874427 -96.195161) (xy 34.815883 -96.130941)
			(xy 34.763514 -96.061594) (xy 34.717767 -95.98771) (xy 34.679033 -95.909921) (xy 34.647641 -95.828889)
			(xy 34.62386 -95.745307) (xy 34.607892 -95.659887) (xy 34.599874 -95.573358) (xy 33.77692 -95.573358)
			(xy 33.77692 -98.113358) (xy 34.599874 -98.113358) (xy 34.599874 -98.026458) (xy 34.607892 -97.939929)
			(xy 34.62386 -97.854509) (xy 34.647641 -97.770927) (xy 34.679033 -97.689895) (xy 34.717767 -97.612106)
			(xy 34.763514 -97.538222) (xy 34.815883 -97.468875) (xy 34.874427 -97.404655) (xy 34.938647 -97.346111)
			(xy 35.007994 -97.293742) (xy 35.081878 -97.247995) (xy 35.159667 -97.209261) (xy 35.240699 -97.177869)
			(xy 35.324281 -97.154088) (xy 35.409701 -97.13812) (xy 35.49623 -97.130102) (xy 35.58313 -97.130102)
			(xy 35.669659 -97.13812) (xy 35.755079 -97.154088) (xy 35.838661 -97.177869) (xy 35.919693 -97.209261)
			(xy 35.997482 -97.247995) (xy 36.071366 -97.293742) (xy 36.140713 -97.346111) (xy 36.204933 -97.404655)
			(xy 36.263477 -97.468875) (xy 36.315846 -97.538222) (xy 36.361593 -97.612106) (xy 36.400327 -97.689895)
			(xy 36.431719 -97.770927) (xy 36.4555 -97.854509) (xy 36.471468 -97.939929) (xy 36.479486 -98.026458)
			(xy 36.479988 -98.069908) (xy 36.479486 -98.113358) (xy 36.471468 -98.199887) (xy 36.4555 -98.285307)
			(xy 36.431719 -98.368889) (xy 36.400327 -98.449921) (xy 36.361593 -98.52771) (xy 36.315846 -98.601594)
			(xy 36.263477 -98.670941) (xy 36.204933 -98.735161) (xy 36.140713 -98.793705) (xy 36.071366 -98.846074)
			(xy 35.997482 -98.891821) (xy 35.919693 -98.930555) (xy 35.838661 -98.961947) (xy 35.755079 -98.985728)
			(xy 35.669659 -99.001696) (xy 35.58313 -99.009714) (xy 35.49623 -99.009714) (xy 35.409701 -99.001696)
			(xy 35.324281 -98.985728) (xy 35.240699 -98.961947) (xy 35.159667 -98.930555) (xy 35.081878 -98.891821)
			(xy 35.007994 -98.846074) (xy 34.938647 -98.793705) (xy 34.874427 -98.735161) (xy 34.815883 -98.670941)
			(xy 34.763514 -98.601594) (xy 34.717767 -98.52771) (xy 34.679033 -98.449921) (xy 34.647641 -98.368889)
			(xy 34.62386 -98.285307) (xy 34.607892 -98.199887) (xy 34.599874 -98.113358) (xy 33.77692 -98.113358)
			(xy 33.77692 -100.609893) (xy 34.598816 -100.609893) (xy 34.60275 -100.523943) (xy 34.61452 -100.438712)
			(xy 34.634027 -100.354912) (xy 34.661107 -100.273245) (xy 34.695534 -100.194393) (xy 34.73702 -100.119015)
			(xy 34.785218 -100.047743) (xy 34.839726 -99.981171) (xy 34.900087 -99.919857) (xy 34.965797 -99.864314)
			(xy 35.036306 -99.815005) (xy 35.111025 -99.772344) (xy 35.189328 -99.736686) (xy 35.270561 -99.708331)
			(xy 35.354045 -99.687514) (xy 35.439082 -99.674411) (xy 35.524959 -99.669131) (xy 35.61096 -99.671718)
			(xy 35.696366 -99.682151) (xy 35.780461 -99.700341) (xy 35.862542 -99.726138) (xy 35.941924 -99.759324)
			(xy 36.017943 -99.799624) (xy 36.089962 -99.8467) (xy 36.15738 -99.900157) (xy 36.219632 -99.95955)
			(xy 36.276199 -100.024381) (xy 36.326607 -100.094109) (xy 36.370434 -100.168149) (xy 36.38931 -100.20681)
			(xy 36.405058 -100.23983) (xy 36.467034 -100.2792) (xy 38.683946 -100.2792) (xy 39.941246 -101.5365)
			(xy 39.968678 -101.546152) (xy 39.995412 -101.556004) (xy 40.045867 -101.582466) (xy 40.091825 -101.616138)
			(xy 40.132264 -101.65627) (xy 40.166285 -101.70197) (xy 40.193131 -101.752222) (xy 40.212204 -101.805908)
			(xy 40.223082 -101.861833) (xy 40.22552 -101.918754) (xy 40.219466 -101.975404) (xy 40.212772 -102.003098)
			(xy 40.212772 -102.027736) (xy 86.51062 -102.027736) (xy 86.514691 -101.972114) (xy 86.526817 -101.917677)
			(xy 86.54674 -101.865586) (xy 86.574036 -101.816951) (xy 86.608122 -101.772808) (xy 86.648271 -101.734099)
			(xy 86.693629 -101.701648) (xy 86.743229 -101.676147) (xy 86.796013 -101.65814) (xy 86.850856 -101.64801)
			(xy 86.90659 -101.645973) (xy 86.962027 -101.652073) (xy 87.015984 -101.666179) (xy 87.067313 -101.687991)
			(xy 87.114919 -101.717045) (xy 87.157787 -101.75272) (xy 87.195004 -101.794257) (xy 87.225777 -101.84077)
			(xy 87.249449 -101.891267) (xy 87.265517 -101.944674) (xy 87.273637 -101.99985) (xy 87.274146 -102.027736)
			(xy 87.273757 -102.049072) (xy 92.029532 -102.049072) (xy 92.033603 -101.99345) (xy 92.045729 -101.939013)
			(xy 92.065652 -101.886922) (xy 92.092948 -101.838287) (xy 92.127034 -101.794144) (xy 92.167183 -101.755435)
			(xy 92.212541 -101.722984) (xy 92.262141 -101.697483) (xy 92.314925 -101.679476) (xy 92.369768 -101.669346)
			(xy 92.425502 -101.667309) (xy 92.480939 -101.673409) (xy 92.534896 -101.687515) (xy 92.586225 -101.709327)
			(xy 92.633831 -101.738381) (xy 92.676699 -101.774056) (xy 92.713916 -101.815593) (xy 92.744689 -101.862106)
			(xy 92.768361 -101.912603) (xy 92.77228 -101.925628) (xy 94.75165 -101.925628) (xy 94.755721 -101.870006)
			(xy 94.767847 -101.815569) (xy 94.78777 -101.763478) (xy 94.815066 -101.714843) (xy 94.849152 -101.6707)
			(xy 94.889301 -101.631991) (xy 94.934659 -101.59954) (xy 94.984259 -101.574039) (xy 95.037043 -101.556032)
			(xy 95.091886 -101.545902) (xy 95.14762 -101.543865) (xy 95.203057 -101.549965) (xy 95.257014 -101.564071)
			(xy 95.308343 -101.585883) (xy 95.355949 -101.614937) (xy 95.398817 -101.650612) (xy 95.436034 -101.692149)
			(xy 95.466807 -101.738662) (xy 95.490479 -101.789159) (xy 95.506547 -101.842566) (xy 95.514667 -101.897742)
			(xy 95.515176 -101.925628) (xy 95.514667 -101.953514) (xy 95.506547 -102.00869) (xy 95.490479 -102.062097)
			(xy 95.466807 -102.112594) (xy 95.436034 -102.159107) (xy 95.398817 -102.200644) (xy 95.355949 -102.236319)
			(xy 95.308343 -102.265373) (xy 95.257014 -102.287185) (xy 95.203057 -102.301291) (xy 95.14762 -102.307391)
			(xy 95.091886 -102.305354) (xy 95.037043 -102.295224) (xy 94.984259 -102.277217) (xy 94.934659 -102.251716)
			(xy 94.889301 -102.219265) (xy 94.849152 -102.180556) (xy 94.815066 -102.136413) (xy 94.78777 -102.087778)
			(xy 94.767847 -102.035687) (xy 94.755721 -101.98125) (xy 94.75165 -101.925628) (xy 92.77228 -101.925628)
			(xy 92.784429 -101.96601) (xy 92.792549 -102.021186) (xy 92.793058 -102.049072) (xy 92.792549 -102.076958)
			(xy 92.784429 -102.132134) (xy 92.768361 -102.185541) (xy 92.744689 -102.236038) (xy 92.713916 -102.282551)
			(xy 92.676699 -102.324088) (xy 92.633831 -102.359763) (xy 92.586225 -102.388817) (xy 92.534896 -102.410629)
			(xy 92.480939 -102.424735) (xy 92.425502 -102.430835) (xy 92.369768 -102.428798) (xy 92.314925 -102.418668)
			(xy 92.262141 -102.400661) (xy 92.212541 -102.37516) (xy 92.167183 -102.342709) (xy 92.127034 -102.304)
			(xy 92.092948 -102.259857) (xy 92.065652 -102.211222) (xy 92.045729 -102.159131) (xy 92.033603 -102.104694)
			(xy 92.029532 -102.049072) (xy 87.273757 -102.049072) (xy 87.273637 -102.055622) (xy 87.265517 -102.110798)
			(xy 87.249449 -102.164205) (xy 87.225777 -102.214702) (xy 87.195004 -102.261215) (xy 87.157787 -102.302752)
			(xy 87.114919 -102.338427) (xy 87.067313 -102.367481) (xy 87.015984 -102.389293) (xy 86.962027 -102.403399)
			(xy 86.90659 -102.409499) (xy 86.850856 -102.407462) (xy 86.796013 -102.397332) (xy 86.743229 -102.379325)
			(xy 86.693629 -102.353824) (xy 86.648271 -102.321373) (xy 86.608122 -102.282664) (xy 86.574036 -102.238521)
			(xy 86.54674 -102.189886) (xy 86.526817 -102.137795) (xy 86.514691 -102.083358) (xy 86.51062 -102.027736)
			(xy 40.212772 -102.027736) (xy 40.212772 -102.570026) (xy 40.158452 -102.624382) (xy 84.84057 -102.624382)
			(xy 84.844641 -102.56876) (xy 84.856767 -102.514323) (xy 84.87669 -102.462232) (xy 84.903986 -102.413597)
			(xy 84.938072 -102.369454) (xy 84.978221 -102.330745) (xy 85.023579 -102.298294) (xy 85.073179 -102.272793)
			(xy 85.125963 -102.254786) (xy 85.180806 -102.244656) (xy 85.23654 -102.242619) (xy 85.291977 -102.248719)
			(xy 85.345934 -102.262825) (xy 85.397263 -102.284637) (xy 85.444869 -102.313691) (xy 85.487737 -102.349366)
			(xy 85.524954 -102.390903) (xy 85.555727 -102.437416) (xy 85.579399 -102.487913) (xy 85.595467 -102.54132)
			(xy 85.603587 -102.596496) (xy 85.604096 -102.624382) (xy 85.603587 -102.652268) (xy 85.597411 -102.694232)
			(xy 93.32036 -102.694232) (xy 93.324431 -102.63861) (xy 93.336557 -102.584173) (xy 93.35648 -102.532082)
			(xy 93.383776 -102.483447) (xy 93.417862 -102.439304) (xy 93.458011 -102.400595) (xy 93.503369 -102.368144)
			(xy 93.552969 -102.342643) (xy 93.605753 -102.324636) (xy 93.660596 -102.314506) (xy 93.71633 -102.312469)
			(xy 93.771767 -102.318569) (xy 93.825724 -102.332675) (xy 93.877053 -102.354487) (xy 93.924659 -102.383541)
			(xy 93.967527 -102.419216) (xy 94.004744 -102.460753) (xy 94.035517 -102.507266) (xy 94.059189 -102.557763)
			(xy 94.075257 -102.61117) (xy 94.083377 -102.666346) (xy 94.083886 -102.694232) (xy 94.083377 -102.722118)
			(xy 94.075257 -102.777294) (xy 94.059189 -102.830701) (xy 94.035517 -102.881198) (xy 94.004744 -102.927711)
			(xy 93.967527 -102.969248) (xy 93.924659 -103.004923) (xy 93.877053 -103.033977) (xy 93.825724 -103.055789)
			(xy 93.771767 -103.069895) (xy 93.71633 -103.075995) (xy 93.660596 -103.073958) (xy 93.605753 -103.063828)
			(xy 93.552969 -103.045821) (xy 93.503369 -103.02032) (xy 93.458011 -102.987869) (xy 93.417862 -102.94916)
			(xy 93.383776 -102.905017) (xy 93.35648 -102.856382) (xy 93.336557 -102.804291) (xy 93.324431 -102.749854)
			(xy 93.32036 -102.694232) (xy 85.597411 -102.694232) (xy 85.595467 -102.707444) (xy 85.579399 -102.760851)
			(xy 85.555727 -102.811348) (xy 85.524954 -102.857861) (xy 85.487737 -102.899398) (xy 85.444869 -102.935073)
			(xy 85.397263 -102.964127) (xy 85.345934 -102.985939) (xy 85.291977 -103.000045) (xy 85.23654 -103.006145)
			(xy 85.180806 -103.004108) (xy 85.125963 -102.993978) (xy 85.073179 -102.975971) (xy 85.023579 -102.95047)
			(xy 84.978221 -102.918019) (xy 84.938072 -102.87931) (xy 84.903986 -102.835167) (xy 84.87669 -102.786532)
			(xy 84.856767 -102.734441) (xy 84.844641 -102.680004) (xy 84.84057 -102.624382) (xy 40.158452 -102.624382)
			(xy 39.825676 -102.957376) (xy 39.825676 -103.058214) (xy 39.837614 -103.070152) (xy 39.849956 -103.081766)
			(xy 39.879324 -103.098651) (xy 39.912103 -103.107202) (xy 39.945976 -103.106816) (xy 39.978552 -103.09752)
			(xy 39.993316 -103.089202) (xy 40.023212 -103.071799) (xy 40.086707 -103.044351) (xy 40.153338 -103.025764)
			(xy 40.221873 -103.016381) (xy 40.25646 -103.015796) (xy 40.989758 -103.015796) (xy 41.021709 -103.016174)
			(xy 41.085108 -103.024178) (xy 41.147004 -103.040066) (xy 41.206421 -103.063586) (xy 41.262421 -103.094368)
			(xy 41.314121 -103.131927) (xy 41.360705 -103.175669) (xy 41.40144 -103.224905) (xy 41.435682 -103.278859)
			(xy 41.462892 -103.336679) (xy 41.464516 -103.341678) (xy 94.72625 -103.341678) (xy 94.730321 -103.286056)
			(xy 94.742447 -103.231619) (xy 94.76237 -103.179528) (xy 94.789666 -103.130893) (xy 94.823752 -103.08675)
			(xy 94.863901 -103.048041) (xy 94.909259 -103.01559) (xy 94.958859 -102.990089) (xy 95.011643 -102.972082)
			(xy 95.066486 -102.961952) (xy 95.12222 -102.959915) (xy 95.177657 -102.966015) (xy 95.231614 -102.980121)
			(xy 95.282943 -103.001933) (xy 95.330549 -103.030987) (xy 95.373417 -103.066662) (xy 95.410634 -103.108199)
			(xy 95.441407 -103.154712) (xy 95.465079 -103.205209) (xy 95.481147 -103.258616) (xy 95.489267 -103.313792)
			(xy 95.489776 -103.341678) (xy 95.489267 -103.369564) (xy 95.481147 -103.42474) (xy 95.465079 -103.478147)
			(xy 95.441407 -103.528644) (xy 95.410634 -103.575157) (xy 95.373417 -103.616694) (xy 95.330549 -103.652369)
			(xy 95.282943 -103.681423) (xy 95.231614 -103.703235) (xy 95.177657 -103.717341) (xy 95.12222 -103.723441)
			(xy 95.066486 -103.721404) (xy 95.011643 -103.711274) (xy 94.958859 -103.693267) (xy 94.909259 -103.667766)
			(xy 94.863901 -103.635315) (xy 94.823752 -103.596606) (xy 94.789666 -103.552463) (xy 94.76237 -103.503828)
			(xy 94.742447 -103.451737) (xy 94.730321 -103.3973) (xy 94.72625 -103.341678) (xy 41.464516 -103.341678)
			(xy 41.48264 -103.397453) (xy 41.494615 -103.460224) (xy 41.498628 -103.524) (xy 41.494615 -103.587776)
			(xy 41.48264 -103.650547) (xy 41.462892 -103.711321) (xy 41.435682 -103.769141) (xy 41.40144 -103.823095)
			(xy 41.360705 -103.872331) (xy 41.314121 -103.916073) (xy 41.279996 -103.940864) (xy 83.171282 -103.940864)
			(xy 83.175353 -103.885242) (xy 83.187479 -103.830805) (xy 83.207402 -103.778714) (xy 83.234698 -103.730079)
			(xy 83.268784 -103.685936) (xy 83.308933 -103.647227) (xy 83.354291 -103.614776) (xy 83.403891 -103.589275)
			(xy 83.456675 -103.571268) (xy 83.511518 -103.561138) (xy 83.567252 -103.559101) (xy 83.622689 -103.565201)
			(xy 83.676646 -103.579307) (xy 83.727975 -103.601119) (xy 83.775581 -103.630173) (xy 83.818449 -103.665848)
			(xy 83.855666 -103.707385) (xy 83.886439 -103.753898) (xy 83.910111 -103.804395) (xy 83.926179 -103.857802)
			(xy 83.934299 -103.912978) (xy 83.934808 -103.940864) (xy 83.934299 -103.96875) (xy 83.926179 -104.023926)
			(xy 83.910111 -104.077333) (xy 83.886439 -104.12783) (xy 83.855666 -104.174343) (xy 83.818449 -104.21588)
			(xy 83.775581 -104.251555) (xy 83.727975 -104.280609) (xy 83.676646 -104.302421) (xy 83.622689 -104.316527)
			(xy 83.567252 -104.322627) (xy 83.511518 -104.32059) (xy 83.456675 -104.31046) (xy 83.403891 -104.292453)
			(xy 83.354291 -104.266952) (xy 83.308933 -104.234501) (xy 83.268784 -104.195792) (xy 83.234698 -104.151649)
			(xy 83.207402 -104.103014) (xy 83.187479 -104.050923) (xy 83.175353 -103.996486) (xy 83.171282 -103.940864)
			(xy 41.279996 -103.940864) (xy 41.262421 -103.953632) (xy 41.206421 -103.984414) (xy 41.147004 -104.007934)
			(xy 41.085108 -104.023822) (xy 41.021709 -104.031826) (xy 40.989758 -104.032304) (xy 40.256206 -104.032304)
			(xy 40.223538 -104.031806) (xy 40.15874 -104.023433) (xy 40.095549 -104.006825) (xy 40.035009 -103.982256)
			(xy 39.978116 -103.95013) (xy 39.95166 -103.930958) (xy 39.917878 -103.905558) (xy 39.100252 -103.905558)
			(xy 39.100252 -103.621332) (xy 39.094101 -103.597482) (xy 39.087468 -103.548677) (xy 39.087044 -103.52405)
			(xy 39.087044 -102.65156) (xy 39.43731 -102.301294) (xy 39.448746 -102.289194) (xy 39.465447 -102.260405)
			(xy 39.474123 -102.228272) (xy 39.474648 -102.211632) (xy 39.474648 -102.006654) (xy 39.473632 -102.004114)
			(xy 38.410134 -100.940616) (xy 36.467034 -100.940616) (xy 36.405058 -100.979986) (xy 36.38931 -101.013006)
			(xy 36.370427 -101.051664) (xy 36.326599 -101.125704) (xy 36.27619 -101.19543) (xy 36.219622 -101.260261)
			(xy 36.157369 -101.319652) (xy 36.08995 -101.373109) (xy 36.01793 -101.420183) (xy 35.941911 -101.460482)
			(xy 35.862529 -101.493667) (xy 35.780447 -101.519463) (xy 35.696351 -101.537652) (xy 35.610946 -101.548083)
			(xy 35.524945 -101.550669) (xy 35.439067 -101.545387) (xy 35.354031 -101.532283) (xy 35.270548 -101.511465)
			(xy 35.189315 -101.483109) (xy 35.111012 -101.44745) (xy 35.036294 -101.404787) (xy 34.965786 -101.355477)
			(xy 34.900077 -101.299933) (xy 34.839717 -101.238618) (xy 34.78521 -101.172046) (xy 34.737012 -101.100772)
			(xy 34.695527 -101.025394) (xy 34.661101 -100.946542) (xy 34.634023 -100.864874) (xy 34.614518 -100.781074)
			(xy 34.602749 -100.695843) (xy 34.598816 -100.609893) (xy 33.77692 -100.609893) (xy 33.77692 -103.193358)
			(xy 34.599874 -103.193358) (xy 34.599874 -103.106458) (xy 34.607892 -103.019929) (xy 34.62386 -102.934509)
			(xy 34.647641 -102.850927) (xy 34.679033 -102.769895) (xy 34.717767 -102.692106) (xy 34.763514 -102.618222)
			(xy 34.815883 -102.548875) (xy 34.874427 -102.484655) (xy 34.938647 -102.426111) (xy 35.007994 -102.373742)
			(xy 35.081878 -102.327995) (xy 35.159667 -102.289261) (xy 35.240699 -102.257869) (xy 35.324281 -102.234088)
			(xy 35.409701 -102.21812) (xy 35.49623 -102.210102) (xy 35.58313 -102.210102) (xy 35.669659 -102.21812)
			(xy 35.755079 -102.234088) (xy 35.838661 -102.257869) (xy 35.919693 -102.289261) (xy 35.997482 -102.327995)
			(xy 36.071366 -102.373742) (xy 36.140713 -102.426111) (xy 36.204933 -102.484655) (xy 36.263477 -102.548875)
			(xy 36.315846 -102.618222) (xy 36.361593 -102.692106) (xy 36.400327 -102.769895) (xy 36.431719 -102.850927)
			(xy 36.4555 -102.934509) (xy 36.471468 -103.019929) (xy 36.479486 -103.106458) (xy 36.479988 -103.149908)
			(xy 36.479486 -103.193358) (xy 36.471468 -103.279887) (xy 36.4555 -103.365307) (xy 36.431719 -103.448889)
			(xy 36.400327 -103.529921) (xy 36.361593 -103.60771) (xy 36.315846 -103.681594) (xy 36.263477 -103.750941)
			(xy 36.204933 -103.815161) (xy 36.140713 -103.873705) (xy 36.071366 -103.926074) (xy 35.997482 -103.971821)
			(xy 35.919693 -104.010555) (xy 35.838661 -104.041947) (xy 35.755079 -104.065728) (xy 35.669659 -104.081696)
			(xy 35.58313 -104.089714) (xy 35.49623 -104.089714) (xy 35.409701 -104.081696) (xy 35.324281 -104.065728)
			(xy 35.240699 -104.041947) (xy 35.159667 -104.010555) (xy 35.081878 -103.971821) (xy 35.007994 -103.926074)
			(xy 34.938647 -103.873705) (xy 34.874427 -103.815161) (xy 34.815883 -103.750941) (xy 34.763514 -103.681594)
			(xy 34.717767 -103.60771) (xy 34.679033 -103.529921) (xy 34.647641 -103.448889) (xy 34.62386 -103.365307)
			(xy 34.607892 -103.279887) (xy 34.599874 -103.193358) (xy 33.77692 -103.193358) (xy 33.77692 -107.173268)
			(xy 34.325052 -107.7214) (xy 34.682176 -107.7214) (xy 34.697007 -107.720963) (xy 34.725867 -107.714115)
			(xy 34.752375 -107.700804) (xy 34.775105 -107.681748) (xy 34.784284 -107.670092) (xy 34.80756 -107.639279)
			(xy 34.858427 -107.581168) (xy 34.885884 -107.554014) (xy 34.90595 -107.535218) (xy 34.940882 -107.50411)
			(xy 35.015886 -107.448209) (xy 35.096067 -107.400027) (xy 35.138106 -107.379516) (xy 35.174637 -107.362742)
			(xy 35.250001 -107.33476) (xy 35.327478 -107.313311) (xy 35.406504 -107.298553) (xy 35.446462 -107.294172)
			(xy 35.485033 -107.290731) (xy 35.562468 -107.289419) (xy 35.639748 -107.29447) (xy 35.67811 -107.29976)
			(xy 35.708082 -107.304332) (xy 35.764978 -107.285536) (xy 36.812982 -106.237532) (xy 36.824432 -106.225414)
			(xy 36.841132 -106.196572) (xy 36.849794 -106.164388) (xy 36.849827 -106.13106) (xy 36.841228 -106.09886)
			(xy 36.824584 -106.069985) (xy 36.801031 -106.046404) (xy 36.772175 -106.029728) (xy 36.739984 -106.021092)
			(xy 36.72332 -106.020616) (xy 36.467034 -106.020616) (xy 36.405058 -106.059986) (xy 36.38931 -106.09326)
			(xy 36.370424 -106.131917) (xy 36.326577 -106.20595) (xy 36.27615 -106.275667) (xy 36.219566 -106.340487)
			(xy 36.157298 -106.399868) (xy 36.089867 -106.453312) (xy 36.017835 -106.500374) (xy 35.941806 -106.54066)
			(xy 35.862415 -106.573833) (xy 35.780326 -106.599615) (xy 35.696225 -106.617791) (xy 35.610815 -106.628209)
			(xy 35.524811 -106.630783) (xy 35.438931 -106.625489) (xy 35.353894 -106.612374) (xy 35.27041 -106.591546)
			(xy 35.189178 -106.563179) (xy 35.110876 -106.527511) (xy 35.03616 -106.48484) (xy 34.965653 -106.435522)
			(xy 34.899946 -106.37997) (xy 34.839588 -106.318649) (xy 34.785084 -106.252071) (xy 34.736889 -106.180793)
			(xy 34.695406 -106.105411) (xy 34.660982 -106.026554) (xy 34.633904 -105.944883) (xy 34.6144 -105.86108)
			(xy 34.602633 -105.775846) (xy 34.5987 -105.689893) (xy 34.602634 -105.60394) (xy 34.614403 -105.518706)
			(xy 34.633908 -105.434903) (xy 34.660987 -105.353232) (xy 34.695412 -105.274376) (xy 34.736896 -105.198995)
			(xy 34.785093 -105.127717) (xy 34.839598 -105.06114) (xy 34.899957 -104.99982) (xy 34.965665 -104.944269)
			(xy 35.036172 -104.894953) (xy 35.110889 -104.852283) (xy 35.189191 -104.816616) (xy 35.270424 -104.78825)
			(xy 35.353908 -104.767423) (xy 35.438945 -104.754309) (xy 35.524825 -104.749017) (xy 35.610829 -104.751592)
			(xy 35.696239 -104.762011) (xy 35.78034 -104.780189) (xy 35.862429 -104.805972) (xy 35.941819 -104.839146)
			(xy 36.017848 -104.879433) (xy 36.089878 -104.926496) (xy 36.157309 -104.979942) (xy 36.219576 -105.039323)
			(xy 36.276159 -105.104144) (xy 36.326585 -105.173863) (xy 36.370431 -105.247895) (xy 36.38931 -105.286556)
			(xy 36.405058 -105.31983) (xy 36.467034 -105.3592) (xy 37.370512 -105.3592) (xy 37.638228 -105.091484)
			(xy 39.324026 -105.091484) (xy 39.324026 -105.066084) (xy 40.087042 -105.066084) (xy 40.087042 -105.090976)
			(xy 40.577516 -105.090976) (xy 40.577516 -105.065322) (xy 41.340532 -105.065322) (xy 41.340532 -105.151428)
			(xy 82.471766 -105.151428) (xy 82.475837 -105.095806) (xy 82.487963 -105.041369) (xy 82.507886 -104.989278)
			(xy 82.535182 -104.940643) (xy 82.569268 -104.8965) (xy 82.609417 -104.857791) (xy 82.654775 -104.82534)
			(xy 82.704375 -104.799839) (xy 82.757159 -104.781832) (xy 82.812002 -104.771702) (xy 82.867736 -104.769665)
			(xy 82.923173 -104.775765) (xy 82.97713 -104.789871) (xy 83.028459 -104.811683) (xy 83.076065 -104.840737)
			(xy 83.118933 -104.876412) (xy 83.15615 -104.917949) (xy 83.186923 -104.964462) (xy 83.210595 -105.014959)
			(xy 83.226663 -105.068366) (xy 83.234783 -105.123542) (xy 83.235292 -105.151428) (xy 83.234783 -105.179314)
			(xy 83.226663 -105.23449) (xy 83.210595 -105.287897) (xy 83.186923 -105.338394) (xy 83.15615 -105.384907)
			(xy 83.118933 -105.426444) (xy 83.076065 -105.462119) (xy 83.028459 -105.491173) (xy 82.97713 -105.512985)
			(xy 82.923173 -105.527091) (xy 82.867736 -105.533191) (xy 82.812002 -105.531154) (xy 82.757159 -105.521024)
			(xy 82.704375 -105.503017) (xy 82.654775 -105.477516) (xy 82.609417 -105.445065) (xy 82.569268 -105.406356)
			(xy 82.535182 -105.362213) (xy 82.507886 -105.313578) (xy 82.487963 -105.261487) (xy 82.475837 -105.20705)
			(xy 82.471766 -105.151428) (xy 41.340532 -105.151428) (xy 41.340532 -105.88498) (xy 41.360438 -105.908261)
			(xy 41.395123 -105.95875) (xy 41.423492 -106.013041) (xy 41.445134 -106.070346) (xy 41.459735 -106.129835)
			(xy 41.467084 -106.190648) (xy 41.467532 -106.221276) (xy 41.467532 -106.251502) (xy 81.739484 -106.251502)
			(xy 81.743555 -106.19588) (xy 81.755681 -106.141443) (xy 81.775604 -106.089352) (xy 81.8029 -106.040717)
			(xy 81.836986 -105.996574) (xy 81.877135 -105.957865) (xy 81.922493 -105.925414) (xy 81.972093 -105.899913)
			(xy 82.024877 -105.881906) (xy 82.07972 -105.871776) (xy 82.135454 -105.869739) (xy 82.190891 -105.875839)
			(xy 82.244848 -105.889945) (xy 82.296177 -105.911757) (xy 82.343783 -105.940811) (xy 82.386651 -105.976486)
			(xy 82.423868 -106.018023) (xy 82.454641 -106.064536) (xy 82.478313 -106.115033) (xy 82.494381 -106.16844)
			(xy 82.502501 -106.223616) (xy 82.50301 -106.251502) (xy 82.502501 -106.279388) (xy 82.494381 -106.334564)
			(xy 82.478313 -106.387971) (xy 82.454641 -106.438468) (xy 82.423868 -106.484981) (xy 82.386651 -106.526518)
			(xy 82.343783 -106.562193) (xy 82.296177 -106.591247) (xy 82.244848 -106.613059) (xy 82.190891 -106.627165)
			(xy 82.135454 -106.633265) (xy 82.07972 -106.631228) (xy 82.024877 -106.621098) (xy 81.972093 -106.603091)
			(xy 81.922493 -106.57759) (xy 81.877135 -106.545139) (xy 81.836986 -106.50643) (xy 81.8029 -106.462287)
			(xy 81.775604 -106.413652) (xy 81.755681 -106.361561) (xy 81.743555 -106.307124) (xy 81.739484 -106.251502)
			(xy 41.467532 -106.251502) (xy 41.467532 -106.29392) (xy 50.87366 -106.29392) (xy 52.525168 -106.29392)
			(xy 52.525168 -107.49915) (xy 81.146902 -107.49915) (xy 81.150973 -107.443528) (xy 81.163099 -107.389091)
			(xy 81.183022 -107.337) (xy 81.210318 -107.288365) (xy 81.244404 -107.244222) (xy 81.284553 -107.205513)
			(xy 81.329911 -107.173062) (xy 81.379511 -107.147561) (xy 81.432295 -107.129554) (xy 81.487138 -107.119424)
			(xy 81.542872 -107.117387) (xy 81.598309 -107.123487) (xy 81.652266 -107.137593) (xy 81.703595 -107.159405)
			(xy 81.751201 -107.188459) (xy 81.794069 -107.224134) (xy 81.831286 -107.265671) (xy 81.862059 -107.312184)
			(xy 81.885731 -107.362681) (xy 81.901799 -107.416088) (xy 81.909919 -107.471264) (xy 81.910428 -107.49915)
			(xy 81.909919 -107.527036) (xy 81.901799 -107.582212) (xy 81.885731 -107.635619) (xy 81.862059 -107.686116)
			(xy 81.831286 -107.732629) (xy 81.794069 -107.774166) (xy 81.751201 -107.809841) (xy 81.703595 -107.838895)
			(xy 81.652266 -107.860707) (xy 81.598309 -107.874813) (xy 81.542872 -107.880913) (xy 81.487138 -107.878876)
			(xy 81.432295 -107.868746) (xy 81.379511 -107.850739) (xy 81.329911 -107.825238) (xy 81.284553 -107.792787)
			(xy 81.244404 -107.754078) (xy 81.210318 -107.709935) (xy 81.183022 -107.6613) (xy 81.163099 -107.609209)
			(xy 81.150973 -107.554772) (xy 81.146902 -107.49915) (xy 52.525168 -107.49915) (xy 52.525168 -107.945936)
			(xy 50.87366 -107.945936) (xy 50.87366 -106.29392) (xy 41.467532 -106.29392) (xy 41.467532 -106.900726)
			(xy 41.467031 -106.932671) (xy 41.459023 -106.996057) (xy 41.443134 -107.05794) (xy 41.419615 -107.117344)
			(xy 41.395898 -107.160483) (xy 47.373784 -107.160483) (xy 47.373784 -107.079373) (xy 47.381734 -106.998654)
			(xy 47.397557 -106.919103) (xy 47.421102 -106.841487) (xy 47.452141 -106.766551) (xy 47.490376 -106.695019)
			(xy 47.535438 -106.627579) (xy 47.586893 -106.56488) (xy 47.644246 -106.507527) (xy 47.706945 -106.456072)
			(xy 47.774385 -106.41101) (xy 47.845917 -106.372775) (xy 47.920853 -106.341736) (xy 47.998469 -106.318191)
			(xy 48.07802 -106.302368) (xy 48.158739 -106.294418) (xy 48.239849 -106.294418) (xy 48.320568 -106.302368)
			(xy 48.400119 -106.318191) (xy 48.477735 -106.341736) (xy 48.552671 -106.372775) (xy 48.624203 -106.41101)
			(xy 48.691643 -106.456072) (xy 48.754342 -106.507527) (xy 48.811695 -106.56488) (xy 48.86315 -106.627579)
			(xy 48.908212 -106.695019) (xy 48.946447 -106.766551) (xy 48.977486 -106.841487) (xy 49.001031 -106.919103)
			(xy 49.016854 -106.998654) (xy 49.024804 -107.079373) (xy 49.025302 -107.119928) (xy 49.024804 -107.160483)
			(xy 49.016854 -107.241202) (xy 49.001031 -107.320753) (xy 48.977486 -107.398369) (xy 48.946447 -107.473305)
			(xy 48.908212 -107.544837) (xy 48.86315 -107.612277) (xy 48.811695 -107.674976) (xy 48.754342 -107.732329)
			(xy 48.691643 -107.783784) (xy 48.624203 -107.828846) (xy 48.552671 -107.867081) (xy 48.477735 -107.89812)
			(xy 48.400119 -107.921665) (xy 48.320568 -107.937488) (xy 48.239849 -107.945438) (xy 48.158739 -107.945438)
			(xy 48.07802 -107.937488) (xy 47.998469 -107.921665) (xy 47.920853 -107.89812) (xy 47.845917 -107.867081)
			(xy 47.774385 -107.828846) (xy 47.706945 -107.783784) (xy 47.644246 -107.732329) (xy 47.586893 -107.674976)
			(xy 47.535438 -107.612277) (xy 47.490376 -107.544837) (xy 47.452141 -107.473305) (xy 47.421102 -107.398369)
			(xy 47.397557 -107.320753) (xy 47.381734 -107.241202) (xy 47.373784 -107.160483) (xy 41.395898 -107.160483)
			(xy 41.388835 -107.173331) (xy 41.351282 -107.22502) (xy 41.307546 -107.271594) (xy 41.258318 -107.312319)
			(xy 41.204373 -107.346553) (xy 41.146564 -107.373756) (xy 41.085801 -107.393499) (xy 41.023042 -107.405471)
			(xy 40.959278 -107.409483) (xy 40.895514 -107.405471) (xy 40.832755 -107.393499) (xy 40.771992 -107.373756)
			(xy 40.714183 -107.346553) (xy 40.660238 -107.312319) (xy 40.61101 -107.271594) (xy 40.567274 -107.22502)
			(xy 40.529721 -107.173331) (xy 40.498941 -107.117344) (xy 40.475422 -107.05794) (xy 40.459533 -106.996057)
			(xy 40.451525 -106.932671) (xy 40.451024 -106.900726) (xy 40.451024 -106.368342) (xy 40.450534 -106.351682)
			(xy 40.441921 -106.319496) (xy 40.42527 -106.290637) (xy 40.401716 -106.267071) (xy 40.372865 -106.250405)
			(xy 40.340683 -106.241774) (xy 40.324024 -106.241342) (xy 40.306988 -106.241894) (xy 40.274129 -106.250914)
			(xy 40.24482 -106.268291) (xy 40.221142 -106.292793) (xy 40.204775 -106.322678) (xy 40.200326 -106.339132)
			(xy 40.191758 -106.372908) (xy 40.166627 -106.4379) (xy 40.132858 -106.498853) (xy 40.112442 -106.527092)
			(xy 40.07358 -106.5784) (xy 40.071802 -106.5784) (xy 40.035734 -106.60888) (xy 40.01475 -106.626329)
			(xy 39.969694 -106.657129) (xy 39.945818 -106.670348) (xy 39.918017 -106.684729) (xy 39.859651 -106.707341)
			(xy 39.798949 -106.72261) (xy 39.736831 -106.730304) (xy 39.705534 -106.7308) (xy 37.757862 -106.7308)
			(xy 36.484052 -108.00461) (xy 36.465256 -108.061506) (xy 36.469828 -108.091478) (xy 36.475676 -108.134017)
			(xy 36.48052 -108.219754) (xy 36.477526 -108.305575) (xy 36.466719 -108.390766) (xy 36.448189 -108.474617)
			(xy 36.42209 -108.556428) (xy 36.388641 -108.635519) (xy 36.348118 -108.71123) (xy 36.300861 -108.782931)
			(xy 36.247263 -108.850024) (xy 36.18777 -108.91195) (xy 36.122878 -108.968193) (xy 36.053128 -109.018285)
			(xy 35.979101 -109.061809) (xy 35.901414 -109.0984) (xy 35.861244 -109.113574) (xy 35.813492 -109.129576)
			(xy 35.770827 -109.142008) (xy 35.683738 -109.159724) (xy 35.595366 -109.169145) (xy 35.506499 -109.170188)
			(xy 35.41793 -109.162843) (xy 35.330449 -109.147177) (xy 35.244836 -109.123328) (xy 35.161855 -109.091509)
			(xy 35.082245 -109.052005) (xy 35.006716 -109.005166) (xy 34.935943 -108.951412) (xy 34.870556 -108.891222)
			(xy 34.811138 -108.825132) (xy 34.784284 -108.789724) (xy 34.775134 -108.778032) (xy 34.752429 -108.758913)
			(xy 34.725908 -108.745584) (xy 34.697018 -108.738772) (xy 34.682176 -108.738416) (xy 33.90392 -108.738416)
			(xy 32.759904 -107.5944) (xy 32.759904 -92.544646) (xy 31.848298 -91.63304) (xy 29.99232 -91.63304)
			(xy 29.944822 -91.680284) (xy 28.591748 -93.033358) (xy 29.519874 -93.033358) (xy 29.519874 -92.946458)
			(xy 29.527892 -92.859929) (xy 29.54386 -92.774509) (xy 29.567641 -92.690927) (xy 29.599033 -92.609895)
			(xy 29.637767 -92.532106) (xy 29.683514 -92.458222) (xy 29.735883 -92.388875) (xy 29.794427 -92.324655)
			(xy 29.858647 -92.266111) (xy 29.927994 -92.213742) (xy 30.001878 -92.167995) (xy 30.079667 -92.129261)
			(xy 30.160699 -92.097869) (xy 30.244281 -92.074088) (xy 30.329701 -92.05812) (xy 30.41623 -92.050102)
			(xy 30.50313 -92.050102) (xy 30.589659 -92.05812) (xy 30.675079 -92.074088) (xy 30.758661 -92.097869)
			(xy 30.839693 -92.129261) (xy 30.917482 -92.167995) (xy 30.991366 -92.213742) (xy 31.060713 -92.266111)
			(xy 31.124933 -92.324655) (xy 31.183477 -92.388875) (xy 31.235846 -92.458222) (xy 31.281593 -92.532106)
			(xy 31.320327 -92.609895) (xy 31.351719 -92.690927) (xy 31.3755 -92.774509) (xy 31.391468 -92.859929)
			(xy 31.399486 -92.946458) (xy 31.399988 -92.989908) (xy 31.399486 -93.033358) (xy 31.391468 -93.119887)
			(xy 31.3755 -93.205307) (xy 31.351719 -93.288889) (xy 31.320327 -93.369921) (xy 31.281593 -93.44771)
			(xy 31.235846 -93.521594) (xy 31.183477 -93.590941) (xy 31.124933 -93.655161) (xy 31.060713 -93.713705)
			(xy 30.991366 -93.766074) (xy 30.917482 -93.811821) (xy 30.839693 -93.850555) (xy 30.758661 -93.881947)
			(xy 30.675079 -93.905728) (xy 30.589659 -93.921696) (xy 30.50313 -93.929714) (xy 30.41623 -93.929714)
			(xy 30.329701 -93.921696) (xy 30.244281 -93.905728) (xy 30.160699 -93.881947) (xy 30.079667 -93.850555)
			(xy 30.001878 -93.811821) (xy 29.927994 -93.766074) (xy 29.858647 -93.713705) (xy 29.794427 -93.655161)
			(xy 29.735883 -93.590941) (xy 29.683514 -93.521594) (xy 29.637767 -93.44771) (xy 29.599033 -93.369921)
			(xy 29.567641 -93.288889) (xy 29.54386 -93.205307) (xy 29.527892 -93.119887) (xy 29.519874 -93.033358)
			(xy 28.591748 -93.033358) (xy 27.46629 -94.158816) (xy 26.802334 -94.158816) (xy 26.786826 -94.160884)
			(xy 26.757425 -94.171555) (xy 26.731477 -94.18902) (xy 26.710522 -94.21224) (xy 26.695804 -94.239839)
			(xy 26.688197 -94.270178) (xy 26.68778 -94.285816) (xy 26.68778 -94.846394) (xy 26.66238 -94.846394)
			(xy 26.66238 -95.244412) (xy 26.73858 -95.320612) (xy 26.898346 -95.320612) (xy 26.929842 -95.300292)
			(xy 26.949071 -95.288287) (xy 26.989822 -95.268426) (xy 27.011122 -95.260668) (xy 27.038808 -95.251016)
			(xy 27.090624 -95.1992) (xy 29.532326 -95.1992) (xy 29.594302 -95.15983) (xy 29.61005 -95.126556)
			(xy 29.628935 -95.087897) (xy 29.672782 -95.01386) (xy 29.723208 -94.944138) (xy 29.779792 -94.879314)
			(xy 29.842061 -94.819929) (xy 29.909493 -94.76648) (xy 29.981526 -94.719415) (xy 30.057557 -94.679125)
			(xy 30.13695 -94.645949) (xy 30.219041 -94.620164) (xy 30.303145 -94.601984) (xy 30.388558 -94.591563)
			(xy 30.474565 -94.588988) (xy 30.560449 -94.594279) (xy 30.645489 -94.607393) (xy 30.728977 -94.62822)
			(xy 30.810213 -94.656586) (xy 30.888518 -94.692253) (xy 30.963239 -94.734925) (xy 31.033749 -94.784242)
			(xy 31.099459 -94.839795) (xy 31.159821 -94.901117) (xy 31.214328 -94.967696) (xy 31.262527 -95.038976)
			(xy 31.304013 -95.114361) (xy 31.33844 -95.19322) (xy 31.365519 -95.274894) (xy 31.385026 -95.358699)
			(xy 31.396795 -95.443937) (xy 31.40073 -95.529893) (xy 31.396796 -95.615849) (xy 31.385028 -95.701086)
			(xy 31.365523 -95.784893) (xy 31.338445 -95.866567) (xy 31.304019 -95.945426) (xy 31.262534 -96.020811)
			(xy 31.214337 -96.092092) (xy 31.15983 -96.158672) (xy 31.09947 -96.219995) (xy 31.03376 -96.275549)
			(xy 30.963251 -96.324868) (xy 30.888531 -96.36754) (xy 30.810226 -96.403209) (xy 30.728991 -96.431576)
			(xy 30.645504 -96.452404) (xy 30.560463 -96.465519) (xy 30.47458 -96.470812) (xy 30.388572 -96.468238)
			(xy 30.303159 -96.457818) (xy 30.219055 -96.43964) (xy 30.136963 -96.413856) (xy 30.05757 -96.380681)
			(xy 29.981538 -96.340393) (xy 29.909505 -96.293328) (xy 29.842071 -96.23988) (xy 29.779802 -96.180496)
			(xy 29.723217 -96.115673) (xy 29.67279 -96.045952) (xy 29.628942 -95.971916) (xy 29.61005 -95.93326)
			(xy 29.594302 -95.899986) (xy 29.532326 -95.860616) (xy 27.488896 -95.860616) (xy 27.402028 -95.895668)
			(xy 27.386026 -95.909638) (xy 27.375685 -95.918436) (xy 27.353947 -95.934707) (xy 27.342592 -95.94215)
			(xy 27.3237 -95.953885) (xy 27.28372 -95.973368) (xy 27.262836 -95.981012) (xy 27.234583 -95.990342)
			(xy 27.176071 -96.001119) (xy 27.116595 -96.002672) (xy 27.0576 -95.994963) (xy 27.028902 -95.987108)
			(xy 27.011376 -95.982028) (xy 26.73858 -95.982028) (xy 26.68778 -96.032828) (xy 26.66238 -96.032828)
			(xy 26.66238 -96.490536) (xy 26.68778 -96.490536) (xy 26.68778 -97.253552) (xy 26.16708 -97.253552)
			(xy 26.150431 -97.254097) (xy 26.118268 -97.262718) (xy 26.089431 -97.279366) (xy 26.065883 -97.302909)
			(xy 26.049229 -97.331742) (xy 26.040601 -97.363903) (xy 26.04008 -97.380552) (xy 26.04008 -97.595182)
			(xy 26.040621 -97.611833) (xy 26.049235 -97.644001) (xy 26.065882 -97.672843) (xy 26.089426 -97.696395)
			(xy 26.118264 -97.71305) (xy 26.150429 -97.721674) (xy 26.16708 -97.722182) (xy 26.68778 -97.722182)
			(xy 26.68778 -98.485198) (xy 26.66238 -98.485198) (xy 26.66238 -98.962972) (xy 26.73858 -99.039172)
			(xy 26.9113 -99.039172) (xy 26.937462 -99.026472) (xy 26.962862 -99.015296) (xy 26.97607 -99.010216)
			(xy 26.992834 -99.004628) (xy 27.020331 -98.996737) (xy 27.076914 -98.988332) (xy 27.134118 -98.98847)
			(xy 27.19066 -98.997147) (xy 27.245274 -99.014168) (xy 27.271218 -99.026218) (xy 27.297634 -99.039172)
			(xy 28.98267 -99.039172) (xy 28.997188 -99.037246) (xy 29.024849 -99.027648) (xy 29.04959 -99.011992)
			(xy 29.06014 -99.001834) (xy 29.544264 -98.51771) (xy 29.556475 -98.504589) (xy 29.573718 -98.473183)
			(xy 29.581563 -98.438226) (xy 29.579395 -98.402464) (xy 29.573982 -98.385376) (xy 29.559704 -98.343754)
			(xy 29.538058 -98.258458) (xy 29.524477 -98.171513) (xy 29.519079 -98.083679) (xy 29.521911 -97.995725)
			(xy 29.53295 -97.90842) (xy 29.552097 -97.822528) (xy 29.579186 -97.738802) (xy 29.61398 -97.657973)
			(xy 29.656173 -97.580748) (xy 29.705398 -97.507804) (xy 29.761224 -97.439778) (xy 29.823161 -97.377266)
			(xy 29.890668 -97.320815) (xy 29.963154 -97.270918) (xy 30.039985 -97.228012) (xy 30.120489 -97.192473)
			(xy 30.203962 -97.164612) (xy 30.289673 -97.144672) (xy 30.376872 -97.132827) (xy 30.464796 -97.129182)
			(xy 30.552676 -97.133768) (xy 30.639743 -97.146546) (xy 30.725236 -97.167402) (xy 30.808405 -97.196156)
			(xy 30.888525 -97.232555) (xy 30.964892 -97.276281) (xy 31.03684 -97.326951) (xy 31.103739 -97.384121)
			(xy 31.165003 -97.447293) (xy 31.220097 -97.515912) (xy 31.268538 -97.589379) (xy 31.309903 -97.667051)
			(xy 31.327344 -97.70745) (xy 31.343572 -97.747542) (xy 31.369465 -97.830073) (xy 31.387669 -97.914634)
			(xy 31.39803 -98.000509) (xy 31.40046 -98.086972) (xy 31.394938 -98.173293) (xy 31.381512 -98.258743)
			(xy 31.360294 -98.342598) (xy 31.331464 -98.42415) (xy 31.295266 -98.502709) (xy 31.252006 -98.577612)
			(xy 31.202049 -98.648225) (xy 31.145818 -98.713951) (xy 31.083789 -98.774235) (xy 31.016484 -98.828567)
			(xy 30.944474 -98.876488) (xy 30.868367 -98.917592) (xy 30.788807 -98.951533) (xy 30.706465 -98.978023)
			(xy 30.622039 -98.996839) (xy 30.536241 -99.007821) (xy 30.449797 -99.010877) (xy 30.363438 -99.00598)
			(xy 30.277894 -98.993173) (xy 30.193888 -98.972562) (xy 30.152848 -98.958908) (xy 30.143196 -98.955352)
			(xy 30.12186 -98.951542) (xy 30.106796 -98.949403) (xy 30.07645 -98.95148) (xy 30.047452 -98.960661)
			(xy 30.021439 -98.976427) (xy 30.010354 -98.986848) (xy 29.514546 -99.482656) (xy 29.42717 -99.569778)
			(xy 29.296868 -99.70008) (xy 27.297888 -99.70008) (xy 27.271726 -99.713034) (xy 27.245641 -99.725111)
			(xy 27.190751 -99.74217) (xy 27.133925 -99.750819) (xy 27.076445 -99.750862) (xy 27.047952 -99.74707)
			(xy 27.03068 -99.744022) (xy 27.020532 -99.741961) (xy 27.000455 -99.736878) (xy 26.990548 -99.733862)
			(xy 26.977146 -99.729575) (xy 26.950957 -99.719278) (xy 26.938224 -99.713288) (xy 26.912062 -99.700588)
			(xy 26.73858 -99.700588) (xy 26.68778 -99.751388) (xy 26.66238 -99.751388) (xy 26.66238 -100.208588)
			(xy 26.68778 -100.208588) (xy 26.68778 -100.656875) (xy 28.701115 -100.656875) (xy 28.702127 -100.602222)
			(xy 28.710931 -100.548273) (xy 28.727346 -100.496134) (xy 28.751036 -100.446872) (xy 28.781516 -100.401496)
			(xy 28.818161 -100.360936) (xy 28.860222 -100.326024) (xy 28.906835 -100.297473) (xy 28.957047 -100.275869)
			(xy 29.009829 -100.261654) (xy 29.0641 -100.25512) (xy 29.118747 -100.256401) (xy 29.172652 -100.265469)
			(xy 29.198824 -100.273358) (xy 29.217874 -100.2792) (xy 29.532326 -100.2792) (xy 29.594302 -100.23983)
			(xy 29.61005 -100.20681) (xy 29.628919 -100.168144) (xy 29.672748 -100.094098) (xy 29.723157 -100.024366)
			(xy 29.779726 -99.959531) (xy 29.841981 -99.900134) (xy 29.909401 -99.846672) (xy 29.981424 -99.799593)
			(xy 30.057446 -99.759291) (xy 30.136831 -99.726101) (xy 30.218917 -99.700302) (xy 30.303016 -99.68211)
			(xy 30.388426 -99.671676) (xy 30.474431 -99.669088) (xy 30.560314 -99.674367) (xy 30.645355 -99.68747)
			(xy 30.728843 -99.708287) (xy 30.810081 -99.736643) (xy 30.888389 -99.772302) (xy 30.963112 -99.814965)
			(xy 31.033625 -99.864276) (xy 31.099338 -99.919822) (xy 31.159703 -99.981139) (xy 31.214214 -100.047714)
			(xy 31.262415 -100.11899) (xy 31.303904 -100.194371) (xy 31.338333 -100.273227) (xy 31.365415 -100.354899)
			(xy 31.384922 -100.438703) (xy 31.396693 -100.523938) (xy 31.400628 -100.609893) (xy 31.396694 -100.695847)
			(xy 31.384925 -100.781083) (xy 31.365419 -100.864887) (xy 31.338338 -100.946559) (xy 31.303911 -101.025416)
			(xy 31.262423 -101.100798) (xy 31.214223 -101.172075) (xy 31.159713 -101.23865) (xy 31.099349 -101.299968)
			(xy 31.033636 -101.355515) (xy 30.963124 -101.404827) (xy 30.888402 -101.447492) (xy 30.810094 -101.483152)
			(xy 30.728857 -101.511509) (xy 30.645369 -101.532327) (xy 30.560328 -101.545431) (xy 30.474446 -101.550712)
			(xy 30.38844 -101.548125) (xy 30.303031 -101.537693) (xy 30.218931 -101.519502) (xy 30.136845 -101.493704)
			(xy 30.057459 -101.460516) (xy 29.981436 -101.420214) (xy 29.909413 -101.373136) (xy 29.841992 -101.319676)
			(xy 29.779736 -101.26028) (xy 29.723166 -101.195445) (xy 29.672756 -101.125714) (xy 29.628926 -101.051669)
			(xy 29.61005 -101.013006) (xy 29.594302 -100.979986) (xy 29.532326 -100.940616) (xy 29.315918 -100.940616)
			(xy 29.28493 -100.95992) (xy 29.261489 -100.973984) (xy 29.211492 -100.996081) (xy 29.158853 -101.010813)
			(xy 29.104649 -101.01788) (xy 29.049992 -101.017137) (xy 28.996 -101.008599) (xy 28.943781 -100.99244)
			(xy 28.894403 -100.968993) (xy 28.848878 -100.938736) (xy 28.808139 -100.90229) (xy 28.77302 -100.860402)
			(xy 28.74424 -100.813929) (xy 28.72239 -100.763824) (xy 28.707916 -100.711113) (xy 28.701115 -100.656875)
			(xy 26.68778 -100.656875) (xy 26.68778 -100.971604) (xy 25.870408 -100.971604) (xy 25.836372 -100.997004)
			(xy 25.804114 -101.019356) (xy 25.792079 -101.026882) (xy 25.767298 -101.04073) (xy 25.754584 -101.047042)
			(xy 25.74671 -101.050852) (xy 25.727914 -101.05898) (xy 25.718516 -101.06279) (xy 25.682194 -101.077268)
			(xy 25.638252 -101.141784) (xy 25.638252 -101.1809) (xy 25.638795 -101.197551) (xy 25.647412 -101.229718)
			(xy 25.664059 -101.25856) (xy 25.687602 -101.282112) (xy 25.716438 -101.298769) (xy 25.748602 -101.307399)
			(xy 25.765252 -101.3079) (xy 26.757884 -101.3079) (xy 26.808684 -101.3587) (xy 29.120338 -101.3587)
			(xy 30.02661 -102.264972) (xy 30.098746 -102.28072) (xy 30.133798 -102.267766) (xy 30.174272 -102.253312)
			(xy 30.25727 -102.230986) (xy 30.341959 -102.216327) (xy 30.427633 -102.209459) (xy 30.513576 -102.210438)
			(xy 30.599071 -102.219256) (xy 30.683404 -102.23584) (xy 30.765873 -102.260051) (xy 30.845787 -102.291687)
			(xy 30.922481 -102.330485) (xy 30.995314 -102.37612) (xy 31.063678 -102.428211) (xy 31.127003 -102.486324)
			(xy 31.18476 -102.549973) (xy 31.236467 -102.618628) (xy 31.281694 -102.691715) (xy 31.320061 -102.768625)
			(xy 31.351249 -102.848716) (xy 31.374998 -102.931318) (xy 31.391109 -103.015743) (xy 31.399448 -103.101286)
			(xy 31.399946 -103.187233) (xy 31.392597 -103.272867) (xy 31.377465 -103.357473) (xy 31.354674 -103.440345)
			(xy 31.324415 -103.520791) (xy 31.286941 -103.59814) (xy 31.242564 -103.671746) (xy 31.191654 -103.740995)
			(xy 31.163514 -103.773478) (xy 31.136376 -103.803458) (xy 31.07775 -103.859164) (xy 31.04642 -103.88473)
			(xy 31.012952 -103.910833) (xy 30.942101 -103.957579) (xy 30.867324 -103.997747) (xy 30.789231 -104.031012)
			(xy 30.748986 -104.044496) (xy 30.707557 -104.057369) (xy 30.622898 -104.076344) (xy 30.53685 -104.08744)
			(xy 30.450147 -104.09056) (xy 30.363524 -104.085679) (xy 30.27772 -104.072839) (xy 30.193464 -104.052148)
			(xy 30.111472 -104.023782) (xy 30.032442 -103.987983) (xy 29.957047 -103.945056) (xy 29.885927 -103.895364)
			(xy 29.819688 -103.839332) (xy 29.758892 -103.777436) (xy 29.704058 -103.710201) (xy 29.655651 -103.638201)
			(xy 29.614084 -103.562047) (xy 29.579709 -103.482388) (xy 29.552819 -103.3999) (xy 29.533644 -103.315286)
			(xy 29.522345 -103.229265) (xy 29.51902 -103.142569) (xy 29.523696 -103.055935) (xy 29.536334 -102.970101)
			(xy 29.556826 -102.885796) (xy 29.570426 -102.8446) (xy 29.582364 -102.810056) (xy 29.565854 -102.739444)
			(xy 28.846526 -102.020116) (xy 26.808684 -102.020116) (xy 26.757884 -102.070916) (xy 26.61031 -102.070916)
			(xy 26.587274 -102.071416) (xy 26.541958 -102.079719) (xy 26.49888 -102.096055) (xy 26.459453 -102.119889)
			(xy 26.424968 -102.150439) (xy 26.396555 -102.186706) (xy 26.375145 -102.2275) (xy 26.36144 -102.271486)
			(xy 26.355888 -102.317221) (xy 26.358671 -102.363208) (xy 26.369699 -102.40794) (xy 26.388609 -102.449951)
			(xy 26.414783 -102.487865) (xy 26.430732 -102.504494) (xy 26.88209 -102.955852) (xy 26.909776 -102.965504)
			(xy 26.935653 -102.975006) (xy 26.984579 -103.000397) (xy 27.029342 -103.032566) (xy 27.06901 -103.070842)
			(xy 27.102756 -103.114428) (xy 27.129878 -103.162417) (xy 27.149812 -103.21381) (xy 27.162141 -103.267536)
			(xy 27.16661 -103.322478) (xy 27.163126 -103.377491) (xy 27.151761 -103.43143) (xy 27.132751 -103.483171)
			(xy 27.106493 -103.531639) (xy 27.073533 -103.575822) (xy 27.034558 -103.614803) (xy 26.990378 -103.647768)
			(xy 26.941914 -103.674032) (xy 26.890175 -103.693048) (xy 26.836237 -103.70442) (xy 26.781225 -103.707911)
			(xy 26.726283 -103.703448) (xy 26.672555 -103.691125) (xy 26.621159 -103.671198) (xy 26.573167 -103.644082)
			(xy 26.529577 -103.610341) (xy 26.491296 -103.570678) (xy 26.459122 -103.525919) (xy 26.433724 -103.476996)
			(xy 26.424128 -103.451152) (xy 26.414476 -103.423466) (xy 25.270968 -102.279958) (xy 25.270968 -102.070916)
			(xy 25.245568 -102.070916) (xy 25.245568 -101.225604) (xy 25.245074 -101.20895) (xy 25.236453 -101.176778)
			(xy 25.219797 -101.147935) (xy 25.196243 -101.124385) (xy 25.167396 -101.107736) (xy 25.135222 -101.099123)
			(xy 25.118568 -101.098604) (xy 24.801322 -101.098604) (xy 24.770159 -101.098133) (xy 24.7083 -101.090519)
			(xy 24.647836 -101.0754) (xy 24.589673 -101.053006) (xy 24.534683 -101.02367) (xy 24.48369 -100.987833)
			(xy 24.43746 -100.946033) (xy 24.396685 -100.898896) (xy 24.361978 -100.847128) (xy 24.333857 -100.791507)
			(xy 24.312745 -100.732866) (xy 24.298959 -100.672084) (xy 24.292705 -100.610073) (xy 24.294077 -100.547762)
			(xy 24.303054 -100.486086) (xy 24.319502 -100.42597) (xy 24.343174 -100.368315) (xy 24.373716 -100.313985)
			(xy 24.410668 -100.263795) (xy 24.453478 -100.218498) (xy 24.501503 -100.178773) (xy 24.52751 -100.161598)
			(xy 24.547163 -100.148411) (xy 24.581627 -100.115982) (xy 24.609494 -100.077735) (xy 24.6298 -100.034991)
			(xy 24.641844 -99.989226) (xy 24.645209 -99.942024) (xy 24.639779 -99.895014) (xy 24.625743 -99.849821)
			(xy 24.603584 -99.808007) (xy 24.574069 -99.771017) (xy 24.556466 -99.755198) (xy 24.532147 -99.733576)
			(xy 24.488655 -99.685173) (xy 24.451693 -99.631617) (xy 24.421866 -99.573783) (xy 24.399661 -99.512616)
			(xy 24.385441 -99.449116) (xy 24.379438 -99.38432) (xy 24.381751 -99.319289) (xy 24.392342 -99.255083)
			(xy 24.411037 -99.192754) (xy 24.437532 -99.133319) (xy 24.471392 -99.07775) (xy 24.512066 -99.026955)
			(xy 24.558887 -98.981764) (xy 24.611091 -98.942916) (xy 24.667825 -98.911045) (xy 24.728161 -98.886672)
			(xy 24.791114 -98.870197) (xy 24.855654 -98.861887) (xy 24.88819 -98.861372) (xy 25.453594 -98.861372)
			(xy 25.470248 -98.860878) (xy 25.502421 -98.852257) (xy 25.531266 -98.835602) (xy 25.554816 -98.812048)
			(xy 25.571466 -98.7832) (xy 25.580081 -98.751026) (xy 25.580594 -98.734372) (xy 25.580594 -98.686366)
			(xy 25.517348 -98.614484) (xy 25.469596 -98.608388) (xy 25.455372 -98.606356) (xy 25.454864 -98.606356)
			(xy 25.43048 -98.601784) (xy 25.418034 -98.599244) (xy 24.35098 -98.599244) (xy 24.336465 -98.601176)
			(xy 24.308812 -98.610783) (xy 24.28408 -98.626446) (xy 24.27351 -98.636582) (xy 23.630128 -99.279964)
			(xy 23.630128 -104.332532) (xy 22.8473 -105.11536) (xy 22.8473 -106.099363) (xy 23.29671 -106.099363)
			(xy 23.301447 -106.04468) (xy 23.313974 -105.99124) (xy 23.334031 -105.940148) (xy 23.361205 -105.892458)
			(xy 23.394935 -105.849156) (xy 23.434523 -105.811136) (xy 23.479152 -105.779183) (xy 23.5279 -105.753958)
			(xy 23.553674 -105.744518) (xy 23.581106 -105.734866) (xy 23.956772 -105.3592) (xy 29.532326 -105.3592)
			(xy 29.594302 -105.31983) (xy 29.61005 -105.28681) (xy 29.628919 -105.248144) (xy 29.672748 -105.174098)
			(xy 29.723157 -105.104366) (xy 29.779726 -105.039531) (xy 29.841981 -104.980134) (xy 29.909401 -104.926672)
			(xy 29.981424 -104.879593) (xy 30.057446 -104.839291) (xy 30.136831 -104.806101) (xy 30.218917 -104.780302)
			(xy 30.303016 -104.76211) (xy 30.388426 -104.751676) (xy 30.474431 -104.749088) (xy 30.560314 -104.754367)
			(xy 30.645355 -104.76747) (xy 30.728843 -104.788287) (xy 30.810081 -104.816643) (xy 30.888389 -104.852302)
			(xy 30.963112 -104.894965) (xy 31.033625 -104.944276) (xy 31.099338 -104.999822) (xy 31.159703 -105.061139)
			(xy 31.214214 -105.127714) (xy 31.262415 -105.19899) (xy 31.303904 -105.274371) (xy 31.338333 -105.353227)
			(xy 31.365415 -105.434899) (xy 31.384922 -105.518703) (xy 31.396693 -105.603938) (xy 31.400628 -105.689893)
			(xy 31.396694 -105.775847) (xy 31.384925 -105.861083) (xy 31.365419 -105.944887) (xy 31.338338 -106.026559)
			(xy 31.303911 -106.105416) (xy 31.262423 -106.180798) (xy 31.214223 -106.252075) (xy 31.159713 -106.31865)
			(xy 31.099349 -106.379968) (xy 31.033636 -106.435515) (xy 30.963124 -106.484827) (xy 30.888402 -106.527492)
			(xy 30.810094 -106.563152) (xy 30.728857 -106.591509) (xy 30.645369 -106.612327) (xy 30.560328 -106.625431)
			(xy 30.474446 -106.630712) (xy 30.38844 -106.628125) (xy 30.303031 -106.617693) (xy 30.218931 -106.599502)
			(xy 30.136845 -106.573704) (xy 30.057459 -106.540516) (xy 29.981436 -106.500214) (xy 29.909413 -106.453136)
			(xy 29.841992 -106.399676) (xy 29.779736 -106.34028) (xy 29.723166 -106.275445) (xy 29.672756 -106.205714)
			(xy 29.628926 -106.131669) (xy 29.61005 -106.093006) (xy 29.594302 -106.059986) (xy 29.532326 -106.020616)
			(xy 28.87345 -106.020616) (xy 28.85055 -106.021078) (xy 28.805495 -106.029311) (xy 28.762645 -106.045485)
			(xy 28.723387 -106.069074) (xy 28.688991 -106.099317) (xy 28.66057 -106.135233) (xy 28.639045 -106.175661)
			(xy 28.625113 -106.219291) (xy 28.619224 -106.264712) (xy 28.621569 -106.310452) (xy 28.632073 -106.355032)
			(xy 28.640786 -106.376216) (xy 28.653183 -106.405888) (xy 28.670917 -106.4677) (xy 28.680295 -106.531319)
			(xy 28.681152 -106.595619) (xy 28.673472 -106.659465) (xy 28.657392 -106.721728) (xy 28.633195 -106.781308)
			(xy 28.601309 -106.837152) (xy 28.562297 -106.888273) (xy 28.539948 -106.911394) (xy 28.162758 -107.28833)
			(xy 28.146765 -107.304919) (xy 28.120588 -107.342838) (xy 28.101675 -107.384856) (xy 28.090647 -107.429594)
			(xy 28.087864 -107.475588) (xy 28.093418 -107.521329) (xy 28.107128 -107.56532) (xy 28.128543 -107.606119)
			(xy 28.156962 -107.642389) (xy 28.191454 -107.672942) (xy 28.230888 -107.696776) (xy 28.273973 -107.71311)
			(xy 28.319297 -107.721411) (xy 28.342336 -107.721908) (xy 28.523184 -107.721908) (xy 28.527502 -107.717844)
			(xy 29.221684 -107.717844) (xy 29.225494 -107.7214) (xy 29.602176 -107.7214) (xy 29.617018 -107.721038)
			(xy 29.645907 -107.714226) (xy 29.672427 -107.700899) (xy 29.695133 -107.681782) (xy 29.704284 -107.670092)
			(xy 29.730635 -107.635347) (xy 29.788824 -107.570389) (xy 29.852779 -107.511098) (xy 29.921949 -107.457985)
			(xy 29.99574 -107.411505) (xy 30.073518 -107.372058) (xy 30.154615 -107.339983) (xy 30.238334 -107.315555)
			(xy 30.323955 -107.298985) (xy 30.410742 -107.290415) (xy 30.49795 -107.289918) (xy 30.58483 -107.297499)
			(xy 30.670634 -107.313092) (xy 30.754626 -107.336564) (xy 30.836083 -107.367713) (xy 30.914306 -107.406272)
			(xy 30.988622 -107.451908) (xy 31.058392 -107.50423) (xy 31.123018 -107.562788) (xy 31.181944 -107.627078)
			(xy 31.234663 -107.69655) (xy 31.280722 -107.770604) (xy 31.319726 -107.848606) (xy 31.351339 -107.929884)
			(xy 31.37529 -108.01374) (xy 31.391372 -108.099454) (xy 31.399449 -108.186289) (xy 31.399449 -108.273498)
			(xy 31.391374 -108.360333) (xy 31.375293 -108.446048) (xy 31.351343 -108.529904) (xy 31.319731 -108.611183)
			(xy 31.280728 -108.689185) (xy 31.23467 -108.76324) (xy 31.181952 -108.832712) (xy 31.123027 -108.897003)
			(xy 31.058402 -108.955562) (xy 30.988632 -109.007885) (xy 30.914317 -109.053522) (xy 30.836095 -109.092081)
			(xy 30.754638 -109.123232) (xy 30.670647 -109.146705) (xy 30.584843 -109.1623) (xy 30.497963 -109.169882)
			(xy 30.410755 -109.169386) (xy 30.323967 -109.160817) (xy 30.238346 -109.144248) (xy 30.154627 -109.119821)
			(xy 30.07353 -109.087747) (xy 29.995751 -109.048301) (xy 29.921959 -109.001823) (xy 29.852788 -108.94871)
			(xy 29.788833 -108.889421) (xy 29.730643 -108.824463) (xy 29.704284 -108.789724) (xy 29.695101 -108.778072)
			(xy 29.672373 -108.759013) (xy 29.645866 -108.745702) (xy 29.617006 -108.738853) (xy 29.602176 -108.738416)
			(xy 28.944824 -108.738416) (xy 28.944316 -108.738924) (xy 28.083764 -108.738924) (xy 28.060857 -108.739461)
			(xy 28.015781 -108.747646) (xy 27.972904 -108.763782) (xy 27.933614 -108.787344) (xy 27.899187 -108.81757)
			(xy 27.870737 -108.853479) (xy 27.849187 -108.893908) (xy 27.835236 -108.937545) (xy 27.829336 -108.982976)
			(xy 27.830018 -109.005878) (xy 27.83078 -109.030516) (xy 27.83078 -109.765592) (xy 28.14828 -110.083092)
			(xy 28.170282 -110.105825) (xy 28.208795 -110.156017) (xy 28.240428 -110.210806) (xy 28.264639 -110.269256)
			(xy 28.281013 -110.330365) (xy 28.289271 -110.393089) (xy 28.289271 -110.456355) (xy 28.281013 -110.519079)
			(xy 28.264639 -110.580188) (xy 28.240428 -110.638638) (xy 28.208795 -110.693427) (xy 28.170282 -110.743619)
			(xy 28.125547 -110.788354) (xy 28.092961 -110.813358) (xy 29.519874 -110.813358) (xy 29.519874 -110.726458)
			(xy 29.527892 -110.639929) (xy 29.54386 -110.554509) (xy 29.567641 -110.470927) (xy 29.599033 -110.389895)
			(xy 29.637767 -110.312106) (xy 29.683514 -110.238222) (xy 29.735883 -110.168875) (xy 29.794427 -110.104655)
			(xy 29.858647 -110.046111) (xy 29.927994 -109.993742) (xy 30.001878 -109.947995) (xy 30.079667 -109.909261)
			(xy 30.160699 -109.877869) (xy 30.244281 -109.854088) (xy 30.329701 -109.83812) (xy 30.41623 -109.830102)
			(xy 30.50313 -109.830102) (xy 30.589659 -109.83812) (xy 30.675079 -109.854088) (xy 30.758661 -109.877869)
			(xy 30.839693 -109.909261) (xy 30.917482 -109.947995) (xy 30.991366 -109.993742) (xy 31.060713 -110.046111)
			(xy 31.124933 -110.104655) (xy 31.183477 -110.168875) (xy 31.235846 -110.238222) (xy 31.281593 -110.312106)
			(xy 31.320327 -110.389895) (xy 31.351719 -110.470927) (xy 31.3755 -110.554509) (xy 31.391468 -110.639929)
			(xy 31.399486 -110.726458) (xy 31.399988 -110.769893) (xy 34.599047 -110.769893) (xy 34.603036 -110.683372)
			(xy 34.614965 -110.597584) (xy 34.634735 -110.513257) (xy 34.662178 -110.431105) (xy 34.69706 -110.351827)
			(xy 34.739087 -110.276092) (xy 34.787902 -110.204545) (xy 34.84309 -110.137791) (xy 34.904185 -110.076396)
			(xy 34.970668 -110.020881) (xy 35.041976 -109.971716) (xy 35.117503 -109.929319) (xy 35.19661 -109.894048)
			(xy 35.278626 -109.866204) (xy 35.362855 -109.846021) (xy 35.448584 -109.833671) (xy 35.535085 -109.829259)
			(xy 35.621625 -109.832822) (xy 35.707471 -109.84433) (xy 35.791894 -109.863685) (xy 35.874179 -109.890724)
			(xy 35.953628 -109.925216) (xy 36.029568 -109.96687) (xy 36.101354 -110.015333) (xy 36.168379 -110.070193)
			(xy 36.230073 -110.130985) (xy 36.285914 -110.197195) (xy 36.311078 -110.232444) (xy 36.320211 -110.244749)
			(xy 36.343219 -110.264975) (xy 36.37039 -110.279124) (xy 36.400154 -110.286374) (xy 36.415472 -110.2868)
			(xy 38.723824 -110.2868) (xy 38.747123 -110.286238) (xy 38.792943 -110.277756) (xy 38.836448 -110.261061)
			(xy 38.87618 -110.236714) (xy 38.910807 -110.205531) (xy 38.939168 -110.168557) (xy 38.960312 -110.127032)
			(xy 38.97353 -110.082347) (xy 38.97838 -110.036002) (xy 38.977062 -110.012734) (xy 38.975003 -109.980664)
			(xy 38.978392 -109.91649) (xy 38.990268 -109.853333) (xy 39.010422 -109.792311) (xy 39.038495 -109.734504)
			(xy 39.055802 -109.707426) (xy 39.076884 -109.675422) (xy 39.076884 -109.618018) (xy 39.129208 -109.618018)
			(xy 39.163498 -109.591602) (xy 39.188935 -109.572629) (xy 39.243848 -109.540821) (xy 39.302454 -109.516482)
			(xy 39.363745 -109.500033) (xy 39.426662 -109.491756) (xy 39.458392 -109.491272) (xy 40.336978 -109.491272)
			(xy 40.368596 -109.491713) (xy 40.431292 -109.499965) (xy 40.492374 -109.516329) (xy 40.550797 -109.540526)
			(xy 40.605563 -109.572143) (xy 40.655732 -109.610637) (xy 40.700448 -109.655351) (xy 40.738945 -109.705519)
			(xy 40.770564 -109.760283) (xy 40.794764 -109.818705) (xy 40.811131 -109.879787) (xy 40.819385 -109.942482)
			(xy 40.819385 -110.005718) (xy 40.811131 -110.068413) (xy 40.794764 -110.129495) (xy 40.770564 -110.187917)
			(xy 40.738945 -110.242681) (xy 40.700448 -110.292849) (xy 40.655732 -110.337563) (xy 40.605563 -110.376057)
			(xy 40.550797 -110.407674) (xy 40.492374 -110.431871) (xy 40.431292 -110.448235) (xy 40.368596 -110.456487)
			(xy 40.336978 -110.45698) (xy 40.192706 -110.45698) (xy 40.169313 -110.457525) (xy 40.123321 -110.466104)
			(xy 40.079675 -110.482956) (xy 40.039851 -110.50751) (xy 40.005193 -110.538939) (xy 39.976872 -110.576179)
			(xy 39.955845 -110.617974) (xy 39.942822 -110.662911) (xy 39.938243 -110.709472) (xy 39.939722 -110.732824)
			(xy 39.941263 -110.753433) (xy 39.941264 -110.786926) (xy 71.010272 -110.786926) (xy 71.010272 -109.81436)
			(xy 71.010895 -109.778302) (xy 71.021099 -109.706912) (xy 71.030592 -109.67212) (xy 71.035672 -109.654594)
			(xy 71.035672 -109.280452) (xy 72.00138 -109.280452) (xy 72.00138 -109.654594) (xy 72.00646 -109.67212)
			(xy 72.015944 -109.706913) (xy 72.026147 -109.778303) (xy 72.02678 -109.81436) (xy 72.02678 -109.942376)
			(xy 72.304656 -109.942376) (xy 72.304656 -108.96981) (xy 72.305164 -108.937084) (xy 72.313557 -108.872172)
			(xy 72.330206 -108.808873) (xy 72.354835 -108.748232) (xy 72.387039 -108.69125) (xy 72.406256 -108.664756)
			(xy 72.431656 -108.630974) (xy 72.431656 -108.613956) (xy 72.446896 -108.613956) (xy 72.48271 -108.583476)
			(xy 72.507887 -108.562623) (xy 72.562619 -108.526872) (xy 72.621484 -108.498433) (xy 72.683509 -108.477778)
			(xy 72.747671 -108.465247) (xy 72.81291 -108.461047) (xy 72.878149 -108.465247) (xy 72.942311 -108.477778)
			(xy 73.004336 -108.498433) (xy 73.063201 -108.526872) (xy 73.117933 -108.562623) (xy 73.14311 -108.583476)
			(xy 73.178924 -108.613956) (xy 73.194164 -108.613956) (xy 73.194164 -108.630974) (xy 73.219564 -108.664756)
			(xy 73.228754 -108.677184) (xy 73.245783 -108.702983) (xy 73.2536 -108.716318) (xy 73.262359 -108.73052)
			(xy 73.285932 -108.754119) (xy 73.314813 -108.770807) (xy 73.347031 -108.779446) (xy 73.380387 -108.779446)
			(xy 73.412605 -108.770807) (xy 73.441486 -108.754119) (xy 73.465059 -108.73052) (xy 73.473818 -108.716318)
			(xy 73.48163 -108.70298) (xy 73.498662 -108.677183) (xy 73.507854 -108.664756) (xy 73.533 -108.630974)
			(xy 73.533 -108.613956) (xy 73.548494 -108.613956) (xy 73.584308 -108.583476) (xy 73.609485 -108.562623)
			(xy 73.664217 -108.526872) (xy 73.723082 -108.498433) (xy 73.785107 -108.477778) (xy 73.849269 -108.465247)
			(xy 73.914508 -108.461047) (xy 73.979747 -108.465247) (xy 74.043909 -108.477778) (xy 74.105934 -108.498433)
			(xy 74.164799 -108.526872) (xy 74.219531 -108.562623) (xy 74.244708 -108.583476) (xy 74.280522 -108.613956)
			(xy 74.296016 -108.613956) (xy 74.296016 -108.630974) (xy 74.321162 -108.664756) (xy 74.340395 -108.69125)
			(xy 74.37266 -108.748215) (xy 74.397348 -108.808851) (xy 74.41405 -108.872153) (xy 74.418985 -108.91012)
			(xy 86.39887 -108.91012) (xy 86.402874 -108.710022) (xy 86.414881 -108.510244) (xy 86.434872 -108.311107)
			(xy 86.462814 -108.112929) (xy 86.498662 -107.916027) (xy 86.54236 -107.720718) (xy 86.593837 -107.527313)
			(xy 86.653011 -107.336123) (xy 86.719787 -107.147453) (xy 86.794059 -106.961606) (xy 86.875706 -106.778879)
			(xy 86.964599 -106.599566) (xy 87.060595 -106.423952) (xy 87.16354 -106.25232) (xy 87.27327 -106.084944)
			(xy 87.389608 -105.922093) (xy 87.512369 -105.764026) (xy 87.641356 -105.610998) (xy 87.776363 -105.463253)
			(xy 87.917172 -105.321027) (xy 88.063559 -105.18455) (xy 88.215289 -105.054038) (xy 88.37212 -104.929702)
			(xy 88.533799 -104.81174) (xy 88.700069 -104.700341) (xy 88.870662 -104.595684) (xy 89.045306 -104.497936)
			(xy 89.223722 -104.407253) (xy 89.405622 -104.323782) (xy 89.590717 -104.247655) (xy 89.778709 -104.178995)
			(xy 89.969298 -104.117911) (xy 90.162178 -104.064501) (xy 90.35704 -104.018852) (xy 90.553573 -103.981035)
			(xy 90.751462 -103.951111) (xy 90.950389 -103.929129) (xy 91.150037 -103.915124) (xy 91.350085 -103.909118)
			(xy 91.550213 -103.91112) (xy 91.750101 -103.921128) (xy 91.949428 -103.939125) (xy 92.147876 -103.965083)
			(xy 92.345126 -103.99896) (xy 92.540863 -104.040702) (xy 92.734773 -104.090241) (xy 92.926546 -104.147499)
			(xy 93.115875 -104.212384) (xy 93.302455 -104.284792) (xy 93.48599 -104.364608) (xy 93.666184 -104.451702)
			(xy 93.842749 -104.545936) (xy 94.015402 -104.647159) (xy 94.183867 -104.755209) (xy 94.347875 -104.869912)
			(xy 94.507162 -104.991086) (xy 94.661473 -105.118535) (xy 94.810561 -105.252056) (xy 94.954188 -105.391436)
			(xy 95.092124 -105.53645) (xy 95.224147 -105.686867) (xy 95.350046 -105.842445) (xy 95.46962 -106.002937)
			(xy 95.582676 -106.168083) (xy 95.689035 -106.337621) (xy 95.788526 -106.511279) (xy 95.880989 -106.688778)
			(xy 95.966276 -106.869834) (xy 96.044251 -107.054158) (xy 96.114788 -107.241454) (xy 96.177776 -107.431422)
			(xy 96.233113 -107.623758) (xy 96.28071 -107.818154) (xy 96.320491 -108.014299) (xy 96.352393 -108.211878)
			(xy 96.376364 -108.410575) (xy 96.392366 -108.610073) (xy 96.400373 -108.810051) (xy 96.400874 -108.91012)
			(xy 96.400373 -109.010189) (xy 96.392366 -109.210167) (xy 96.376364 -109.409665) (xy 96.352393 -109.608362)
			(xy 96.320491 -109.805941) (xy 96.28071 -110.002086) (xy 96.233113 -110.196482) (xy 96.177776 -110.388818)
			(xy 96.114788 -110.578786) (xy 96.044251 -110.766082) (xy 95.966276 -110.950406) (xy 95.880989 -111.131462)
			(xy 95.788526 -111.308961) (xy 95.689035 -111.482619) (xy 95.582676 -111.652157) (xy 95.46962 -111.817303)
			(xy 95.350046 -111.977795) (xy 95.224147 -112.133373) (xy 95.092124 -112.28379) (xy 94.954188 -112.428804)
			(xy 94.810561 -112.568184) (xy 94.661473 -112.701705) (xy 94.507162 -112.829154) (xy 94.347875 -112.950328)
			(xy 94.183867 -113.065031) (xy 94.015402 -113.173081) (xy 93.842749 -113.274304) (xy 93.666184 -113.368538)
			(xy 93.48599 -113.455632) (xy 93.302455 -113.535448) (xy 93.115875 -113.607856) (xy 92.926546 -113.672741)
			(xy 92.734773 -113.729999) (xy 92.540863 -113.779538) (xy 92.345126 -113.82128) (xy 92.147876 -113.855157)
			(xy 91.949428 -113.881115) (xy 91.750101 -113.899112) (xy 91.550213 -113.90912) (xy 91.350085 -113.911122)
			(xy 91.150037 -113.905116) (xy 90.950389 -113.891111) (xy 90.751462 -113.869129) (xy 90.553573 -113.839205)
			(xy 90.35704 -113.801388) (xy 90.162178 -113.755739) (xy 89.969298 -113.702329) (xy 89.778709 -113.641245)
			(xy 89.590717 -113.572585) (xy 89.405622 -113.496458) (xy 89.223722 -113.412987) (xy 89.045306 -113.322304)
			(xy 88.870662 -113.224556) (xy 88.700069 -113.119899) (xy 88.533799 -113.0085) (xy 88.37212 -112.890538)
			(xy 88.215289 -112.766202) (xy 88.063559 -112.63569) (xy 87.917172 -112.499213) (xy 87.776363 -112.356987)
			(xy 87.641356 -112.209242) (xy 87.512369 -112.056214) (xy 87.389608 -111.898147) (xy 87.27327 -111.735296)
			(xy 87.16354 -111.56792) (xy 87.060595 -111.396288) (xy 86.964599 -111.220674) (xy 86.875706 -111.041361)
			(xy 86.794059 -110.858634) (xy 86.719787 -110.672787) (xy 86.653011 -110.484117) (xy 86.593837 -110.292927)
			(xy 86.54236 -110.099522) (xy 86.498662 -109.904213) (xy 86.462814 -109.707311) (xy 86.434872 -109.509133)
			(xy 86.414881 -109.309996) (xy 86.402874 -109.110218) (xy 86.39887 -108.91012) (xy 74.418985 -108.91012)
			(xy 74.422489 -108.937076) (xy 74.423016 -108.96981) (xy 74.423016 -109.942376) (xy 74.422453 -109.974203)
			(xy 74.414498 -110.037357) (xy 74.398722 -110.099025) (xy 74.375372 -110.158241) (xy 74.344814 -110.214079)
			(xy 74.307524 -110.265667) (xy 74.264087 -110.312196) (xy 74.215181 -110.352939) (xy 74.161573 -110.387259)
			(xy 74.104099 -110.41462) (xy 74.04366 -110.434592) (xy 73.981201 -110.446864) (xy 73.917699 -110.451244)
			(xy 73.854146 -110.447663) (xy 73.791537 -110.436177) (xy 73.730852 -110.416965) (xy 73.673039 -110.39033)
			(xy 73.619004 -110.356686) (xy 73.56959 -110.31656) (xy 73.547224 -110.293912) (xy 73.531122 -110.277745)
			(xy 73.494226 -110.250908) (xy 73.453127 -110.231097) (xy 73.409149 -110.218949) (xy 73.363709 -110.214856)
			(xy 73.318269 -110.218949) (xy 73.274291 -110.231097) (xy 73.233192 -110.250908) (xy 73.196296 -110.277745)
			(xy 73.180194 -110.293912) (xy 73.157797 -110.316519) (xy 73.108392 -110.356629) (xy 73.054366 -110.390259)
			(xy 72.996566 -110.416882) (xy 72.935895 -110.436083) (xy 72.873301 -110.447561) (xy 72.809765 -110.451136)
			(xy 72.746279 -110.446753) (xy 72.683836 -110.43448) (xy 72.623414 -110.41451) (xy 72.565957 -110.387153)
			(xy 72.512364 -110.35284) (xy 72.463473 -110.312105) (xy 72.420048 -110.265586) (xy 72.38277 -110.214011)
			(xy 72.35222 -110.158186) (xy 72.328877 -110.098985) (xy 72.313106 -110.037333) (xy 72.305154 -109.974194)
			(xy 72.304656 -109.942376) (xy 72.02678 -109.942376) (xy 72.02678 -110.786926) (xy 72.026279 -110.818871)
			(xy 72.018271 -110.882257) (xy 72.002382 -110.94414) (xy 71.978863 -111.003544) (xy 71.948083 -111.059531)
			(xy 71.91053 -111.11122) (xy 71.866794 -111.157794) (xy 71.817566 -111.198519) (xy 71.763621 -111.232753)
			(xy 71.705812 -111.259956) (xy 71.645049 -111.279699) (xy 71.58229 -111.291671) (xy 71.518526 -111.295683)
			(xy 71.454762 -111.291671) (xy 71.392003 -111.279699) (xy 71.33124 -111.259956) (xy 71.273431 -111.232753)
			(xy 71.219486 -111.198519) (xy 71.170258 -111.157794) (xy 71.126522 -111.11122) (xy 71.088969 -111.059531)
			(xy 71.058189 -111.003544) (xy 71.03467 -110.94414) (xy 71.018781 -110.882257) (xy 71.010773 -110.818871)
			(xy 71.010272 -110.786926) (xy 39.941264 -110.786926) (xy 39.941264 -110.794765) (xy 39.939722 -110.815374)
			(xy 39.938197 -110.838715) (xy 39.942792 -110.885259) (xy 39.95583 -110.930176) (xy 39.97687 -110.971947)
			(xy 40.005201 -111.009161) (xy 40.039866 -111.040559) (xy 40.079693 -111.065081) (xy 40.123336 -111.081898)
			(xy 40.16932 -111.090441) (xy 40.192706 -111.090964) (xy 40.390826 -111.090964) (xy 40.422454 -111.091539)
			(xy 40.485168 -111.099798) (xy 40.546267 -111.116173) (xy 40.604707 -111.140382) (xy 40.659486 -111.172012)
			(xy 40.709669 -111.210521) (xy 40.754396 -111.25525) (xy 40.792903 -111.305435) (xy 40.82453 -111.360217)
			(xy 40.848736 -111.418657) (xy 40.865107 -111.479758) (xy 40.873363 -111.542472) (xy 40.873363 -111.605728)
			(xy 40.865107 -111.668442) (xy 40.848736 -111.729543) (xy 40.82453 -111.787983) (xy 40.792903 -111.842765)
			(xy 40.754396 -111.89295) (xy 40.709669 -111.937679) (xy 40.659486 -111.976188) (xy 40.604707 -112.007818)
			(xy 40.546267 -112.032027) (xy 40.485168 -112.048402) (xy 40.422454 -112.056661) (xy 40.390826 -112.05718)
			(xy 39.459154 -112.05718) (xy 39.427416 -112.05666) (xy 39.36449 -112.048336) (xy 39.303196 -112.031836)
			(xy 39.244594 -112.007447) (xy 39.189693 -111.975587) (xy 39.16426 -111.956596) (xy 39.12997 -111.93018)
			(xy 39.077646 -111.93018) (xy 39.077646 -111.872776) (xy 39.056564 -111.840772) (xy 39.038963 -111.813241)
			(xy 39.010523 -111.754411) (xy 38.990273 -111.692285) (xy 38.978582 -111.627995) (xy 38.975663 -111.562717)
			(xy 38.978078 -111.53013) (xy 38.979728 -111.506726) (xy 38.975338 -111.460016) (xy 38.962452 -111.414905)
			(xy 38.941508 -111.372924) (xy 38.913218 -111.335498) (xy 38.878542 -111.303897) (xy 38.838656 -111.279195)
			(xy 38.794916 -111.26223) (xy 38.748805 -111.253577) (xy 38.725348 -111.253016) (xy 36.415472 -111.253016)
			(xy 36.400156 -111.253447) (xy 36.370398 -111.260709) (xy 36.343229 -111.274857) (xy 36.320217 -111.295073)
			(xy 36.311078 -111.307372) (xy 36.285906 -111.342616) (xy 36.230064 -111.408824) (xy 36.168369 -111.469616)
			(xy 36.101344 -111.524475) (xy 36.029557 -111.572936) (xy 35.953616 -111.61459) (xy 35.874167 -111.649081)
			(xy 35.791881 -111.676118) (xy 35.707458 -111.695473) (xy 35.621612 -111.706979) (xy 35.535072 -111.710541)
			(xy 35.44857 -111.706128) (xy 35.362842 -111.693777) (xy 35.278613 -111.673593) (xy 35.196598 -111.645747)
			(xy 35.117491 -111.610475) (xy 35.041964 -111.568077) (xy 34.970658 -111.518911) (xy 34.904176 -111.463395)
			(xy 34.843082 -111.402) (xy 34.787894 -111.335245) (xy 34.73908 -111.263696) (xy 34.697054 -111.187962)
			(xy 34.662173 -111.108682) (xy 34.634732 -111.026531) (xy 34.614963 -110.942203) (xy 34.603035 -110.856415)
			(xy 34.599047 -110.769893) (xy 31.399988 -110.769893) (xy 31.399988 -110.769908) (xy 31.399486 -110.813358)
			(xy 31.391468 -110.899887) (xy 31.3755 -110.985307) (xy 31.351719 -111.068889) (xy 31.320327 -111.149921)
			(xy 31.281593 -111.22771) (xy 31.235846 -111.301594) (xy 31.183477 -111.370941) (xy 31.124933 -111.435161)
			(xy 31.060713 -111.493705) (xy 30.991366 -111.546074) (xy 30.917482 -111.591821) (xy 30.839693 -111.630555)
			(xy 30.758661 -111.661947) (xy 30.675079 -111.685728) (xy 30.589659 -111.701696) (xy 30.50313 -111.709714)
			(xy 30.41623 -111.709714) (xy 30.329701 -111.701696) (xy 30.244281 -111.685728) (xy 30.160699 -111.661947)
			(xy 30.079667 -111.630555) (xy 30.001878 -111.591821) (xy 29.927994 -111.546074) (xy 29.858647 -111.493705)
			(xy 29.794427 -111.435161) (xy 29.735883 -111.370941) (xy 29.683514 -111.301594) (xy 29.637767 -111.22771)
			(xy 29.599033 -111.149921) (xy 29.567641 -111.068889) (xy 29.54386 -110.985307) (xy 29.527892 -110.899887)
			(xy 29.519874 -110.813358) (xy 28.092961 -110.813358) (xy 28.075355 -110.826867) (xy 28.020566 -110.8585)
			(xy 27.962116 -110.882711) (xy 27.901007 -110.899085) (xy 27.838283 -110.907343) (xy 27.775017 -110.907343)
			(xy 27.712293 -110.899085) (xy 27.651184 -110.882711) (xy 27.592734 -110.8585) (xy 27.537945 -110.826867)
			(xy 27.487753 -110.788354) (xy 27.46502 -110.766352) (xy 26.864564 -110.165896) (xy 26.864564 -109.030516)
			(xy 26.866596 -108.987082) (xy 26.868128 -108.964902) (xy 26.864315 -108.920608) (xy 26.852854 -108.877654)
			(xy 26.834093 -108.837349) (xy 26.808606 -108.800923) (xy 26.777169 -108.769487) (xy 26.740742 -108.744001)
			(xy 26.700436 -108.725242) (xy 26.657481 -108.713783) (xy 26.613187 -108.709972) (xy 26.591006 -108.711492)
			(xy 26.547572 -108.713524) (xy 25.90546 -108.713524) (xy 25.873829 -108.713015) (xy 25.811108 -108.704758)
			(xy 25.750002 -108.688384) (xy 25.691556 -108.664175) (xy 25.636769 -108.632544) (xy 25.58658 -108.594033)
			(xy 25.541847 -108.5493) (xy 25.503336 -108.499111) (xy 25.471705 -108.444324) (xy 25.447496 -108.385878)
			(xy 25.431122 -108.324772) (xy 25.422865 -108.262051) (xy 25.422865 -108.198789) (xy 25.431122 -108.136068)
			(xy 25.447496 -108.074962) (xy 25.471705 -108.016516) (xy 25.503336 -107.961729) (xy 25.541847 -107.91154)
			(xy 25.58658 -107.866807) (xy 25.636769 -107.828296) (xy 25.691556 -107.796665) (xy 25.750002 -107.772456)
			(xy 25.811108 -107.756082) (xy 25.873829 -107.747825) (xy 25.90546 -107.747308) (xy 26.547572 -107.747308)
			(xy 26.591006 -107.74934) (xy 26.613185 -107.750921) (xy 26.657485 -107.747109) (xy 26.700445 -107.735647)
			(xy 26.740756 -107.716883) (xy 26.777185 -107.69139) (xy 26.808622 -107.659946) (xy 26.834108 -107.623511)
			(xy 26.852864 -107.583198) (xy 26.864318 -107.540235) (xy 26.868121 -107.495934) (xy 26.866596 -107.47375)
			(xy 26.864564 -107.430316) (xy 26.864564 -107.220258) (xy 26.94686 -107.138216) (xy 26.966164 -107.091734)
			(xy 26.966164 -107.074208) (xy 27.010868 -107.074208) (xy 27.630882 -106.454194) (xy 27.646822 -106.437558)
			(xy 27.672994 -106.399645) (xy 27.691903 -106.357635) (xy 27.702929 -106.312905) (xy 27.705712 -106.266919)
			(xy 27.70016 -106.221186) (xy 27.686456 -106.177202) (xy 27.665047 -106.136409) (xy 27.636636 -106.100144)
			(xy 27.602153 -106.069593) (xy 27.562729 -106.045759) (xy 27.519653 -106.029422) (xy 27.474339 -106.021117)
			(xy 27.451304 -106.020616) (xy 24.230584 -106.020616) (xy 24.04872 -106.20248) (xy 24.039068 -106.229912)
			(xy 24.029106 -106.257044) (xy 24.002199 -106.308194) (xy 23.985474 -106.331766) (xy 23.972027 -106.350969)
			(xy 23.951534 -106.393123) (xy 23.939123 -106.43832) (xy 23.935214 -106.485028) (xy 23.93994 -106.53166)
			(xy 23.953141 -106.576633) (xy 23.974369 -106.618421) (xy 24.002903 -106.655606) (xy 24.037775 -106.686924)
			(xy 24.077801 -106.711313) (xy 24.09952 -106.720132) (xy 24.125536 -106.730475) (xy 24.174412 -106.757783)
			(xy 24.218772 -106.79194) (xy 24.257665 -106.832213) (xy 24.290255 -106.877738) (xy 24.315843 -106.927535)
			(xy 24.333879 -106.980538) (xy 24.343976 -107.035607) (xy 24.345918 -107.09156) (xy 24.339663 -107.147197)
			(xy 24.325344 -107.201322) (xy 24.30327 -107.252774) (xy 24.273914 -107.300448) (xy 24.237907 -107.34332)
			(xy 24.196021 -107.38047) (xy 24.149156 -107.411101) (xy 24.098318 -107.434555) (xy 24.044599 -107.450328)
			(xy 23.989151 -107.458081) (xy 23.933166 -107.457649) (xy 23.877844 -107.44904) (xy 23.824375 -107.43244)
			(xy 23.773905 -107.408204) (xy 23.727519 -107.376854) (xy 23.686212 -107.339061) (xy 23.65087 -107.295638)
			(xy 23.622254 -107.247517) (xy 23.600977 -107.19573) (xy 23.587495 -107.141391) (xy 23.5821 -107.085664)
			(xy 23.584905 -107.029747) (xy 23.595851 -106.974841) (xy 23.614703 -106.922123) (xy 23.641057 -106.872726)
			(xy 23.657306 -106.849926) (xy 23.670771 -106.830734) (xy 23.691266 -106.788579) (xy 23.703678 -106.743378)
			(xy 23.707587 -106.696668) (xy 23.702859 -106.650034) (xy 23.689656 -106.605058) (xy 23.668425 -106.563268)
			(xy 23.639887 -106.526083) (xy 23.605011 -106.494765) (xy 23.564981 -106.470378) (xy 23.54326 -106.46156)
			(xy 23.51779 -106.451326) (xy 23.469793 -106.424698) (xy 23.426109 -106.391465) (xy 23.38764 -106.352313)
			(xy 23.35518 -106.308052) (xy 23.3294 -106.259594) (xy 23.310832 -106.207942) (xy 23.29986 -106.154161)
			(xy 23.29671 -106.099363) (xy 22.8473 -106.099363) (xy 22.8473 -107.967272) (xy 27.89936 -113.019332)
			(xy 27.89936 -113.353358) (xy 29.519874 -113.353358) (xy 29.519874 -113.266458) (xy 29.527892 -113.179929)
			(xy 29.54386 -113.094509) (xy 29.567641 -113.010927) (xy 29.599033 -112.929895) (xy 29.637767 -112.852106)
			(xy 29.683514 -112.778222) (xy 29.735883 -112.708875) (xy 29.794427 -112.644655) (xy 29.858647 -112.586111)
			(xy 29.927994 -112.533742) (xy 30.001878 -112.487995) (xy 30.079667 -112.449261) (xy 30.160699 -112.417869)
			(xy 30.244281 -112.394088) (xy 30.329701 -112.37812) (xy 30.41623 -112.370102) (xy 30.50313 -112.370102)
			(xy 30.589659 -112.37812) (xy 30.675079 -112.394088) (xy 30.758661 -112.417869) (xy 30.839693 -112.449261)
			(xy 30.917482 -112.487995) (xy 30.991366 -112.533742) (xy 31.060713 -112.586111) (xy 31.124933 -112.644655)
			(xy 31.183477 -112.708875) (xy 31.235846 -112.778222) (xy 31.281593 -112.852106) (xy 31.320327 -112.929895)
			(xy 31.351719 -113.010927) (xy 31.3755 -113.094509) (xy 31.391468 -113.179929) (xy 31.399486 -113.266458)
			(xy 31.399988 -113.309908) (xy 31.399486 -113.353358) (xy 34.599874 -113.353358) (xy 34.599874 -113.266458)
			(xy 34.607892 -113.179929) (xy 34.62386 -113.094509) (xy 34.647641 -113.010927) (xy 34.679033 -112.929895)
			(xy 34.717767 -112.852106) (xy 34.763514 -112.778222) (xy 34.815883 -112.708875) (xy 34.874427 -112.644655)
			(xy 34.938647 -112.586111) (xy 35.007994 -112.533742) (xy 35.081878 -112.487995) (xy 35.159667 -112.449261)
			(xy 35.240699 -112.417869) (xy 35.324281 -112.394088) (xy 35.409701 -112.37812) (xy 35.49623 -112.370102)
			(xy 35.58313 -112.370102) (xy 35.669659 -112.37812) (xy 35.755079 -112.394088) (xy 35.838661 -112.417869)
			(xy 35.919693 -112.449261) (xy 35.997482 -112.487995) (xy 36.071366 -112.533742) (xy 36.140713 -112.586111)
			(xy 36.204933 -112.644655) (xy 36.263477 -112.708875) (xy 36.315846 -112.778222) (xy 36.361593 -112.852106)
			(xy 36.400327 -112.929895) (xy 36.431719 -113.010927) (xy 36.4555 -113.094509) (xy 36.471468 -113.179929)
			(xy 36.479486 -113.266458) (xy 36.479988 -113.309908) (xy 36.479486 -113.353358) (xy 36.471468 -113.439887)
			(xy 36.4555 -113.525307) (xy 36.431719 -113.608889) (xy 36.400327 -113.689921) (xy 36.361593 -113.76771)
			(xy 36.315846 -113.841594) (xy 36.263477 -113.910941) (xy 36.204933 -113.975161) (xy 36.140713 -114.033705)
			(xy 36.071366 -114.086074) (xy 35.997482 -114.131821) (xy 35.919693 -114.170555) (xy 35.838661 -114.201947)
			(xy 35.755079 -114.225728) (xy 35.669659 -114.241696) (xy 35.58313 -114.249714) (xy 35.49623 -114.249714)
			(xy 35.409701 -114.241696) (xy 35.324281 -114.225728) (xy 35.240699 -114.201947) (xy 35.159667 -114.170555)
			(xy 35.081878 -114.131821) (xy 35.007994 -114.086074) (xy 34.938647 -114.033705) (xy 34.874427 -113.975161)
			(xy 34.815883 -113.910941) (xy 34.763514 -113.841594) (xy 34.717767 -113.76771) (xy 34.679033 -113.689921)
			(xy 34.647641 -113.608889) (xy 34.62386 -113.525307) (xy 34.607892 -113.439887) (xy 34.599874 -113.353358)
			(xy 31.399486 -113.353358) (xy 31.391468 -113.439887) (xy 31.3755 -113.525307) (xy 31.351719 -113.608889)
			(xy 31.320327 -113.689921) (xy 31.281593 -113.76771) (xy 31.235846 -113.841594) (xy 31.183477 -113.910941)
			(xy 31.124933 -113.975161) (xy 31.060713 -114.033705) (xy 30.991366 -114.086074) (xy 30.917482 -114.131821)
			(xy 30.839693 -114.170555) (xy 30.758661 -114.201947) (xy 30.675079 -114.225728) (xy 30.589659 -114.241696)
			(xy 30.50313 -114.249714) (xy 30.41623 -114.249714) (xy 30.329701 -114.241696) (xy 30.244281 -114.225728)
			(xy 30.160699 -114.201947) (xy 30.079667 -114.170555) (xy 30.001878 -114.131821) (xy 29.927994 -114.086074)
			(xy 29.858647 -114.033705) (xy 29.794427 -113.975161) (xy 29.735883 -113.910941) (xy 29.683514 -113.841594)
			(xy 29.637767 -113.76771) (xy 29.599033 -113.689921) (xy 29.567641 -113.608889) (xy 29.54386 -113.525307)
			(xy 29.527892 -113.439887) (xy 29.519874 -113.353358) (xy 27.89936 -113.353358) (xy 27.89936 -115.893358)
			(xy 29.519874 -115.893358) (xy 29.519874 -115.806458) (xy 29.527892 -115.719929) (xy 29.54386 -115.634509)
			(xy 29.567641 -115.550927) (xy 29.599033 -115.469895) (xy 29.637767 -115.392106) (xy 29.683514 -115.318222)
			(xy 29.735883 -115.248875) (xy 29.794427 -115.184655) (xy 29.858647 -115.126111) (xy 29.927994 -115.073742)
			(xy 30.001878 -115.027995) (xy 30.079667 -114.989261) (xy 30.160699 -114.957869) (xy 30.244281 -114.934088)
			(xy 30.329701 -114.91812) (xy 30.41623 -114.910102) (xy 30.50313 -114.910102) (xy 30.589659 -114.91812)
			(xy 30.675079 -114.934088) (xy 30.758661 -114.957869) (xy 30.839693 -114.989261) (xy 30.917482 -115.027995)
			(xy 30.991366 -115.073742) (xy 31.060713 -115.126111) (xy 31.124933 -115.184655) (xy 31.183477 -115.248875)
			(xy 31.235846 -115.318222) (xy 31.281593 -115.392106) (xy 31.320327 -115.469895) (xy 31.351719 -115.550927)
			(xy 31.3755 -115.634509) (xy 31.391468 -115.719929) (xy 31.399486 -115.806458) (xy 31.399988 -115.849908)
			(xy 31.399486 -115.893358) (xy 34.599874 -115.893358) (xy 34.599874 -115.806458) (xy 34.607892 -115.719929)
			(xy 34.62386 -115.634509) (xy 34.647641 -115.550927) (xy 34.679033 -115.469895) (xy 34.717767 -115.392106)
			(xy 34.763514 -115.318222) (xy 34.815883 -115.248875) (xy 34.874427 -115.184655) (xy 34.938647 -115.126111)
			(xy 35.007994 -115.073742) (xy 35.081878 -115.027995) (xy 35.159667 -114.989261) (xy 35.240699 -114.957869)
			(xy 35.324281 -114.934088) (xy 35.409701 -114.91812) (xy 35.49623 -114.910102) (xy 35.58313 -114.910102)
			(xy 35.669659 -114.91812) (xy 35.755079 -114.934088) (xy 35.838661 -114.957869) (xy 35.919693 -114.989261)
			(xy 35.997482 -115.027995) (xy 36.071366 -115.073742) (xy 36.140713 -115.126111) (xy 36.204933 -115.184655)
			(xy 36.263477 -115.248875) (xy 36.315846 -115.318222) (xy 36.361593 -115.392106) (xy 36.400327 -115.469895)
			(xy 36.431719 -115.550927) (xy 36.4555 -115.634509) (xy 36.471468 -115.719929) (xy 36.479486 -115.806458)
			(xy 36.479988 -115.849908) (xy 36.479486 -115.893358) (xy 36.471468 -115.979887) (xy 36.4555 -116.065307)
			(xy 36.431719 -116.148889) (xy 36.400327 -116.229921) (xy 36.361593 -116.30771) (xy 36.315846 -116.381594)
			(xy 36.263477 -116.450941) (xy 36.204933 -116.515161) (xy 36.140713 -116.573705) (xy 36.071366 -116.626074)
			(xy 35.997482 -116.671821) (xy 35.919693 -116.710555) (xy 35.838661 -116.741947) (xy 35.755079 -116.765728)
			(xy 35.669659 -116.781696) (xy 35.58313 -116.789714) (xy 35.49623 -116.789714) (xy 35.409701 -116.781696)
			(xy 35.324281 -116.765728) (xy 35.240699 -116.741947) (xy 35.159667 -116.710555) (xy 35.081878 -116.671821)
			(xy 35.007994 -116.626074) (xy 34.938647 -116.573705) (xy 34.874427 -116.515161) (xy 34.815883 -116.450941)
			(xy 34.763514 -116.381594) (xy 34.717767 -116.30771) (xy 34.679033 -116.229921) (xy 34.647641 -116.148889)
			(xy 34.62386 -116.065307) (xy 34.607892 -115.979887) (xy 34.599874 -115.893358) (xy 31.399486 -115.893358)
			(xy 31.391468 -115.979887) (xy 31.3755 -116.065307) (xy 31.351719 -116.148889) (xy 31.320327 -116.229921)
			(xy 31.281593 -116.30771) (xy 31.235846 -116.381594) (xy 31.183477 -116.450941) (xy 31.124933 -116.515161)
			(xy 31.060713 -116.573705) (xy 30.991366 -116.626074) (xy 30.917482 -116.671821) (xy 30.839693 -116.710555)
			(xy 30.758661 -116.741947) (xy 30.675079 -116.765728) (xy 30.589659 -116.781696) (xy 30.50313 -116.789714)
			(xy 30.41623 -116.789714) (xy 30.329701 -116.781696) (xy 30.244281 -116.765728) (xy 30.160699 -116.741947)
			(xy 30.079667 -116.710555) (xy 30.001878 -116.671821) (xy 29.927994 -116.626074) (xy 29.858647 -116.573705)
			(xy 29.794427 -116.515161) (xy 29.735883 -116.450941) (xy 29.683514 -116.381594) (xy 29.637767 -116.30771)
			(xy 29.599033 -116.229921) (xy 29.567641 -116.148889) (xy 29.54386 -116.065307) (xy 29.527892 -115.979887)
			(xy 29.519874 -115.893358) (xy 27.89936 -115.893358) (xy 27.89936 -117.275426) (xy 39.351236 -117.275426)
			(xy 39.355121 -117.221063) (xy 39.366703 -117.167807) (xy 39.385747 -117.116741) (xy 39.411865 -117.068905)
			(xy 39.444526 -117.025273) (xy 39.483063 -116.986734) (xy 39.526694 -116.954072) (xy 39.574529 -116.927953)
			(xy 39.625594 -116.908907) (xy 39.67885 -116.897323) (xy 39.733213 -116.893436) (xy 39.787576 -116.897326)
			(xy 39.840831 -116.908914) (xy 39.891895 -116.927963) (xy 39.939728 -116.954086) (xy 39.96182 -116.970048)
			(xy 39.980832 -116.983644) (xy 40.022715 -117.004376) (xy 40.067683 -117.017102) (xy 40.11422 -117.021392)
			(xy 40.160757 -117.017102) (xy 40.205725 -117.004376) (xy 40.247608 -116.983644) (xy 40.26662 -116.970048)
			(xy 40.288749 -116.954149) (xy 40.33657 -116.928037) (xy 40.387621 -116.908997) (xy 40.440862 -116.897416)
			(xy 40.49521 -116.893531) (xy 40.549557 -116.897419) (xy 40.602797 -116.909003) (xy 40.653847 -116.928045)
			(xy 40.701667 -116.95416) (xy 40.745284 -116.986814) (xy 40.78381 -117.025343) (xy 40.81646 -117.068963)
			(xy 40.841655 -117.115111) (xy 57.923274 -117.115111) (xy 57.92716 -117.060755) (xy 57.938743 -117.007505)
			(xy 57.957786 -116.956446) (xy 57.983902 -116.908617) (xy 58.016559 -116.864992) (xy 58.055093 -116.826458)
			(xy 58.098719 -116.793801) (xy 58.146548 -116.767685) (xy 58.197607 -116.748642) (xy 58.250857 -116.73706)
			(xy 58.305213 -116.733174) (xy 58.359568 -116.737063) (xy 58.412817 -116.748649) (xy 58.463875 -116.767696)
			(xy 58.511703 -116.793815) (xy 58.533792 -116.809774) (xy 58.552804 -116.82337) (xy 58.594687 -116.844102)
			(xy 58.639655 -116.856828) (xy 58.686192 -116.861118) (xy 58.732729 -116.856828) (xy 58.777697 -116.844102)
			(xy 58.81958 -116.82337) (xy 58.838592 -116.809774) (xy 58.860697 -116.793838) (xy 58.908522 -116.767718)
			(xy 58.959578 -116.748671) (xy 59.012824 -116.737084) (xy 59.067178 -116.733193) (xy 59.121532 -116.737078)
			(xy 59.17478 -116.748659) (xy 59.225838 -116.7677) (xy 59.273666 -116.793814) (xy 59.317291 -116.826469)
			(xy 59.355823 -116.865001) (xy 59.38848 -116.908625) (xy 59.414596 -116.956452) (xy 59.433638 -117.007509)
			(xy 59.445221 -117.060757) (xy 59.449107 -117.115111) (xy 59.445218 -117.169465) (xy 59.433632 -117.222712)
			(xy 59.414587 -117.273768) (xy 59.388468 -117.321594) (xy 59.355809 -117.365215) (xy 59.317274 -117.403745)
			(xy 59.273648 -117.436398) (xy 59.225818 -117.462509) (xy 59.17476 -117.481548) (xy 59.121511 -117.493125)
			(xy 59.067157 -117.497007) (xy 59.012803 -117.493113) (xy 58.959557 -117.481523) (xy 58.908503 -117.462473)
			(xy 58.860679 -117.436351) (xy 58.838592 -117.42039) (xy 58.81958 -117.406794) (xy 58.777697 -117.386062)
			(xy 58.732729 -117.373336) (xy 58.686192 -117.369046) (xy 58.639655 -117.373336) (xy 58.594687 -117.386062)
			(xy 58.552804 -117.406794) (xy 58.533792 -117.42039) (xy 58.511721 -117.436374) (xy 58.463895 -117.462495)
			(xy 58.412838 -117.481545) (xy 58.35959 -117.493133) (xy 58.305234 -117.497026) (xy 58.250878 -117.493143)
			(xy 58.197628 -117.481564) (xy 58.146568 -117.462524) (xy 58.098737 -117.436411) (xy 58.055109 -117.403756)
			(xy 58.016574 -117.365225) (xy 57.983914 -117.321601) (xy 57.957795 -117.273774) (xy 57.938749 -117.222715)
			(xy 57.927163 -117.169467) (xy 57.923274 -117.115111) (xy 40.841655 -117.115111) (xy 40.84257 -117.116786)
			(xy 40.861608 -117.167837) (xy 40.873186 -117.221079) (xy 40.877069 -117.275426) (xy 40.873178 -117.329773)
			(xy 40.861593 -117.383013) (xy 40.842548 -117.434062) (xy 40.816431 -117.481881) (xy 40.783775 -117.525497)
			(xy 40.745244 -117.564021) (xy 40.701623 -117.596669) (xy 40.653799 -117.622777) (xy 40.602747 -117.641812)
			(xy 40.549505 -117.653388) (xy 40.495157 -117.657269) (xy 40.44081 -117.653376) (xy 40.387571 -117.641788)
			(xy 40.336522 -117.622741) (xy 40.288705 -117.596622) (xy 40.26662 -117.580664) (xy 40.247608 -117.567068)
			(xy 40.205725 -117.546336) (xy 40.160757 -117.53361) (xy 40.11422 -117.52932) (xy 40.067683 -117.53361)
			(xy 40.022715 -117.546336) (xy 39.980832 -117.567068) (xy 39.96182 -117.580664) (xy 39.939773 -117.596685)
			(xy 39.891943 -117.622815) (xy 39.840882 -117.641871) (xy 39.787628 -117.653466) (xy 39.733266 -117.657364)
			(xy 39.678903 -117.653485) (xy 39.625645 -117.641908) (xy 39.574577 -117.622869) (xy 39.526738 -117.596756)
			(xy 39.483103 -117.5641) (xy 39.44456 -117.525567) (xy 39.411894 -117.481939) (xy 39.385769 -117.434107)
			(xy 39.366718 -117.383044) (xy 39.355128 -117.329789) (xy 39.351236 -117.275426) (xy 27.89936 -117.275426)
			(xy 27.89936 -118.433358) (xy 29.519874 -118.433358) (xy 29.519874 -118.346458) (xy 29.527892 -118.259929)
			(xy 29.54386 -118.174509) (xy 29.567641 -118.090927) (xy 29.599033 -118.009895) (xy 29.637767 -117.932106)
			(xy 29.683514 -117.858222) (xy 29.735883 -117.788875) (xy 29.794427 -117.724655) (xy 29.858647 -117.666111)
			(xy 29.927994 -117.613742) (xy 30.001878 -117.567995) (xy 30.079667 -117.529261) (xy 30.160699 -117.497869)
			(xy 30.244281 -117.474088) (xy 30.329701 -117.45812) (xy 30.41623 -117.450102) (xy 30.50313 -117.450102)
			(xy 30.589659 -117.45812) (xy 30.675079 -117.474088) (xy 30.758661 -117.497869) (xy 30.839693 -117.529261)
			(xy 30.917482 -117.567995) (xy 30.991366 -117.613742) (xy 31.060713 -117.666111) (xy 31.124933 -117.724655)
			(xy 31.183477 -117.788875) (xy 31.235846 -117.858222) (xy 31.281593 -117.932106) (xy 31.320327 -118.009895)
			(xy 31.351719 -118.090927) (xy 31.3755 -118.174509) (xy 31.391468 -118.259929) (xy 31.399486 -118.346458)
			(xy 31.399988 -118.389908) (xy 31.399486 -118.433358) (xy 34.599874 -118.433358) (xy 34.599874 -118.346458)
			(xy 34.607892 -118.259929) (xy 34.62386 -118.174509) (xy 34.647641 -118.090927) (xy 34.679033 -118.009895)
			(xy 34.717767 -117.932106) (xy 34.763514 -117.858222) (xy 34.815883 -117.788875) (xy 34.874427 -117.724655)
			(xy 34.938647 -117.666111) (xy 35.007994 -117.613742) (xy 35.081878 -117.567995) (xy 35.159667 -117.529261)
			(xy 35.240699 -117.497869) (xy 35.324281 -117.474088) (xy 35.409701 -117.45812) (xy 35.49623 -117.450102)
			(xy 35.58313 -117.450102) (xy 35.669659 -117.45812) (xy 35.755079 -117.474088) (xy 35.838661 -117.497869)
			(xy 35.919693 -117.529261) (xy 35.997482 -117.567995) (xy 36.071366 -117.613742) (xy 36.131998 -117.65953)
			(xy 67.010817 -117.65953) (xy 67.010817 -117.59627) (xy 67.019074 -117.533552) (xy 67.035446 -117.472448)
			(xy 67.059654 -117.414004) (xy 67.091283 -117.35922) (xy 67.129793 -117.309032) (xy 67.174523 -117.264301)
			(xy 67.22471 -117.22579) (xy 67.279493 -117.19416) (xy 67.337937 -117.16995) (xy 67.39904 -117.153576)
			(xy 67.461758 -117.145318) (xy 67.493388 -117.1448) (xy 68.291964 -117.1448) (xy 68.32263 -117.143785)
			(xy 68.383805 -117.148515) (xy 68.443889 -117.16095) (xy 68.501915 -117.180891) (xy 68.556951 -117.208016)
			(xy 68.582794 -117.224556) (xy 68.614798 -117.245638) (xy 68.81749 -117.245638) (xy 68.849494 -117.224556)
			(xy 68.873282 -117.209294) (xy 68.923737 -117.183819) (xy 68.976817 -117.164399) (xy 69.031799 -117.151299)
			(xy 69.087934 -117.144698) (xy 69.116194 -117.144292) (xy 69.847714 -117.144292) (xy 69.87933 -117.144718)
			(xy 69.942022 -117.152973) (xy 70.0031 -117.16934) (xy 70.061519 -117.19354) (xy 70.11628 -117.225157)
			(xy 70.166445 -117.263652) (xy 70.211157 -117.308365) (xy 70.24965 -117.358532) (xy 70.281266 -117.413293)
			(xy 70.305464 -117.471713) (xy 70.32183 -117.532792) (xy 70.330083 -117.595484) (xy 70.330083 -117.658716)
			(xy 70.32183 -117.721408) (xy 70.305464 -117.782487) (xy 70.281266 -117.840907) (xy 70.24965 -117.895668)
			(xy 70.211157 -117.945835) (xy 70.166445 -117.990548) (xy 70.11628 -118.029043) (xy 70.061519 -118.06066)
			(xy 70.0031 -118.08486) (xy 69.942022 -118.101227) (xy 69.87933 -118.109482) (xy 69.847714 -118.11)
			(xy 69.116194 -118.11) (xy 69.087931 -118.109621) (xy 69.031789 -118.103046) (xy 68.9768 -118.089953)
			(xy 68.92372 -118.070519) (xy 68.873275 -118.045014) (xy 68.849494 -118.029736) (xy 68.81749 -118.008654)
			(xy 68.67017 -118.008654) (xy 68.65349 -118.009195) (xy 68.621271 -118.017843) (xy 68.592391 -118.034539)
			(xy 68.580254 -118.045992) (xy 68.515484 -118.111016) (xy 67.493388 -118.111016) (xy 67.461758 -118.110482)
			(xy 67.39904 -118.102224) (xy 67.337937 -118.08585) (xy 67.279493 -118.06164) (xy 67.22471 -118.03001)
			(xy 67.174523 -117.991499) (xy 67.129793 -117.946768) (xy 67.091283 -117.89658) (xy 67.059654 -117.841796)
			(xy 67.035446 -117.783352) (xy 67.019074 -117.722248) (xy 67.010817 -117.65953) (xy 36.131998 -117.65953)
			(xy 36.140713 -117.666111) (xy 36.204933 -117.724655) (xy 36.263477 -117.788875) (xy 36.315846 -117.858222)
			(xy 36.361593 -117.932106) (xy 36.400327 -118.009895) (xy 36.431719 -118.090927) (xy 36.4555 -118.174509)
			(xy 36.471468 -118.259929) (xy 36.479486 -118.346458) (xy 36.479988 -118.389908) (xy 36.479486 -118.433358)
			(xy 36.471468 -118.519887) (xy 36.4555 -118.605307) (xy 36.431719 -118.688889) (xy 36.400327 -118.769921)
			(xy 36.361593 -118.84771) (xy 36.315846 -118.921594) (xy 36.263477 -118.990941) (xy 36.204933 -119.055161)
			(xy 36.145862 -119.109011) (xy 39.351257 -119.109011) (xy 39.355144 -119.054651) (xy 39.366727 -119.001398)
			(xy 39.385772 -118.950335) (xy 39.411891 -118.902503) (xy 39.444551 -118.858875) (xy 39.483089 -118.82034)
			(xy 39.526718 -118.787681) (xy 39.574551 -118.761565) (xy 39.625615 -118.742522) (xy 39.678869 -118.730941)
			(xy 39.733229 -118.727057) (xy 39.787588 -118.730949) (xy 39.84084 -118.742539) (xy 39.891901 -118.761589)
			(xy 39.93973 -118.787712) (xy 39.96182 -118.803674) (xy 39.980832 -118.81727) (xy 40.022715 -118.838002)
			(xy 40.067683 -118.850728) (xy 40.11422 -118.855018) (xy 40.160757 -118.850728) (xy 40.205725 -118.838002)
			(xy 40.247608 -118.81727) (xy 40.26662 -118.803674) (xy 40.288725 -118.78774) (xy 40.336548 -118.761625)
			(xy 40.387601 -118.742582) (xy 40.440844 -118.730998) (xy 40.495194 -118.72711) (xy 40.549544 -118.730996)
			(xy 40.602788 -118.742578) (xy 40.653842 -118.76162) (xy 40.701666 -118.787734) (xy 40.745286 -118.820388)
			(xy 40.783815 -118.858918) (xy 40.816469 -118.902539) (xy 40.841671 -118.948695) (xy 57.923295 -118.948695)
			(xy 57.927183 -118.894342) (xy 57.938767 -118.841096) (xy 57.957811 -118.790041) (xy 57.983928 -118.742215)
			(xy 58.016585 -118.698594) (xy 58.055119 -118.660064) (xy 58.098743 -118.62741) (xy 58.146571 -118.601298)
			(xy 58.197628 -118.582258) (xy 58.250875 -118.570678) (xy 58.305228 -118.566795) (xy 58.359581 -118.570686)
			(xy 58.412826 -118.582274) (xy 58.463881 -118.601321) (xy 58.511705 -118.627441) (xy 58.533792 -118.6434)
			(xy 58.552804 -118.656996) (xy 58.594687 -118.677728) (xy 58.639655 -118.690454) (xy 58.686192 -118.694744)
			(xy 58.732729 -118.690454) (xy 58.777697 -118.677728) (xy 58.81958 -118.656996) (xy 58.838592 -118.6434)
			(xy 58.860673 -118.627429) (xy 58.908499 -118.601306) (xy 58.959557 -118.582255) (xy 59.012806 -118.570665)
			(xy 59.067163 -118.566772) (xy 59.12152 -118.570655) (xy 59.174771 -118.582234) (xy 59.225833 -118.601274)
			(xy 59.273664 -118.627388) (xy 59.317292 -118.660044) (xy 59.355829 -118.698576) (xy 59.388489 -118.7422)
			(xy 59.414608 -118.790029) (xy 59.433654 -118.841088) (xy 59.445239 -118.894338) (xy 59.449128 -118.948695)
			(xy 60.16427 -118.948695) (xy 60.168158 -118.894337) (xy 60.179744 -118.841085) (xy 60.198791 -118.790024)
			(xy 60.224912 -118.742194) (xy 60.257573 -118.698569) (xy 60.296112 -118.660036) (xy 60.339742 -118.627381)
			(xy 60.387576 -118.601267) (xy 60.43864 -118.582228) (xy 60.491893 -118.57065) (xy 60.546252 -118.56677)
			(xy 60.60061 -118.570665) (xy 60.653861 -118.582258) (xy 60.704919 -118.601311) (xy 60.752746 -118.627437)
			(xy 60.774834 -118.6434) (xy 60.793846 -118.656996) (xy 60.835729 -118.677728) (xy 60.880697 -118.690454)
			(xy 60.927234 -118.694744) (xy 60.973771 -118.690454) (xy 61.018739 -118.677728) (xy 61.060622 -118.656996)
			(xy 61.079634 -118.6434) (xy 61.101714 -118.627432) (xy 61.149538 -118.601316) (xy 61.200591 -118.582271)
			(xy 61.253835 -118.570687) (xy 61.308186 -118.566797) (xy 61.362538 -118.570683) (xy 61.415783 -118.582264)
			(xy 61.466838 -118.601305) (xy 61.514663 -118.627418) (xy 61.558286 -118.660071) (xy 61.596817 -118.6986)
			(xy 61.629473 -118.742221) (xy 61.655588 -118.790045) (xy 61.674631 -118.841099) (xy 61.686215 -118.894344)
			(xy 61.690103 -118.948695) (xy 62.068279 -118.948695) (xy 62.072168 -118.894339) (xy 62.083753 -118.841089)
			(xy 62.102799 -118.79003) (xy 62.128918 -118.742202) (xy 62.161578 -118.698578) (xy 62.200114 -118.660047)
			(xy 62.243743 -118.627392) (xy 62.291574 -118.601279) (xy 62.342635 -118.582239) (xy 62.395886 -118.570661)
			(xy 62.450243 -118.566779) (xy 62.504599 -118.570673) (xy 62.557848 -118.582264) (xy 62.608904 -118.601315)
			(xy 62.65673 -118.627439) (xy 62.678818 -118.6434) (xy 62.69783 -118.656996) (xy 62.739713 -118.677728)
			(xy 62.784681 -118.690454) (xy 62.831218 -118.694744) (xy 62.877755 -118.690454) (xy 62.922723 -118.677728)
			(xy 62.964606 -118.656996) (xy 62.983618 -118.6434) (xy 63.005698 -118.627431) (xy 63.053523 -118.601312)
			(xy 63.104578 -118.582265) (xy 63.157824 -118.570679) (xy 63.212177 -118.566788) (xy 63.266531 -118.570672)
			(xy 63.319779 -118.582253) (xy 63.370836 -118.601293) (xy 63.418664 -118.627406) (xy 63.462288 -118.660061)
			(xy 63.500821 -118.698591) (xy 63.533479 -118.742213) (xy 63.559595 -118.790039) (xy 63.57864 -118.841095)
			(xy 63.590224 -118.894342) (xy 63.594112 -118.948695) (xy 63.590225 -119.003049) (xy 63.578642 -119.056296)
			(xy 63.559599 -119.107352) (xy 63.533484 -119.155179) (xy 63.500828 -119.198802) (xy 63.462296 -119.237333)
			(xy 63.418672 -119.269988) (xy 63.370845 -119.296103) (xy 63.319788 -119.315145) (xy 63.26654 -119.326726)
			(xy 63.212187 -119.330612) (xy 63.157834 -119.326723) (xy 63.104587 -119.315137) (xy 63.053532 -119.296092)
			(xy 63.005706 -119.269974) (xy 62.983618 -119.254016) (xy 62.964606 -119.24042) (xy 62.922723 -119.219688)
			(xy 62.877755 -119.206962) (xy 62.831218 -119.202672) (xy 62.784681 -119.206962) (xy 62.739713 -119.219688)
			(xy 62.69783 -119.24042) (xy 62.678818 -119.254016) (xy 62.656722 -119.269967) (xy 62.608896 -119.296089)
			(xy 62.557838 -119.315139) (xy 62.50459 -119.326728) (xy 62.450233 -119.330621) (xy 62.395877 -119.326738)
			(xy 62.342626 -119.315158) (xy 62.291565 -119.296117) (xy 62.243734 -119.270003) (xy 62.200107 -119.237347)
			(xy 62.161572 -119.198815) (xy 62.128913 -119.15519) (xy 62.102795 -119.107361) (xy 62.08375 -119.056302)
			(xy 62.072166 -119.003052) (xy 62.068279 -118.948695) (xy 61.690103 -118.948695) (xy 61.686216 -119.003046)
			(xy 61.674634 -119.056291) (xy 61.655592 -119.107346) (xy 61.629478 -119.155171) (xy 61.596823 -119.198792)
			(xy 61.558293 -119.237323) (xy 61.514671 -119.269977) (xy 61.466847 -119.296091) (xy 61.415792 -119.315133)
			(xy 61.362547 -119.326716) (xy 61.308196 -119.330603) (xy 61.253845 -119.326715) (xy 61.2006 -119.315131)
			(xy 61.149546 -119.296088) (xy 61.101722 -119.269973) (xy 61.079634 -119.254016) (xy 61.060622 -119.24042)
			(xy 61.018739 -119.219688) (xy 60.973771 -119.206962) (xy 60.927234 -119.202672) (xy 60.880697 -119.206962)
			(xy 60.835729 -119.219688) (xy 60.793846 -119.24042) (xy 60.774834 -119.254016) (xy 60.752738 -119.269968)
			(xy 60.70491 -119.296093) (xy 60.653851 -119.315145) (xy 60.600601 -119.326736) (xy 60.546243 -119.33063)
			(xy 60.491884 -119.326748) (xy 60.43863 -119.315169) (xy 60.387567 -119.296129) (xy 60.339734 -119.270014)
			(xy 60.296105 -119.237358) (xy 60.257567 -119.198824) (xy 60.224906 -119.155198) (xy 60.198787 -119.107367)
			(xy 60.179741 -119.056306) (xy 60.168157 -119.003054) (xy 60.16427 -118.948695) (xy 59.449128 -118.948695)
			(xy 59.445241 -119.003052) (xy 59.433657 -119.056303) (xy 59.414612 -119.107362) (xy 59.388494 -119.155192)
			(xy 59.355835 -119.198817) (xy 59.3173 -119.23735) (xy 59.273672 -119.270007) (xy 59.225841 -119.296122)
			(xy 59.17478 -119.315163) (xy 59.121529 -119.326744) (xy 59.067172 -119.330628) (xy 59.012816 -119.326736)
			(xy 58.959566 -119.315147) (xy 58.908508 -119.296098) (xy 58.860681 -119.269977) (xy 58.838592 -119.254016)
			(xy 58.81958 -119.24042) (xy 58.777697 -119.219688) (xy 58.732729 -119.206962) (xy 58.686192 -119.202672)
			(xy 58.639655 -119.206962) (xy 58.594687 -119.219688) (xy 58.552804 -119.24042) (xy 58.533792 -119.254016)
			(xy 58.511697 -119.269964) (xy 58.463872 -119.296083) (xy 58.412817 -119.315129) (xy 58.359571 -119.326715)
			(xy 58.305219 -119.330605) (xy 58.250866 -119.32672) (xy 58.197619 -119.31514) (xy 58.146562 -119.296098)
			(xy 58.098735 -119.269985) (xy 58.055111 -119.23733) (xy 58.016579 -119.198799) (xy 57.983923 -119.155177)
			(xy 57.957807 -119.107351) (xy 57.938764 -119.056295) (xy 57.927182 -119.003048) (xy 57.923295 -118.948695)
			(xy 40.841671 -118.948695) (xy 40.842582 -118.950363) (xy 40.861623 -119.001417) (xy 40.873204 -119.054661)
			(xy 40.87709 -119.109011) (xy 40.873201 -119.163361) (xy 40.861617 -119.216604) (xy 40.842573 -119.267657)
			(xy 40.816457 -119.31548) (xy 40.783801 -119.359099) (xy 40.74527 -119.397626) (xy 40.701647 -119.430278)
			(xy 40.653822 -119.456389) (xy 40.602767 -119.475428) (xy 40.549523 -119.487007) (xy 40.495173 -119.49089)
			(xy 40.440823 -119.486999) (xy 40.38758 -119.475412) (xy 40.336528 -119.456366) (xy 40.288706 -119.430248)
			(xy 40.26662 -119.41429) (xy 40.247608 -119.400694) (xy 40.205725 -119.379962) (xy 40.160757 -119.367236)
			(xy 40.11422 -119.362946) (xy 40.067683 -119.367236) (xy 40.022715 -119.379962) (xy 39.980832 -119.400694)
			(xy 39.96182 -119.41429) (xy 39.939748 -119.430276) (xy 39.89192 -119.456402) (xy 39.840861 -119.475455)
			(xy 39.787609 -119.487048) (xy 39.73325 -119.490943) (xy 39.67889 -119.487062) (xy 39.625636 -119.475484)
			(xy 39.574571 -119.456444) (xy 39.526736 -119.43033) (xy 39.483105 -119.397674) (xy 39.444566 -119.359141)
			(xy 39.411903 -119.315515) (xy 39.385781 -119.267684) (xy 39.366734 -119.216623) (xy 39.355147 -119.16337)
			(xy 39.351257 -119.109011) (xy 36.145862 -119.109011) (xy 36.140713 -119.113705) (xy 36.071366 -119.166074)
			(xy 35.997482 -119.211821) (xy 35.919693 -119.250555) (xy 35.838661 -119.281947) (xy 35.755079 -119.305728)
			(xy 35.669659 -119.321696) (xy 35.58313 -119.329714) (xy 35.49623 -119.329714) (xy 35.409701 -119.321696)
			(xy 35.324281 -119.305728) (xy 35.240699 -119.281947) (xy 35.159667 -119.250555) (xy 35.081878 -119.211821)
			(xy 35.007994 -119.166074) (xy 34.938647 -119.113705) (xy 34.874427 -119.055161) (xy 34.815883 -118.990941)
			(xy 34.763514 -118.921594) (xy 34.717767 -118.84771) (xy 34.679033 -118.769921) (xy 34.647641 -118.688889)
			(xy 34.62386 -118.605307) (xy 34.607892 -118.519887) (xy 34.599874 -118.433358) (xy 31.399486 -118.433358)
			(xy 31.391468 -118.519887) (xy 31.3755 -118.605307) (xy 31.351719 -118.688889) (xy 31.320327 -118.769921)
			(xy 31.281593 -118.84771) (xy 31.235846 -118.921594) (xy 31.183477 -118.990941) (xy 31.124933 -119.055161)
			(xy 31.060713 -119.113705) (xy 30.991366 -119.166074) (xy 30.917482 -119.211821) (xy 30.839693 -119.250555)
			(xy 30.758661 -119.281947) (xy 30.675079 -119.305728) (xy 30.589659 -119.321696) (xy 30.50313 -119.329714)
			(xy 30.41623 -119.329714) (xy 30.329701 -119.321696) (xy 30.244281 -119.305728) (xy 30.160699 -119.281947)
			(xy 30.079667 -119.250555) (xy 30.001878 -119.211821) (xy 29.927994 -119.166074) (xy 29.858647 -119.113705)
			(xy 29.794427 -119.055161) (xy 29.735883 -118.990941) (xy 29.683514 -118.921594) (xy 29.637767 -118.84771)
			(xy 29.599033 -118.769921) (xy 29.567641 -118.688889) (xy 29.54386 -118.605307) (xy 29.527892 -118.519887)
			(xy 29.519874 -118.433358) (xy 27.89936 -118.433358) (xy 27.89936 -120.973358) (xy 29.519874 -120.973358)
			(xy 29.519874 -120.886458) (xy 29.527892 -120.799929) (xy 29.54386 -120.714509) (xy 29.567641 -120.630927)
			(xy 29.599033 -120.549895) (xy 29.637767 -120.472106) (xy 29.683514 -120.398222) (xy 29.735883 -120.328875)
			(xy 29.794427 -120.264655) (xy 29.858647 -120.206111) (xy 29.927994 -120.153742) (xy 30.001878 -120.107995)
			(xy 30.079667 -120.069261) (xy 30.160699 -120.037869) (xy 30.244281 -120.014088) (xy 30.329701 -119.99812)
			(xy 30.41623 -119.990102) (xy 30.50313 -119.990102) (xy 30.589659 -119.99812) (xy 30.675079 -120.014088)
			(xy 30.758661 -120.037869) (xy 30.839693 -120.069261) (xy 30.917482 -120.107995) (xy 30.991366 -120.153742)
			(xy 31.060713 -120.206111) (xy 31.124933 -120.264655) (xy 31.183477 -120.328875) (xy 31.235846 -120.398222)
			(xy 31.281593 -120.472106) (xy 31.320327 -120.549895) (xy 31.351719 -120.630927) (xy 31.3755 -120.714509)
			(xy 31.391468 -120.799929) (xy 31.399486 -120.886458) (xy 31.399988 -120.929908) (xy 31.399486 -120.973358)
			(xy 34.599874 -120.973358) (xy 34.599874 -120.886458) (xy 34.607892 -120.799929) (xy 34.62386 -120.714509)
			(xy 34.647641 -120.630927) (xy 34.679033 -120.549895) (xy 34.717767 -120.472106) (xy 34.763514 -120.398222)
			(xy 34.815883 -120.328875) (xy 34.874427 -120.264655) (xy 34.938647 -120.206111) (xy 35.007994 -120.153742)
			(xy 35.081878 -120.107995) (xy 35.159667 -120.069261) (xy 35.240699 -120.037869) (xy 35.324281 -120.014088)
			(xy 35.409701 -119.99812) (xy 35.49623 -119.990102) (xy 35.58313 -119.990102) (xy 35.669659 -119.99812)
			(xy 35.755079 -120.014088) (xy 35.838661 -120.037869) (xy 35.919693 -120.069261) (xy 35.997482 -120.107995)
			(xy 36.071366 -120.153742) (xy 36.140713 -120.206111) (xy 36.204933 -120.264655) (xy 36.263477 -120.328875)
			(xy 36.276658 -120.346329) (xy 67.014629 -120.346329) (xy 67.014629 -120.283071) (xy 67.022886 -120.220353)
			(xy 67.039258 -120.15925) (xy 67.063466 -120.100807) (xy 67.095095 -120.046023) (xy 67.133605 -119.995837)
			(xy 67.178335 -119.951106) (xy 67.228522 -119.912597) (xy 67.283305 -119.880967) (xy 67.341748 -119.856759)
			(xy 67.402851 -119.840386) (xy 67.465569 -119.832129) (xy 67.497198 -119.831612) (xy 68.273422 -119.831612)
			(xy 68.304113 -119.830548) (xy 68.365342 -119.83527) (xy 68.42548 -119.847708) (xy 68.483558 -119.867663)
			(xy 68.538642 -119.894812) (xy 68.564506 -119.911368) (xy 68.596256 -119.932704) (xy 68.65366 -119.932704)
			(xy 68.65366 -119.987568) (xy 68.673477 -120.009928) (xy 68.708112 -120.058612) (xy 68.736478 -120.111196)
			(xy 68.758141 -120.166877) (xy 68.772771 -120.224805) (xy 68.780144 -120.284096) (xy 68.780148 -120.343843)
			(xy 68.772782 -120.403134) (xy 68.75816 -120.461064) (xy 68.736504 -120.516748) (xy 68.708145 -120.569336)
			(xy 68.673516 -120.618024) (xy 68.65366 -120.640348) (xy 68.65366 -120.695212) (xy 68.651882 -120.695212)
			(xy 68.635197 -120.695686) (xy 68.602974 -120.70436) (xy 68.574097 -120.721084) (xy 68.561966 -120.73255)
			(xy 68.496942 -120.797828) (xy 67.497198 -120.797828) (xy 67.465569 -120.797271) (xy 67.402851 -120.789014)
			(xy 67.341748 -120.772641) (xy 67.283305 -120.748433) (xy 67.228522 -120.716803) (xy 67.178335 -120.678294)
			(xy 67.133605 -120.633563) (xy 67.095095 -120.583377) (xy 67.063466 -120.528593) (xy 67.039258 -120.47015)
			(xy 67.022886 -120.409047) (xy 67.014629 -120.346329) (xy 36.276658 -120.346329) (xy 36.315846 -120.398222)
			(xy 36.361593 -120.472106) (xy 36.400327 -120.549895) (xy 36.431719 -120.630927) (xy 36.4555 -120.714509)
			(xy 36.471468 -120.799929) (xy 36.479486 -120.886458) (xy 36.479988 -120.929908) (xy 36.479486 -120.973358)
			(xy 36.476101 -121.009889) (xy 39.351286 -121.009889) (xy 39.355175 -120.955534) (xy 39.366761 -120.902285)
			(xy 39.385808 -120.851228) (xy 39.411927 -120.803401) (xy 39.444587 -120.759778) (xy 39.483124 -120.721247)
			(xy 39.526752 -120.688594) (xy 39.574583 -120.662482) (xy 39.625644 -120.643444) (xy 39.678894 -120.631867)
			(xy 39.73325 -120.627986) (xy 39.787605 -120.631881) (xy 39.840853 -120.643472) (xy 39.891908 -120.662524)
			(xy 39.939733 -120.688648) (xy 39.96182 -120.70461) (xy 39.980832 -120.718206) (xy 40.022715 -120.738938)
			(xy 40.067683 -120.751664) (xy 40.11422 -120.755954) (xy 40.160757 -120.751664) (xy 40.205725 -120.738938)
			(xy 40.247608 -120.718206) (xy 40.26662 -120.70461) (xy 40.288691 -120.688627) (xy 40.336516 -120.662508)
			(xy 40.387572 -120.64346) (xy 40.440819 -120.631873) (xy 40.495173 -120.627981) (xy 40.549527 -120.631865)
			(xy 40.602776 -120.643445) (xy 40.653834 -120.662485) (xy 40.701663 -120.688598) (xy 40.745289 -120.721252)
			(xy 40.783823 -120.759782) (xy 40.816482 -120.803405) (xy 40.841694 -120.849574) (xy 57.923323 -120.849574)
			(xy 57.927215 -120.795225) (xy 57.938801 -120.741984) (xy 57.957847 -120.690933) (xy 57.983964 -120.643113)
			(xy 58.016621 -120.599496) (xy 58.055154 -120.560971) (xy 58.098777 -120.528323) (xy 58.146602 -120.502215)
			(xy 58.197657 -120.483179) (xy 58.250901 -120.471604) (xy 58.30525 -120.467723) (xy 58.359598 -120.471618)
			(xy 58.412839 -120.483207) (xy 58.463888 -120.502256) (xy 58.511707 -120.528377) (xy 58.533792 -120.544336)
			(xy 58.552804 -120.557932) (xy 58.594687 -120.578664) (xy 58.639655 -120.59139) (xy 58.686192 -120.59568)
			(xy 58.732729 -120.59139) (xy 58.777697 -120.578664) (xy 58.81958 -120.557932) (xy 58.838592 -120.544336)
			(xy 58.860639 -120.528316) (xy 58.908468 -120.502188) (xy 58.959528 -120.483134) (xy 59.012781 -120.47154)
			(xy 59.067141 -120.467643) (xy 59.121503 -120.471523) (xy 59.174759 -120.4831) (xy 59.225825 -120.502139)
			(xy 59.273662 -120.528252) (xy 59.317295 -120.560908) (xy 59.355836 -120.599441) (xy 59.388502 -120.643067)
			(xy 59.414625 -120.690897) (xy 59.433676 -120.741959) (xy 59.445265 -120.795213) (xy 59.449157 -120.849574)
			(xy 60.164298 -120.849574) (xy 60.16819 -120.795219) (xy 60.179778 -120.741972) (xy 60.198826 -120.690917)
			(xy 60.224947 -120.643092) (xy 60.257609 -120.599471) (xy 60.296147 -120.560944) (xy 60.339776 -120.528293)
			(xy 60.387608 -120.502185) (xy 60.438668 -120.48315) (xy 60.491918 -120.471576) (xy 60.546274 -120.467698)
			(xy 60.600628 -120.471597) (xy 60.653873 -120.483191) (xy 60.704927 -120.502246) (xy 60.752748 -120.528373)
			(xy 60.774834 -120.544336) (xy 60.793846 -120.557932) (xy 60.835729 -120.578664) (xy 60.880697 -120.59139)
			(xy 60.927234 -120.59568) (xy 60.973771 -120.59139) (xy 61.018739 -120.578664) (xy 61.060622 -120.557932)
			(xy 61.079634 -120.544336) (xy 61.10168 -120.52832) (xy 61.149506 -120.502199) (xy 61.200562 -120.48315)
			(xy 61.25381 -120.471561) (xy 61.308165 -120.467669) (xy 61.362521 -120.471551) (xy 61.41577 -120.48313)
			(xy 61.46683 -120.502169) (xy 61.514661 -120.528282) (xy 61.558288 -120.560935) (xy 61.596825 -120.599465)
			(xy 61.629485 -120.643087) (xy 61.655605 -120.690914) (xy 61.674653 -120.741971) (xy 61.68624 -120.795219)
			(xy 61.690131 -120.849574) (xy 62.068308 -120.849574) (xy 62.072199 -120.795222) (xy 62.083787 -120.741977)
			(xy 62.102834 -120.690923) (xy 62.128954 -120.6431) (xy 62.161614 -120.599481) (xy 62.20015 -120.560954)
			(xy 62.243776 -120.528304) (xy 62.291606 -120.502196) (xy 62.342664 -120.483161) (xy 62.395912 -120.471586)
			(xy 62.450265 -120.467708) (xy 62.504616 -120.471605) (xy 62.55786 -120.483197) (xy 62.608912 -120.50225)
			(xy 62.656733 -120.528374) (xy 62.678818 -120.544336) (xy 62.69783 -120.557932) (xy 62.739713 -120.578664)
			(xy 62.784681 -120.59139) (xy 62.831218 -120.59568) (xy 62.877755 -120.59139) (xy 62.922723 -120.578664)
			(xy 62.964606 -120.557932) (xy 62.983618 -120.544336) (xy 63.005664 -120.528318) (xy 63.053491 -120.502195)
			(xy 63.104549 -120.483144) (xy 63.157799 -120.471553) (xy 63.212156 -120.467659) (xy 63.266514 -120.471541)
			(xy 63.319766 -120.483119) (xy 63.370828 -120.502158) (xy 63.418661 -120.52827) (xy 63.462291 -120.560925)
			(xy 63.500829 -120.599456) (xy 63.533491 -120.643079) (xy 63.559613 -120.690908) (xy 63.578661 -120.741966)
			(xy 63.590249 -120.795216) (xy 63.594141 -120.849574) (xy 63.590257 -120.903931) (xy 63.578676 -120.957183)
			(xy 63.559635 -121.008244) (xy 63.53352 -121.056076) (xy 63.500864 -121.099704) (xy 63.462331 -121.138241)
			(xy 63.418706 -121.170901) (xy 63.370876 -121.19702) (xy 63.363128 -121.19991) (xy 69.997584 -121.19991)
			(xy 70.001572 -120.94729) (xy 70.013533 -120.694922) (xy 70.033455 -120.443058) (xy 70.061319 -120.191948)
			(xy 70.097095 -119.941842) (xy 70.140749 -119.692991) (xy 70.192238 -119.445642) (xy 70.251509 -119.200041)
			(xy 70.318504 -118.956434) (xy 70.393155 -118.715064) (xy 70.47539 -118.47617) (xy 70.565124 -118.239992)
			(xy 70.66227 -118.006764) (xy 70.76673 -117.776718) (xy 70.878401 -117.550086) (xy 70.99717 -117.327091)
			(xy 71.122919 -117.107957) (xy 71.255524 -116.892902) (xy 71.394851 -116.68214) (xy 71.540763 -116.475882)
			(xy 71.693113 -116.274333) (xy 71.851749 -116.077693) (xy 72.016514 -115.88616) (xy 72.187244 -115.699923)
			(xy 72.363768 -115.519169) (xy 72.54591 -115.344078) (xy 72.733488 -115.174824) (xy 72.926316 -115.011575)
			(xy 73.124201 -114.854496) (xy 73.326947 -114.703741) (xy 73.534351 -114.559463) (xy 73.746206 -114.421803)
			(xy 73.962301 -114.2909) (xy 74.182421 -114.166884) (xy 74.406346 -114.049879) (xy 74.633853 -113.940001)
			(xy 74.864715 -113.83736) (xy 75.098703 -113.742058) (xy 75.335582 -113.654191) (xy 75.575118 -113.573844)
			(xy 75.81707 -113.5011) (xy 76.061198 -113.43603) (xy 76.307259 -113.3787) (xy 76.555007 -113.329166)
			(xy 76.804195 -113.287477) (xy 77.054575 -113.253676) (xy 77.305897 -113.227795) (xy 77.557911 -113.209862)
			(xy 77.810365 -113.199893) (xy 78.063009 -113.197899) (xy 78.315589 -113.203881) (xy 78.567855 -113.217834)
			(xy 78.819554 -113.239744) (xy 79.070437 -113.269588) (xy 79.320252 -113.307338) (xy 79.568751 -113.352955)
			(xy 79.815686 -113.406394) (xy 80.060811 -113.467602) (xy 80.303881 -113.536517) (xy 80.544655 -113.613072)
			(xy 80.782892 -113.697189) (xy 81.018355 -113.788786) (xy 81.250809 -113.88777) (xy 81.480023 -113.994042)
			(xy 81.705767 -114.107498) (xy 81.927817 -114.228023) (xy 82.145951 -114.355499) (xy 82.359953 -114.489797)
			(xy 82.569609 -114.630783) (xy 82.774709 -114.778318) (xy 82.975049 -114.932254) (xy 83.17043 -115.092438)
			(xy 83.360657 -115.25871) (xy 83.54554 -115.430905) (xy 83.724896 -115.608849) (xy 83.898544 -115.792368)
			(xy 84.066312 -115.981276) (xy 84.228033 -116.175387) (xy 84.383546 -116.374506) (xy 84.532695 -116.578435)
			(xy 84.675332 -116.786971) (xy 84.811315 -116.999906) (xy 84.940508 -117.217028) (xy 85.062783 -117.43812)
			(xy 85.178017 -117.662961) (xy 85.286096 -117.891329) (xy 85.386911 -118.122994) (xy 85.480363 -118.357727)
			(xy 85.566358 -118.595292) (xy 85.644811 -118.835454) (xy 85.715643 -119.077973) (xy 85.778784 -119.322608)
			(xy 85.834171 -119.569113) (xy 85.881748 -119.817244) (xy 85.921468 -120.066754) (xy 85.953292 -120.317393)
			(xy 85.977188 -120.568911) (xy 85.993132 -120.821059) (xy 86.001107 -121.073584) (xy 86.001606 -121.19991)
			(xy 86.001107 -121.326236) (xy 85.993132 -121.578761) (xy 85.977188 -121.830909) (xy 85.953292 -122.082427)
			(xy 85.921468 -122.333066) (xy 85.881748 -122.582576) (xy 85.834171 -122.830707) (xy 85.778784 -123.077212)
			(xy 85.715643 -123.321847) (xy 85.644811 -123.564366) (xy 85.566358 -123.804528) (xy 85.480363 -124.042093)
			(xy 85.386911 -124.276826) (xy 85.286096 -124.508491) (xy 85.178017 -124.736859) (xy 85.062783 -124.9617)
			(xy 84.940508 -125.182792) (xy 84.811315 -125.399914) (xy 84.675332 -125.612849) (xy 84.532695 -125.821385)
			(xy 84.383546 -126.025314) (xy 84.228033 -126.224433) (xy 84.066312 -126.418544) (xy 83.898544 -126.607452)
			(xy 83.724896 -126.790971) (xy 83.54554 -126.968915) (xy 83.360657 -127.14111) (xy 83.17043 -127.307382)
			(xy 82.975049 -127.467566) (xy 82.774709 -127.621502) (xy 82.569609 -127.769037) (xy 82.359953 -127.910023)
			(xy 82.145951 -128.044321) (xy 81.927817 -128.171797) (xy 81.705767 -128.292322) (xy 81.480023 -128.405778)
			(xy 81.250809 -128.51205) (xy 81.018355 -128.611034) (xy 80.782892 -128.702631) (xy 80.544655 -128.786748)
			(xy 80.303881 -128.863303) (xy 80.060811 -128.932218) (xy 79.815686 -128.993426) (xy 79.568751 -129.046865)
			(xy 79.320252 -129.092482) (xy 79.070437 -129.130232) (xy 78.819554 -129.160076) (xy 78.567855 -129.181986)
			(xy 78.315589 -129.195939) (xy 78.063009 -129.201921) (xy 77.810365 -129.199927) (xy 77.557911 -129.189958)
			(xy 77.305897 -129.172025) (xy 77.054575 -129.146144) (xy 76.804195 -129.112343) (xy 76.555007 -129.070654)
			(xy 76.307259 -129.02112) (xy 76.061198 -128.96379) (xy 75.81707 -128.89872) (xy 75.575118 -128.825976)
			(xy 75.335582 -128.745629) (xy 75.098703 -128.657762) (xy 74.864715 -128.56246) (xy 74.633853 -128.459819)
			(xy 74.406346 -128.349941) (xy 74.182421 -128.232936) (xy 73.962301 -128.10892) (xy 73.746206 -127.978017)
			(xy 73.534351 -127.840357) (xy 73.326947 -127.696079) (xy 73.124201 -127.545324) (xy 72.926316 -127.388245)
			(xy 72.733488 -127.224996) (xy 72.54591 -127.055742) (xy 72.363768 -126.880651) (xy 72.187244 -126.699897)
			(xy 72.016514 -126.51366) (xy 71.851749 -126.322127) (xy 71.693113 -126.125487) (xy 71.540763 -125.923938)
			(xy 71.394851 -125.71768) (xy 71.255524 -125.506918) (xy 71.122919 -125.291863) (xy 70.99717 -125.072729)
			(xy 70.878401 -124.849734) (xy 70.76673 -124.623102) (xy 70.66227 -124.393056) (xy 70.565124 -124.159828)
			(xy 70.47539 -123.92365) (xy 70.393155 -123.684756) (xy 70.318504 -123.443386) (xy 70.251509 -123.199779)
			(xy 70.192238 -122.954178) (xy 70.140749 -122.706829) (xy 70.097095 -122.457978) (xy 70.061319 -122.207872)
			(xy 70.033455 -121.956762) (xy 70.013533 -121.704898) (xy 70.001572 -121.45253) (xy 69.997584 -121.19991)
			(xy 63.363128 -121.19991) (xy 63.319817 -121.216066) (xy 63.266566 -121.227652) (xy 63.212209 -121.231541)
			(xy 63.157851 -121.227654) (xy 63.1046 -121.216071) (xy 63.053539 -121.197027) (xy 63.005709 -121.17091)
			(xy 62.983618 -121.154952) (xy 62.964606 -121.141356) (xy 62.922723 -121.120624) (xy 62.877755 -121.107898)
			(xy 62.831218 -121.103608) (xy 62.784681 -121.107898) (xy 62.739713 -121.120624) (xy 62.69783 -121.141356)
			(xy 62.678818 -121.154952) (xy 62.656688 -121.170854) (xy 62.608864 -121.196972) (xy 62.55781 -121.216017)
			(xy 62.504564 -121.227603) (xy 62.450212 -121.231492) (xy 62.395859 -121.227606) (xy 62.342613 -121.216024)
			(xy 62.291558 -121.196982) (xy 62.243732 -121.170867) (xy 62.20011 -121.138211) (xy 62.161579 -121.099679)
			(xy 62.128925 -121.056056) (xy 62.102812 -121.008229) (xy 62.083772 -120.957173) (xy 62.072192 -120.903926)
			(xy 62.068308 -120.849574) (xy 61.690131 -120.849574) (xy 61.686248 -120.903929) (xy 61.674667 -120.957179)
			(xy 61.655627 -121.008238) (xy 61.629514 -121.056068) (xy 61.596859 -121.099695) (xy 61.558328 -121.13823)
			(xy 61.514705 -121.17089) (xy 61.466878 -121.197009) (xy 61.415821 -121.216055) (xy 61.362573 -121.227641)
			(xy 61.308218 -121.231531) (xy 61.253862 -121.227646) (xy 61.200613 -121.216065) (xy 61.149554 -121.197023)
			(xy 61.101725 -121.170909) (xy 61.079634 -121.154952) (xy 61.060622 -121.141356) (xy 61.018739 -121.120624)
			(xy 60.973771 -121.107898) (xy 60.927234 -121.103608) (xy 60.880697 -121.107898) (xy 60.835729 -121.120624)
			(xy 60.793846 -121.141356) (xy 60.774834 -121.154952) (xy 60.752704 -121.170855) (xy 60.704879 -121.196976)
			(xy 60.653823 -121.216024) (xy 60.600575 -121.227611) (xy 60.546221 -121.231502) (xy 60.491866 -121.227617)
			(xy 60.438618 -121.216035) (xy 60.38756 -121.196993) (xy 60.339732 -121.170878) (xy 60.296107 -121.138222)
			(xy 60.257575 -121.099689) (xy 60.224919 -121.056064) (xy 60.198804 -121.008235) (xy 60.179763 -120.957177)
			(xy 60.168182 -120.903928) (xy 60.164298 -120.849574) (xy 59.449157 -120.849574) (xy 59.445272 -120.903935)
			(xy 59.43369 -120.95719) (xy 59.414647 -121.008255) (xy 59.38853 -121.056089) (xy 59.355871 -121.09972)
			(xy 59.317335 -121.138258) (xy 59.273706 -121.170919) (xy 59.225873 -121.197039) (xy 59.174809 -121.216085)
			(xy 59.121555 -121.227669) (xy 59.067194 -121.231557) (xy 59.012833 -121.227667) (xy 58.959579 -121.216081)
			(xy 58.908516 -121.197034) (xy 58.860684 -121.170913) (xy 58.838592 -121.154952) (xy 58.81958 -121.141356)
			(xy 58.777697 -121.120624) (xy 58.732729 -121.107898) (xy 58.686192 -121.103608) (xy 58.639655 -121.107898)
			(xy 58.594687 -121.120624) (xy 58.552804 -121.141356) (xy 58.533792 -121.154952) (xy 58.511663 -121.170852)
			(xy 58.46384 -121.196966) (xy 58.412788 -121.216007) (xy 58.359546 -121.22759) (xy 58.305197 -121.231477)
			(xy 58.250848 -121.227589) (xy 58.197606 -121.216006) (xy 58.146554 -121.196963) (xy 58.098732 -121.170849)
			(xy 58.055114 -121.138194) (xy 58.016587 -121.099664) (xy 57.983935 -121.056043) (xy 57.957825 -121.008219)
			(xy 57.938786 -120.957166) (xy 57.927207 -120.903923) (xy 57.923323 -120.849574) (xy 40.841694 -120.849574)
			(xy 40.842599 -120.851231) (xy 40.861645 -120.902288) (xy 40.87323 -120.955535) (xy 40.877119 -121.009889)
			(xy 40.873233 -121.064244) (xy 40.861651 -121.117492) (xy 40.842608 -121.168549) (xy 40.816493 -121.216377)
			(xy 40.783837 -121.260001) (xy 40.745305 -121.298534) (xy 40.701681 -121.331191) (xy 40.653854 -121.357306)
			(xy 40.602796 -121.376349) (xy 40.549548 -121.387932) (xy 40.495194 -121.391819) (xy 40.44084 -121.387931)
			(xy 40.387592 -121.376346) (xy 40.336536 -121.357301) (xy 40.288709 -121.331184) (xy 40.26662 -121.315226)
			(xy 40.247608 -121.30163) (xy 40.205725 -121.280898) (xy 40.160757 -121.268172) (xy 40.11422 -121.263882)
			(xy 40.067683 -121.268172) (xy 40.022715 -121.280898) (xy 39.980832 -121.30163) (xy 39.96182 -121.315226)
			(xy 39.939714 -121.331163) (xy 39.891889 -121.357285) (xy 39.840832 -121.376334) (xy 39.787584 -121.387922)
			(xy 39.733229 -121.391814) (xy 39.678873 -121.38793) (xy 39.625623 -121.37635) (xy 39.574563 -121.357309)
			(xy 39.526734 -121.331194) (xy 39.483108 -121.298538) (xy 39.444573 -121.260006) (xy 39.411915 -121.216381)
			(xy 39.385799 -121.168553) (xy 39.366755 -121.117494) (xy 39.355172 -121.064245) (xy 39.351286 -121.009889)
			(xy 36.476101 -121.009889) (xy 36.471468 -121.059887) (xy 36.4555 -121.145307) (xy 36.431719 -121.228889)
			(xy 36.400327 -121.309921) (xy 36.361593 -121.38771) (xy 36.315846 -121.461594) (xy 36.263477 -121.530941)
			(xy 36.204933 -121.595161) (xy 36.140713 -121.653705) (xy 36.071366 -121.706074) (xy 35.997482 -121.751821)
			(xy 35.919693 -121.790555) (xy 35.838661 -121.821947) (xy 35.755079 -121.845728) (xy 35.669659 -121.861696)
			(xy 35.58313 -121.869714) (xy 35.49623 -121.869714) (xy 35.409701 -121.861696) (xy 35.324281 -121.845728)
			(xy 35.240699 -121.821947) (xy 35.159667 -121.790555) (xy 35.081878 -121.751821) (xy 35.007994 -121.706074)
			(xy 34.938647 -121.653705) (xy 34.874427 -121.595161) (xy 34.815883 -121.530941) (xy 34.763514 -121.461594)
			(xy 34.717767 -121.38771) (xy 34.679033 -121.309921) (xy 34.647641 -121.228889) (xy 34.62386 -121.145307)
			(xy 34.607892 -121.059887) (xy 34.599874 -120.973358) (xy 31.399486 -120.973358) (xy 31.391468 -121.059887)
			(xy 31.3755 -121.145307) (xy 31.351719 -121.228889) (xy 31.320327 -121.309921) (xy 31.281593 -121.38771)
			(xy 31.235846 -121.461594) (xy 31.183477 -121.530941) (xy 31.124933 -121.595161) (xy 31.060713 -121.653705)
			(xy 30.991366 -121.706074) (xy 30.917482 -121.751821) (xy 30.839693 -121.790555) (xy 30.758661 -121.821947)
			(xy 30.675079 -121.845728) (xy 30.589659 -121.861696) (xy 30.50313 -121.869714) (xy 30.41623 -121.869714)
			(xy 30.329701 -121.861696) (xy 30.244281 -121.845728) (xy 30.160699 -121.821947) (xy 30.079667 -121.790555)
			(xy 30.001878 -121.751821) (xy 29.927994 -121.706074) (xy 29.858647 -121.653705) (xy 29.794427 -121.595161)
			(xy 29.735883 -121.530941) (xy 29.683514 -121.461594) (xy 29.637767 -121.38771) (xy 29.599033 -121.309921)
			(xy 29.567641 -121.228889) (xy 29.54386 -121.145307) (xy 29.527892 -121.059887) (xy 29.519874 -120.973358)
			(xy 27.89936 -120.973358) (xy 27.89936 -123.513358) (xy 29.519874 -123.513358) (xy 29.519874 -123.426458)
			(xy 29.527892 -123.339929) (xy 29.54386 -123.254509) (xy 29.567641 -123.170927) (xy 29.599033 -123.089895)
			(xy 29.637767 -123.012106) (xy 29.683514 -122.938222) (xy 29.735883 -122.868875) (xy 29.794427 -122.804655)
			(xy 29.858647 -122.746111) (xy 29.927994 -122.693742) (xy 30.001878 -122.647995) (xy 30.079667 -122.609261)
			(xy 30.160699 -122.577869) (xy 30.244281 -122.554088) (xy 30.329701 -122.53812) (xy 30.41623 -122.530102)
			(xy 30.50313 -122.530102) (xy 30.589659 -122.53812) (xy 30.675079 -122.554088) (xy 30.758661 -122.577869)
			(xy 30.839693 -122.609261) (xy 30.917482 -122.647995) (xy 30.991366 -122.693742) (xy 31.060713 -122.746111)
			(xy 31.124933 -122.804655) (xy 31.183477 -122.868875) (xy 31.235846 -122.938222) (xy 31.281593 -123.012106)
			(xy 31.320327 -123.089895) (xy 31.351719 -123.170927) (xy 31.3755 -123.254509) (xy 31.391468 -123.339929)
			(xy 31.399486 -123.426458) (xy 31.399988 -123.469908) (xy 31.399486 -123.513358) (xy 34.599874 -123.513358)
			(xy 34.599874 -123.426458) (xy 34.607892 -123.339929) (xy 34.62386 -123.254509) (xy 34.647641 -123.170927)
			(xy 34.679033 -123.089895) (xy 34.717767 -123.012106) (xy 34.763514 -122.938222) (xy 34.815883 -122.868875)
			(xy 34.874427 -122.804655) (xy 34.938647 -122.746111) (xy 35.007994 -122.693742) (xy 35.081878 -122.647995)
			(xy 35.159667 -122.609261) (xy 35.240699 -122.577869) (xy 35.324281 -122.554088) (xy 35.409701 -122.53812)
			(xy 35.49623 -122.530102) (xy 35.58313 -122.530102) (xy 35.669659 -122.53812) (xy 35.755079 -122.554088)
			(xy 35.838661 -122.577869) (xy 35.919693 -122.609261) (xy 35.997482 -122.647995) (xy 36.0572 -122.684971)
			(xy 39.35131 -122.684971) (xy 39.355202 -122.630619) (xy 39.366789 -122.577375) (xy 39.385837 -122.526321)
			(xy 39.411957 -122.478498) (xy 39.444617 -122.43488) (xy 39.483153 -122.396354) (xy 39.52678 -122.363704)
			(xy 39.574609 -122.337597) (xy 39.625668 -122.318562) (xy 39.678915 -122.306988) (xy 39.733268 -122.30311)
			(xy 39.78762 -122.307007) (xy 39.840863 -122.3186) (xy 39.891915 -122.337653) (xy 39.939735 -122.363778)
			(xy 39.96182 -122.37974) (xy 39.980832 -122.393336) (xy 40.022715 -122.414068) (xy 40.067683 -122.426794)
			(xy 40.11422 -122.431084) (xy 40.160757 -122.426794) (xy 40.205725 -122.414068) (xy 40.247608 -122.393336)
			(xy 40.26662 -122.37974) (xy 40.288663 -122.363717) (xy 40.33649 -122.337593) (xy 40.387548 -122.318542)
			(xy 40.440797 -122.306951) (xy 40.495155 -122.303057) (xy 40.549513 -122.306938) (xy 40.602765 -122.318516)
			(xy 40.653828 -122.337555) (xy 40.701661 -122.363668) (xy 40.745291 -122.396322) (xy 40.783829 -122.434853)
			(xy 40.816492 -122.478477) (xy 40.841801 -122.524816) (xy 57.923267 -122.524816) (xy 57.927153 -122.470459)
			(xy 57.938735 -122.417208) (xy 57.957778 -122.366148) (xy 57.983894 -122.318318) (xy 58.016551 -122.274691)
			(xy 58.055085 -122.236156) (xy 58.098711 -122.203498) (xy 58.146541 -122.177381) (xy 58.197601 -122.158337)
			(xy 58.250851 -122.146754) (xy 58.305208 -122.142867) (xy 58.359565 -122.146756) (xy 58.412814 -122.158342)
			(xy 58.463874 -122.177388) (xy 58.511702 -122.203507) (xy 58.533792 -122.219466) (xy 58.552804 -122.233062)
			(xy 58.594687 -122.253794) (xy 58.639655 -122.26652) (xy 58.686192 -122.27081) (xy 58.732729 -122.26652)
			(xy 58.777697 -122.253794) (xy 58.81958 -122.233062) (xy 58.838592 -122.219466) (xy 58.860705 -122.20354)
			(xy 58.908529 -122.177422) (xy 58.959584 -122.158376) (xy 59.01283 -122.14679) (xy 59.067183 -122.142899)
			(xy 59.121536 -122.146785) (xy 59.174783 -122.158366) (xy 59.22584 -122.177408) (xy 59.273667 -122.203522)
			(xy 59.31729 -122.236177) (xy 59.355822 -122.274709) (xy 59.388477 -122.318332) (xy 59.414592 -122.366159)
			(xy 59.433634 -122.417215) (xy 59.445215 -122.470462) (xy 59.449101 -122.524816) (xy 60.164242 -122.524816)
			(xy 60.168128 -122.470453) (xy 60.179712 -122.417197) (xy 60.198758 -122.366131) (xy 60.224878 -122.318297)
			(xy 60.25754 -122.274666) (xy 60.296079 -122.236129) (xy 60.33971 -122.203469) (xy 60.387546 -122.177351)
			(xy 60.438612 -122.158308) (xy 60.491869 -122.146726) (xy 60.546232 -122.142842) (xy 60.600594 -122.146735)
			(xy 60.653849 -122.158326) (xy 60.704912 -122.177378) (xy 60.752743 -122.203503) (xy 60.774834 -122.219466)
			(xy 60.793846 -122.233062) (xy 60.835729 -122.253794) (xy 60.880697 -122.26652) (xy 60.927234 -122.27081)
			(xy 60.973771 -122.26652) (xy 61.018739 -122.253794) (xy 61.060622 -122.233062) (xy 61.079634 -122.219466)
			(xy 61.101746 -122.203544) (xy 61.149567 -122.177432) (xy 61.200618 -122.158392) (xy 61.25386 -122.146811)
			(xy 61.308207 -122.142925) (xy 61.362554 -122.146813) (xy 61.415795 -122.158396) (xy 61.466845 -122.177438)
			(xy 61.514666 -122.203551) (xy 61.558283 -122.236205) (xy 61.59681 -122.274734) (xy 61.629461 -122.318353)
			(xy 61.655572 -122.366175) (xy 61.674611 -122.417227) (xy 61.68619 -122.470468) (xy 61.690075 -122.524816)
			(xy 62.068252 -122.524816) (xy 62.072138 -122.470455) (xy 62.083721 -122.417201) (xy 62.102766 -122.366138)
			(xy 62.128884 -122.318305) (xy 62.161544 -122.274676) (xy 62.200081 -122.236139) (xy 62.243711 -122.20348)
			(xy 62.291544 -122.177363) (xy 62.342608 -122.158319) (xy 62.395862 -122.146737) (xy 62.450223 -122.142852)
			(xy 62.504583 -122.146743) (xy 62.557836 -122.158332) (xy 62.608897 -122.177382) (xy 62.656728 -122.203505)
			(xy 62.678818 -122.219466) (xy 62.69783 -122.233062) (xy 62.739713 -122.253794) (xy 62.784681 -122.26652)
			(xy 62.831218 -122.27081) (xy 62.877755 -122.26652) (xy 62.922723 -122.253794) (xy 62.964606 -122.233062)
			(xy 62.983618 -122.219466) (xy 63.00573 -122.203543) (xy 63.053553 -122.177428) (xy 63.104605 -122.158386)
			(xy 63.157848 -122.146803) (xy 63.212198 -122.142915) (xy 63.266547 -122.146802) (xy 63.31979 -122.158384)
			(xy 63.370843 -122.177426) (xy 63.418666 -122.20354) (xy 63.462286 -122.236194) (xy 63.500814 -122.274724)
			(xy 63.533467 -122.318345) (xy 63.559579 -122.366169) (xy 63.578619 -122.417222) (xy 63.5902 -122.470466)
			(xy 63.594085 -122.524816) (xy 63.590195 -122.579165) (xy 63.578611 -122.632407) (xy 63.559566 -122.683459)
			(xy 63.53345 -122.731281) (xy 63.500794 -122.774899) (xy 63.462262 -122.813426) (xy 63.41864 -122.846077)
			(xy 63.370815 -122.872187) (xy 63.31976 -122.891224) (xy 63.266516 -122.902802) (xy 63.212167 -122.906685)
			(xy 63.157817 -122.902793) (xy 63.104575 -122.891206) (xy 63.053524 -122.872159) (xy 63.005704 -122.84604)
			(xy 62.983618 -122.830082) (xy 62.964606 -122.816486) (xy 62.922723 -122.795754) (xy 62.877755 -122.783028)
			(xy 62.831218 -122.778738) (xy 62.784681 -122.783028) (xy 62.739713 -122.795754) (xy 62.69783 -122.816486)
			(xy 62.678818 -122.830082) (xy 62.656754 -122.846079) (xy 62.608926 -122.872206) (xy 62.557866 -122.891259)
			(xy 62.504614 -122.902852) (xy 62.450254 -122.906748) (xy 62.395893 -122.902868) (xy 62.342638 -122.89129)
			(xy 62.291573 -122.87225) (xy 62.243737 -122.846137) (xy 62.200105 -122.813481) (xy 62.161564 -122.774948)
			(xy 62.128901 -122.731322) (xy 62.102779 -122.683491) (xy 62.08373 -122.632429) (xy 62.072142 -122.579176)
			(xy 62.068252 -122.524816) (xy 61.690075 -122.524816) (xy 61.686186 -122.579163) (xy 61.674602 -122.632403)
			(xy 61.655559 -122.683453) (xy 61.629444 -122.731273) (xy 61.596789 -122.77489) (xy 61.55826 -122.813415)
			(xy 61.51464 -122.846065) (xy 61.466817 -122.872175) (xy 61.415765 -122.891213) (xy 61.362523 -122.902792)
			(xy 61.308176 -122.906675) (xy 61.253829 -122.902785) (xy 61.200588 -122.891199) (xy 61.149539 -122.872155)
			(xy 61.10172 -122.846039) (xy 61.079634 -122.830082) (xy 61.060622 -122.816486) (xy 61.018739 -122.795754)
			(xy 60.973771 -122.783028) (xy 60.927234 -122.778738) (xy 60.880697 -122.783028) (xy 60.835729 -122.795754)
			(xy 60.793846 -122.816486) (xy 60.774834 -122.830082) (xy 60.752769 -122.84608) (xy 60.70494 -122.872209)
			(xy 60.653879 -122.891266) (xy 60.600625 -122.90286) (xy 60.546263 -122.906758) (xy 60.4919 -122.902878)
			(xy 60.438642 -122.891301) (xy 60.387575 -122.872262) (xy 60.339737 -122.846148) (xy 60.296102 -122.813492)
			(xy 60.25756 -122.774957) (xy 60.224894 -122.73133) (xy 60.198771 -122.683497) (xy 60.179721 -122.632433)
			(xy 60.168133 -122.579178) (xy 60.164242 -122.524816) (xy 59.449101 -122.524816) (xy 59.445211 -122.579168)
			(xy 59.433625 -122.632414) (xy 59.414579 -122.683469) (xy 59.38846 -122.731294) (xy 59.355801 -122.774915)
			(xy 59.317266 -122.813443) (xy 59.27364 -122.846095) (xy 59.225811 -122.872205) (xy 59.174753 -122.891243)
			(xy 59.121505 -122.90282) (xy 59.067152 -122.906701) (xy 59.012799 -122.902806) (xy 58.959554 -122.891216)
			(xy 58.908501 -122.872165) (xy 58.860678 -122.846043) (xy 58.838592 -122.830082) (xy 58.81958 -122.816486)
			(xy 58.777697 -122.795754) (xy 58.732729 -122.783028) (xy 58.686192 -122.778738) (xy 58.639655 -122.783028)
			(xy 58.594687 -122.795754) (xy 58.552804 -122.816486) (xy 58.533792 -122.830082) (xy 58.511728 -122.846076)
			(xy 58.463902 -122.872199) (xy 58.412844 -122.891249) (xy 58.359595 -122.902839) (xy 58.305239 -122.906733)
			(xy 58.250882 -122.90285) (xy 58.197631 -122.891271) (xy 58.146569 -122.872232) (xy 58.098737 -122.846119)
			(xy 58.055109 -122.813464) (xy 58.016572 -122.774932) (xy 57.983911 -122.731309) (xy 57.957791 -122.683481)
			(xy 57.938744 -122.632422) (xy 57.927158 -122.579172) (xy 57.923267 -122.524816) (xy 40.841801 -122.524816)
			(xy 40.842614 -122.526305) (xy 40.861663 -122.577364) (xy 40.873251 -122.630614) (xy 40.877143 -122.684971)
			(xy 40.873259 -122.739329) (xy 40.861679 -122.792581) (xy 40.842638 -122.843643) (xy 40.816523 -122.891475)
			(xy 40.783867 -122.935103) (xy 40.745334 -122.97364) (xy 40.701709 -123.006301) (xy 40.65388 -123.032421)
			(xy 40.60282 -123.051467) (xy 40.54957 -123.063053) (xy 40.495212 -123.066943) (xy 40.440854 -123.063057)
			(xy 40.387603 -123.051474) (xy 40.336542 -123.032431) (xy 40.288711 -123.006314) (xy 40.26662 -122.990356)
			(xy 40.247608 -122.97676) (xy 40.205725 -122.956028) (xy 40.160757 -122.943302) (xy 40.11422 -122.939012)
			(xy 40.067683 -122.943302) (xy 40.022715 -122.956028) (xy 39.980832 -122.97676) (xy 39.96182 -122.990356)
			(xy 39.939686 -123.006253) (xy 39.891862 -123.032371) (xy 39.840808 -123.051416) (xy 39.787563 -123.063001)
			(xy 39.733211 -123.06689) (xy 39.678858 -123.063004) (xy 39.625612 -123.051422) (xy 39.574557 -123.032379)
			(xy 39.526731 -123.006264) (xy 39.48311 -122.973608) (xy 39.44458 -122.935077) (xy 39.411926 -122.891453)
			(xy 39.385813 -122.843626) (xy 39.366773 -122.79257) (xy 39.355193 -122.739324) (xy 39.35131 -122.684971)
			(xy 36.0572 -122.684971) (xy 36.071366 -122.693742) (xy 36.140713 -122.746111) (xy 36.204933 -122.804655)
			(xy 36.263477 -122.868875) (xy 36.315846 -122.938222) (xy 36.361593 -123.012106) (xy 36.400327 -123.089895)
			(xy 36.431719 -123.170927) (xy 36.4555 -123.254509) (xy 36.471468 -123.339929) (xy 36.479486 -123.426458)
			(xy 36.479988 -123.469908) (xy 36.479486 -123.513358) (xy 36.471468 -123.599887) (xy 36.4555 -123.685307)
			(xy 36.431719 -123.768889) (xy 36.400327 -123.849921) (xy 36.361593 -123.92771) (xy 36.315846 -124.001594)
			(xy 36.263477 -124.070941) (xy 36.204933 -124.135161) (xy 36.140713 -124.193705) (xy 36.071366 -124.246074)
			(xy 35.997482 -124.291821) (xy 35.919693 -124.330555) (xy 35.838661 -124.361947) (xy 35.755079 -124.385728)
			(xy 35.669659 -124.401696) (xy 35.58313 -124.409714) (xy 35.49623 -124.409714) (xy 35.409701 -124.401696)
			(xy 35.324281 -124.385728) (xy 35.240699 -124.361947) (xy 35.159667 -124.330555) (xy 35.081878 -124.291821)
			(xy 35.007994 -124.246074) (xy 34.938647 -124.193705) (xy 34.874427 -124.135161) (xy 34.815883 -124.070941)
			(xy 34.763514 -124.001594) (xy 34.717767 -123.92771) (xy 34.679033 -123.849921) (xy 34.647641 -123.768889)
			(xy 34.62386 -123.685307) (xy 34.607892 -123.599887) (xy 34.599874 -123.513358) (xy 31.399486 -123.513358)
			(xy 31.391468 -123.599887) (xy 31.3755 -123.685307) (xy 31.351719 -123.768889) (xy 31.320327 -123.849921)
			(xy 31.281593 -123.92771) (xy 31.235846 -124.001594) (xy 31.183477 -124.070941) (xy 31.124933 -124.135161)
			(xy 31.060713 -124.193705) (xy 30.991366 -124.246074) (xy 30.917482 -124.291821) (xy 30.839693 -124.330555)
			(xy 30.758661 -124.361947) (xy 30.675079 -124.385728) (xy 30.589659 -124.401696) (xy 30.50313 -124.409714)
			(xy 30.41623 -124.409714) (xy 30.329701 -124.401696) (xy 30.244281 -124.385728) (xy 30.160699 -124.361947)
			(xy 30.079667 -124.330555) (xy 30.001878 -124.291821) (xy 29.927994 -124.246074) (xy 29.858647 -124.193705)
			(xy 29.794427 -124.135161) (xy 29.735883 -124.070941) (xy 29.683514 -124.001594) (xy 29.637767 -123.92771)
			(xy 29.599033 -123.849921) (xy 29.567641 -123.768889) (xy 29.54386 -123.685307) (xy 29.527892 -123.599887)
			(xy 29.519874 -123.513358) (xy 27.89936 -123.513358) (xy 27.89936 -124.696188) (xy 39.307908 -124.696188)
			(xy 39.311797 -124.641837) (xy 39.323382 -124.588594) (xy 39.342426 -124.53754) (xy 39.368542 -124.489717)
			(xy 39.401199 -124.446098) (xy 39.439731 -124.40757) (xy 39.483354 -124.374919) (xy 39.53118 -124.348808)
			(xy 39.582236 -124.329769) (xy 39.635481 -124.318191) (xy 39.689832 -124.314308) (xy 39.744182 -124.3182)
			(xy 39.797426 -124.329787) (xy 39.848478 -124.348834) (xy 39.8963 -124.374953) (xy 39.918386 -124.390912)
			(xy 39.937398 -124.404508) (xy 39.979281 -124.42524) (xy 40.024249 -124.437966) (xy 40.070786 -124.442256)
			(xy 40.117323 -124.437966) (xy 40.162291 -124.42524) (xy 40.204174 -124.404508) (xy 40.223186 -124.390912)
			(xy 40.245256 -124.374924) (xy 40.293083 -124.348798) (xy 40.344142 -124.329746) (xy 40.397393 -124.318154)
			(xy 40.451752 -124.314259) (xy 40.506112 -124.31814) (xy 40.559365 -124.329719) (xy 40.610429 -124.348758)
			(xy 40.658263 -124.374872) (xy 40.701894 -124.407528) (xy 40.740433 -124.44606) (xy 40.773096 -124.489686)
			(xy 40.798319 -124.535872) (xy 57.879945 -124.535872) (xy 57.883836 -124.481529) (xy 57.895421 -124.428292)
			(xy 57.914465 -124.377246) (xy 57.940579 -124.329429) (xy 57.973233 -124.285816) (xy 58.011761 -124.247294)
			(xy 58.055379 -124.214647) (xy 58.1032 -124.18854) (xy 58.154249 -124.169505) (xy 58.207487 -124.157928)
			(xy 58.261832 -124.154045) (xy 58.316175 -124.157937) (xy 58.369412 -124.169522) (xy 58.420458 -124.188567)
			(xy 58.468274 -124.214682) (xy 58.490358 -124.230638) (xy 58.50937 -124.244234) (xy 58.551253 -124.264966)
			(xy 58.596221 -124.277692) (xy 58.642758 -124.281982) (xy 58.689295 -124.277692) (xy 58.734263 -124.264966)
			(xy 58.776146 -124.244234) (xy 58.795158 -124.230638) (xy 58.817204 -124.214612) (xy 58.865035 -124.188479)
			(xy 58.916099 -124.169419) (xy 58.969355 -124.157821) (xy 59.02372 -124.153921) (xy 59.078087 -124.157799)
			(xy 59.131349 -124.169375) (xy 59.18242 -124.188413) (xy 59.230262 -124.214526) (xy 59.2739 -124.247183)
			(xy 59.312447 -124.285719) (xy 59.345116 -124.329348) (xy 59.371243 -124.377182) (xy 59.390295 -124.428249)
			(xy 59.401886 -124.481507) (xy 59.405779 -124.535872) (xy 60.12092 -124.535872) (xy 60.124812 -124.481523)
			(xy 60.136398 -124.428281) (xy 60.155445 -124.377229) (xy 60.181563 -124.329408) (xy 60.214221 -124.285791)
			(xy 60.252754 -124.247266) (xy 60.296378 -124.214618) (xy 60.344205 -124.18851) (xy 60.395261 -124.169475)
			(xy 60.448505 -124.1579) (xy 60.502856 -124.15402) (xy 60.557205 -124.157916) (xy 60.610446 -124.169506)
			(xy 60.661496 -124.188556) (xy 60.709315 -124.214678) (xy 60.7314 -124.230638) (xy 60.750412 -124.244234)
			(xy 60.792295 -124.264966) (xy 60.837263 -124.277692) (xy 60.8838 -124.281982) (xy 60.930337 -124.277692)
			(xy 60.975305 -124.264966) (xy 61.017188 -124.244234) (xy 61.0362 -124.230638) (xy 61.058245 -124.214616)
			(xy 61.106073 -124.188489) (xy 61.157133 -124.169436) (xy 61.210385 -124.157843) (xy 61.264744 -124.153947)
			(xy 61.319105 -124.157827) (xy 61.37236 -124.169404) (xy 61.423425 -124.188443) (xy 61.471261 -124.214556)
			(xy 61.514894 -124.247211) (xy 61.553435 -124.285743) (xy 61.586099 -124.329369) (xy 61.612222 -124.377199)
			(xy 61.631272 -124.42826) (xy 61.642861 -124.481513) (xy 61.646753 -124.535872) (xy 62.02493 -124.535872)
			(xy 62.028821 -124.481525) (xy 62.040407 -124.428285) (xy 62.059452 -124.377236) (xy 62.085569 -124.329416)
			(xy 62.118226 -124.285801) (xy 62.156757 -124.247277) (xy 62.200379 -124.214629) (xy 62.248203 -124.188522)
			(xy 62.299256 -124.169486) (xy 62.352499 -124.15791) (xy 62.406847 -124.15403) (xy 62.461194 -124.157924)
			(xy 62.514433 -124.169512) (xy 62.565482 -124.18856) (xy 62.6133 -124.214679) (xy 62.635384 -124.230638)
			(xy 62.654396 -124.244234) (xy 62.696279 -124.264966) (xy 62.741247 -124.277692) (xy 62.787784 -124.281982)
			(xy 62.834321 -124.277692) (xy 62.879289 -124.264966) (xy 62.921172 -124.244234) (xy 62.940184 -124.230638)
			(xy 62.962229 -124.214615) (xy 63.010059 -124.188485) (xy 63.06112 -124.169429) (xy 63.114374 -124.157835)
			(xy 63.168735 -124.153937) (xy 63.223098 -124.157816) (xy 63.276356 -124.169393) (xy 63.327423 -124.188432)
			(xy 63.375262 -124.214545) (xy 63.418896 -124.2472) (xy 63.457439 -124.285734) (xy 63.490105 -124.329361)
			(xy 63.51623 -124.377193) (xy 63.535281 -124.428256) (xy 63.546871 -124.48151) (xy 63.550763 -124.535872)
			(xy 63.546879 -124.590235) (xy 63.535297 -124.643491) (xy 63.516253 -124.694557) (xy 63.490135 -124.742393)
			(xy 63.457475 -124.786024) (xy 63.418938 -124.824564) (xy 63.375308 -124.857226) (xy 63.327474 -124.883345)
			(xy 63.276409 -124.902392) (xy 63.223153 -124.913976) (xy 63.16879 -124.917863) (xy 63.114428 -124.913973)
			(xy 63.061173 -124.902386) (xy 63.010109 -124.883338) (xy 62.962276 -124.857215) (xy 62.940184 -124.841254)
			(xy 62.921172 -124.827658) (xy 62.879289 -124.806926) (xy 62.834321 -124.7942) (xy 62.787784 -124.78991)
			(xy 62.741247 -124.7942) (xy 62.696279 -124.806926) (xy 62.654396 -124.827658) (xy 62.635384 -124.841254)
			(xy 62.613253 -124.857151) (xy 62.565431 -124.883263) (xy 62.51438 -124.902303) (xy 62.461139 -124.913884)
			(xy 62.406791 -124.91777) (xy 62.352444 -124.913882) (xy 62.299203 -124.902298) (xy 62.248153 -124.883256)
			(xy 62.200332 -124.857141) (xy 62.156715 -124.824487) (xy 62.118189 -124.785957) (xy 62.085539 -124.742337)
			(xy 62.059429 -124.694514) (xy 62.040392 -124.643462) (xy 62.028813 -124.59022) (xy 62.02493 -124.535872)
			(xy 61.646753 -124.535872) (xy 61.642869 -124.590233) (xy 61.631288 -124.643487) (xy 61.612245 -124.694551)
			(xy 61.586129 -124.742385) (xy 61.553471 -124.786015) (xy 61.514936 -124.824553) (xy 61.471308 -124.857214)
			(xy 61.423476 -124.883334) (xy 61.372413 -124.90238) (xy 61.31916 -124.913965) (xy 61.2648 -124.917853)
			(xy 61.210439 -124.913965) (xy 61.157186 -124.90238) (xy 61.106123 -124.883334) (xy 61.058291 -124.857214)
			(xy 61.0362 -124.841254) (xy 61.017188 -124.827658) (xy 60.975305 -124.806926) (xy 60.930337 -124.7942)
			(xy 60.8838 -124.78991) (xy 60.837263 -124.7942) (xy 60.792295 -124.806926) (xy 60.750412 -124.827658)
			(xy 60.7314 -124.841254) (xy 60.709269 -124.857152) (xy 60.661446 -124.883267) (xy 60.610393 -124.902309)
			(xy 60.55715 -124.913892) (xy 60.5028 -124.91778) (xy 60.448451 -124.913892) (xy 60.395208 -124.90231)
			(xy 60.344155 -124.883267) (xy 60.296332 -124.857152) (xy 60.252713 -124.824497) (xy 60.214185 -124.785967)
			(xy 60.181533 -124.742345) (xy 60.155422 -124.69452) (xy 60.136383 -124.643466) (xy 60.124804 -124.590222)
			(xy 60.12092 -124.535872) (xy 59.405779 -124.535872) (xy 59.401894 -124.590239) (xy 59.390311 -124.643498)
			(xy 59.371265 -124.694567) (xy 59.345145 -124.742406) (xy 59.312483 -124.78604) (xy 59.273942 -124.824581)
			(xy 59.230309 -124.857244) (xy 59.18247 -124.883364) (xy 59.131402 -124.90241) (xy 59.078142 -124.913993)
			(xy 59.023776 -124.917879) (xy 58.96941 -124.913986) (xy 58.916152 -124.902396) (xy 58.865085 -124.883344)
			(xy 58.81725 -124.857217) (xy 58.795158 -124.841254) (xy 58.776146 -124.827658) (xy 58.734263 -124.806926)
			(xy 58.689295 -124.7942) (xy 58.642758 -124.78991) (xy 58.596221 -124.7942) (xy 58.551253 -124.806926)
			(xy 58.50937 -124.827658) (xy 58.490358 -124.841254) (xy 58.468228 -124.857148) (xy 58.420408 -124.883256)
			(xy 58.369359 -124.902293) (xy 58.316121 -124.913871) (xy 58.261777 -124.917755) (xy 58.207433 -124.913864)
			(xy 58.154196 -124.90228) (xy 58.10315 -124.883237) (xy 58.055333 -124.857123) (xy 58.011719 -124.82447)
			(xy 57.973197 -124.785942) (xy 57.940549 -124.742324) (xy 57.914442 -124.694504) (xy 57.895406 -124.643455)
			(xy 57.883828 -124.590217) (xy 57.879945 -124.535872) (xy 40.798319 -124.535872) (xy 40.799217 -124.537516)
			(xy 40.818264 -124.588577) (xy 40.829851 -124.641829) (xy 40.833741 -124.696188) (xy 40.829855 -124.750547)
			(xy 40.818271 -124.8038) (xy 40.799227 -124.854862) (xy 40.773109 -124.902694) (xy 40.740449 -124.946321)
			(xy 40.701912 -124.984857) (xy 40.658284 -125.017515) (xy 40.610451 -125.043632) (xy 40.559388 -125.062675)
			(xy 40.506135 -125.074256) (xy 40.451776 -125.078141) (xy 40.397417 -125.074249) (xy 40.344165 -125.062661)
			(xy 40.293105 -125.043612) (xy 40.245276 -125.017489) (xy 40.223186 -125.001528) (xy 40.204174 -124.987932)
			(xy 40.162291 -124.9672) (xy 40.117323 -124.954474) (xy 40.070786 -124.950184) (xy 40.024249 -124.954474)
			(xy 39.979281 -124.9672) (xy 39.937398 -124.987932) (xy 39.918386 -125.001528) (xy 39.896279 -125.01746)
			(xy 39.848456 -125.043576) (xy 39.797403 -125.06262) (xy 39.744159 -125.074204) (xy 39.689808 -125.078092)
			(xy 39.635457 -125.074206) (xy 39.582213 -125.062624) (xy 39.531159 -125.043582) (xy 39.483334 -125.017469)
			(xy 39.439713 -124.984814) (xy 39.401183 -124.946284) (xy 39.368529 -124.902663) (xy 39.342416 -124.854838)
			(xy 39.323375 -124.803783) (xy 39.311794 -124.750539) (xy 39.307908 -124.696188) (xy 27.89936 -124.696188)
			(xy 27.89936 -126.053358) (xy 29.519874 -126.053358) (xy 29.519874 -125.966458) (xy 29.527892 -125.879929)
			(xy 29.54386 -125.794509) (xy 29.567641 -125.710927) (xy 29.599033 -125.629895) (xy 29.637767 -125.552106)
			(xy 29.683514 -125.478222) (xy 29.735883 -125.408875) (xy 29.794427 -125.344655) (xy 29.858647 -125.286111)
			(xy 29.927994 -125.233742) (xy 30.001878 -125.187995) (xy 30.079667 -125.149261) (xy 30.160699 -125.117869)
			(xy 30.244281 -125.094088) (xy 30.329701 -125.07812) (xy 30.41623 -125.070102) (xy 30.50313 -125.070102)
			(xy 30.589659 -125.07812) (xy 30.675079 -125.094088) (xy 30.758661 -125.117869) (xy 30.839693 -125.149261)
			(xy 30.917482 -125.187995) (xy 30.991366 -125.233742) (xy 31.060713 -125.286111) (xy 31.124933 -125.344655)
			(xy 31.183477 -125.408875) (xy 31.235846 -125.478222) (xy 31.281593 -125.552106) (xy 31.320327 -125.629895)
			(xy 31.351719 -125.710927) (xy 31.3755 -125.794509) (xy 31.391468 -125.879929) (xy 31.399486 -125.966458)
			(xy 31.399988 -126.009908) (xy 31.399486 -126.053358) (xy 34.599874 -126.053358) (xy 34.599874 -125.966458)
			(xy 34.607892 -125.879929) (xy 34.62386 -125.794509) (xy 34.647641 -125.710927) (xy 34.679033 -125.629895)
			(xy 34.717767 -125.552106) (xy 34.763514 -125.478222) (xy 34.815883 -125.408875) (xy 34.874427 -125.344655)
			(xy 34.938647 -125.286111) (xy 35.007994 -125.233742) (xy 35.081878 -125.187995) (xy 35.159667 -125.149261)
			(xy 35.240699 -125.117869) (xy 35.324281 -125.094088) (xy 35.409701 -125.07812) (xy 35.49623 -125.070102)
			(xy 35.58313 -125.070102) (xy 35.669659 -125.07812) (xy 35.755079 -125.094088) (xy 35.838661 -125.117869)
			(xy 35.919693 -125.149261) (xy 35.997482 -125.187995) (xy 36.071366 -125.233742) (xy 36.140713 -125.286111)
			(xy 36.204933 -125.344655) (xy 36.263477 -125.408875) (xy 36.315846 -125.478222) (xy 36.361593 -125.552106)
			(xy 36.400327 -125.629895) (xy 36.431719 -125.710927) (xy 36.4555 -125.794509) (xy 36.471468 -125.879929)
			(xy 36.479486 -125.966458) (xy 36.479988 -126.009908) (xy 36.479486 -126.053358) (xy 36.471468 -126.139887)
			(xy 36.4555 -126.225307) (xy 36.431719 -126.308889) (xy 36.400327 -126.389921) (xy 36.361593 -126.46771)
			(xy 36.315846 -126.541594) (xy 36.281802 -126.586675) (xy 39.307925 -126.586675) (xy 39.311816 -126.532327)
			(xy 39.323402 -126.479086) (xy 39.342447 -126.428036) (xy 39.368564 -126.380216) (xy 39.401221 -126.336599)
			(xy 39.439753 -126.298075) (xy 39.483375 -126.265426) (xy 39.5312 -126.239318) (xy 39.582253 -126.220282)
			(xy 39.635497 -126.208706) (xy 39.689845 -126.204825) (xy 39.744193 -126.208719) (xy 39.797433 -126.220308)
			(xy 39.848483 -126.239356) (xy 39.896301 -126.265475) (xy 39.918386 -126.281434) (xy 39.937398 -126.29503)
			(xy 39.979281 -126.315762) (xy 40.024249 -126.328488) (xy 40.070786 -126.332778) (xy 40.117323 -126.328488)
			(xy 40.162291 -126.315762) (xy 40.204174 -126.29503) (xy 40.223186 -126.281434) (xy 40.245235 -126.265416)
			(xy 40.293064 -126.239288) (xy 40.344125 -126.220233) (xy 40.397378 -126.208638) (xy 40.451739 -126.204741)
			(xy 40.506101 -126.208621) (xy 40.559358 -126.220198) (xy 40.610425 -126.239237) (xy 40.658262 -126.26535)
			(xy 40.701896 -126.298006) (xy 40.740438 -126.336539) (xy 40.773103 -126.380165) (xy 40.79842 -126.426519)
			(xy 57.879883 -126.426519) (xy 57.883768 -126.372166) (xy 57.895348 -126.318919) (xy 57.914389 -126.267862)
			(xy 57.940501 -126.220035) (xy 57.973155 -126.176411) (xy 58.011685 -126.137878) (xy 58.055306 -126.10522)
			(xy 58.103131 -126.079103) (xy 58.154186 -126.060058) (xy 58.207432 -126.048473) (xy 58.261785 -126.044583)
			(xy 58.316138 -126.048468) (xy 58.369385 -126.060049) (xy 58.420441 -126.07909) (xy 58.468269 -126.105204)
			(xy 58.490358 -126.12116) (xy 58.50937 -126.134756) (xy 58.551253 -126.155488) (xy 58.596221 -126.168214)
			(xy 58.642758 -126.172504) (xy 58.689295 -126.168214) (xy 58.734263 -126.155488) (xy 58.776146 -126.134756)
			(xy 58.795158 -126.12116) (xy 58.817277 -126.10524) (xy 58.865104 -126.079116) (xy 58.916161 -126.060066)
			(xy 58.969411 -126.048477) (xy 59.023767 -126.044584) (xy 59.078125 -126.048467) (xy 59.131376 -126.060048)
			(xy 59.182437 -126.079089) (xy 59.230268 -126.105204) (xy 59.273895 -126.137861) (xy 59.31243 -126.176395)
			(xy 59.345088 -126.220021) (xy 59.371205 -126.267851) (xy 59.390249 -126.318911) (xy 59.401831 -126.372162)
			(xy 59.405716 -126.426519) (xy 60.120858 -126.426519) (xy 60.124743 -126.37216) (xy 60.136325 -126.318908)
			(xy 60.155368 -126.267846) (xy 60.181485 -126.220014) (xy 60.214143 -126.176386) (xy 60.252678 -126.13785)
			(xy 60.296305 -126.105191) (xy 60.344137 -126.079073) (xy 60.395198 -126.060028) (xy 60.44845 -126.048445)
			(xy 60.502809 -126.044558) (xy 60.557167 -126.048447) (xy 60.610419 -126.060033) (xy 60.661479 -126.07908)
			(xy 60.70931 -126.1052) (xy 60.7314 -126.12116) (xy 60.750412 -126.134756) (xy 60.792295 -126.155488)
			(xy 60.837263 -126.168214) (xy 60.8838 -126.172504) (xy 60.930337 -126.168214) (xy 60.975305 -126.155488)
			(xy 61.017188 -126.134756) (xy 61.0362 -126.12116) (xy 61.058318 -126.105243) (xy 61.106142 -126.079127)
			(xy 61.157196 -126.060082) (xy 61.21044 -126.048498) (xy 61.264791 -126.044609) (xy 61.319143 -126.048495)
			(xy 61.372388 -126.060077) (xy 61.423442 -126.079119) (xy 61.471267 -126.105234) (xy 61.514888 -126.137889)
			(xy 61.553418 -126.17642) (xy 61.586072 -126.220042) (xy 61.612185 -126.267867) (xy 61.631226 -126.318922)
			(xy 61.642806 -126.372168) (xy 61.646691 -126.426519) (xy 62.024867 -126.426519) (xy 62.028752 -126.372163)
			(xy 62.040334 -126.318912) (xy 62.059376 -126.267852) (xy 62.085491 -126.220022) (xy 62.118148 -126.176395)
			(xy 62.156681 -126.13786) (xy 62.200306 -126.105202) (xy 62.248135 -126.079084) (xy 62.299194 -126.060039)
			(xy 62.352443 -126.048455) (xy 62.4068 -126.044567) (xy 62.461156 -126.048455) (xy 62.514406 -126.060039)
			(xy 62.565465 -126.079084) (xy 62.613294 -126.105201) (xy 62.635384 -126.12116) (xy 62.654396 -126.134756)
			(xy 62.696279 -126.155488) (xy 62.741247 -126.168214) (xy 62.787784 -126.172504) (xy 62.834321 -126.168214)
			(xy 62.879289 -126.155488) (xy 62.921172 -126.134756) (xy 62.940184 -126.12116) (xy 62.962303 -126.105242)
			(xy 63.010127 -126.079123) (xy 63.061183 -126.060076) (xy 63.114429 -126.04849) (xy 63.168782 -126.0446)
			(xy 63.223136 -126.048485) (xy 63.276383 -126.060066) (xy 63.32744 -126.079108) (xy 63.375267 -126.105222)
			(xy 63.418891 -126.137878) (xy 63.457423 -126.17641) (xy 63.490078 -126.220034) (xy 63.516193 -126.267861)
			(xy 63.535234 -126.318918) (xy 63.546816 -126.372166) (xy 63.5507 -126.426519) (xy 63.54681 -126.480872)
			(xy 63.535224 -126.534119) (xy 63.516177 -126.585174) (xy 63.490057 -126.632999) (xy 63.457398 -126.676619)
			(xy 63.418862 -126.715147) (xy 63.375235 -126.747798) (xy 63.327405 -126.773908) (xy 63.276346 -126.792945)
			(xy 63.223098 -126.804521) (xy 63.168744 -126.8084) (xy 63.114391 -126.804505) (xy 63.061146 -126.792913)
			(xy 63.010092 -126.773861) (xy 62.96227 -126.747737) (xy 62.940184 -126.731776) (xy 62.921172 -126.71818)
			(xy 62.879289 -126.697448) (xy 62.834321 -126.684722) (xy 62.787784 -126.680432) (xy 62.741247 -126.684722)
			(xy 62.696279 -126.697448) (xy 62.654396 -126.71818) (xy 62.635384 -126.731776) (xy 62.613326 -126.747778)
			(xy 62.5655 -126.7739) (xy 62.514443 -126.79295) (xy 62.461194 -126.804539) (xy 62.406838 -126.808433)
			(xy 62.352481 -126.80455) (xy 62.29923 -126.792971) (xy 62.248169 -126.773932) (xy 62.200338 -126.747819)
			(xy 62.15671 -126.715165) (xy 62.118173 -126.676634) (xy 62.085512 -126.63301) (xy 62.059392 -126.585183)
			(xy 62.040345 -126.534125) (xy 62.028758 -126.480875) (xy 62.024867 -126.426519) (xy 61.646691 -126.426519)
			(xy 61.642801 -126.48087) (xy 61.631215 -126.534114) (xy 61.612169 -126.585168) (xy 61.586051 -126.632991)
			(xy 61.553393 -126.67661) (xy 61.514859 -126.715136) (xy 61.471235 -126.747787) (xy 61.423407 -126.773897)
			(xy 61.372351 -126.792934) (xy 61.319105 -126.80451) (xy 61.264753 -126.808391) (xy 61.210402 -126.804497)
			(xy 61.157159 -126.792907) (xy 61.106107 -126.773857) (xy 61.058286 -126.747736) (xy 61.0362 -126.731776)
			(xy 61.017188 -126.71818) (xy 60.975305 -126.697448) (xy 60.930337 -126.684722) (xy 60.8838 -126.680432)
			(xy 60.837263 -126.684722) (xy 60.792295 -126.697448) (xy 60.750412 -126.71818) (xy 60.7314 -126.731776)
			(xy 60.709342 -126.747779) (xy 60.661514 -126.773904) (xy 60.610456 -126.792956) (xy 60.557205 -126.804547)
			(xy 60.502847 -126.808442) (xy 60.448488 -126.804561) (xy 60.395235 -126.792983) (xy 60.344172 -126.773943)
			(xy 60.296338 -126.74783) (xy 60.252707 -126.715175) (xy 60.214168 -126.676643) (xy 60.181506 -126.633018)
			(xy 60.155384 -126.585189) (xy 60.136336 -126.534129) (xy 60.124749 -126.480878) (xy 60.120858 -126.426519)
			(xy 59.405716 -126.426519) (xy 59.401825 -126.480876) (xy 59.390238 -126.534126) (xy 59.371189 -126.585184)
			(xy 59.345068 -126.633011) (xy 59.312405 -126.676634) (xy 59.273866 -126.715164) (xy 59.230235 -126.747817)
			(xy 59.182402 -126.773927) (xy 59.131339 -126.792963) (xy 59.078087 -126.804538) (xy 59.023729 -126.808416)
			(xy 58.969373 -126.804518) (xy 58.916124 -126.792923) (xy 58.865069 -126.773868) (xy 58.817245 -126.74774)
			(xy 58.795158 -126.731776) (xy 58.776146 -126.71818) (xy 58.734263 -126.697448) (xy 58.689295 -126.684722)
			(xy 58.642758 -126.680432) (xy 58.596221 -126.684722) (xy 58.551253 -126.697448) (xy 58.50937 -126.71818)
			(xy 58.490358 -126.731776) (xy 58.468301 -126.747776) (xy 58.420476 -126.773894) (xy 58.369422 -126.79294)
			(xy 58.316176 -126.804526) (xy 58.261823 -126.808417) (xy 58.20747 -126.804533) (xy 58.154223 -126.792953)
			(xy 58.103166 -126.773913) (xy 58.055338 -126.747801) (xy 58.011714 -126.715148) (xy 57.97318 -126.676618)
			(xy 57.940522 -126.632997) (xy 57.914405 -126.585173) (xy 57.895359 -126.534118) (xy 57.883773 -126.480872)
			(xy 57.879883 -126.426519) (xy 40.79842 -126.426519) (xy 40.799227 -126.427997) (xy 40.818278 -126.479059)
			(xy 40.829867 -126.532313) (xy 40.833759 -126.586675) (xy 40.829874 -126.641037) (xy 40.818292 -126.694292)
			(xy 40.799248 -126.745357) (xy 40.773131 -126.793192) (xy 40.740471 -126.836823) (xy 40.701934 -126.875361)
			(xy 40.658304 -126.908023) (xy 40.61047 -126.934142) (xy 40.559406 -126.953188) (xy 40.506151 -126.964772)
			(xy 40.451789 -126.968659) (xy 40.397428 -126.964769) (xy 40.344173 -126.953182) (xy 40.29311 -126.934133)
			(xy 40.245278 -126.908011) (xy 40.223186 -126.89205) (xy 40.204174 -126.878454) (xy 40.162291 -126.857722)
			(xy 40.117323 -126.844996) (xy 40.070786 -126.840706) (xy 40.024249 -126.844996) (xy 39.979281 -126.857722)
			(xy 39.937398 -126.878454) (xy 39.918386 -126.89205) (xy 39.896259 -126.907952) (xy 39.848437 -126.934065)
			(xy 39.797385 -126.953106) (xy 39.744143 -126.964688) (xy 39.689795 -126.968575) (xy 39.635447 -126.964687)
			(xy 39.582205 -126.953103) (xy 39.531154 -126.934061) (xy 39.483333 -126.907947) (xy 39.439715 -126.875292)
			(xy 39.401188 -126.836762) (xy 39.368537 -126.793142) (xy 39.342427 -126.745318) (xy 39.323388 -126.694266)
			(xy 39.311809 -126.641023) (xy 39.307925 -126.586675) (xy 36.281802 -126.586675) (xy 36.263477 -126.610941)
			(xy 36.204933 -126.675161) (xy 36.140713 -126.733705) (xy 36.071366 -126.786074) (xy 35.997482 -126.831821)
			(xy 35.919693 -126.870555) (xy 35.838661 -126.901947) (xy 35.755079 -126.925728) (xy 35.669659 -126.941696)
			(xy 35.58313 -126.949714) (xy 35.49623 -126.949714) (xy 35.409701 -126.941696) (xy 35.324281 -126.925728)
			(xy 35.240699 -126.901947) (xy 35.159667 -126.870555) (xy 35.081878 -126.831821) (xy 35.007994 -126.786074)
			(xy 34.938647 -126.733705) (xy 34.874427 -126.675161) (xy 34.815883 -126.610941) (xy 34.763514 -126.541594)
			(xy 34.717767 -126.46771) (xy 34.679033 -126.389921) (xy 34.647641 -126.308889) (xy 34.62386 -126.225307)
			(xy 34.607892 -126.139887) (xy 34.599874 -126.053358) (xy 31.399486 -126.053358) (xy 31.391468 -126.139887)
			(xy 31.3755 -126.225307) (xy 31.351719 -126.308889) (xy 31.320327 -126.389921) (xy 31.281593 -126.46771)
			(xy 31.235846 -126.541594) (xy 31.183477 -126.610941) (xy 31.124933 -126.675161) (xy 31.060713 -126.733705)
			(xy 30.991366 -126.786074) (xy 30.917482 -126.831821) (xy 30.839693 -126.870555) (xy 30.758661 -126.901947)
			(xy 30.675079 -126.925728) (xy 30.589659 -126.941696) (xy 30.50313 -126.949714) (xy 30.41623 -126.949714)
			(xy 30.329701 -126.941696) (xy 30.244281 -126.925728) (xy 30.160699 -126.901947) (xy 30.079667 -126.870555)
			(xy 30.001878 -126.831821) (xy 29.927994 -126.786074) (xy 29.858647 -126.733705) (xy 29.794427 -126.675161)
			(xy 29.735883 -126.610941) (xy 29.683514 -126.541594) (xy 29.637767 -126.46771) (xy 29.599033 -126.389921)
			(xy 29.567641 -126.308889) (xy 29.54386 -126.225307) (xy 29.527892 -126.139887) (xy 29.519874 -126.053358)
			(xy 27.89936 -126.053358) (xy 27.89936 -127.233426) (xy 66.678556 -127.233426) (xy 66.678556 -126.324614)
			(xy 66.67901 -126.292509) (xy 66.687104 -126.228811) (xy 66.703154 -126.166639) (xy 66.726903 -126.106982)
			(xy 66.757974 -126.05079) (xy 66.795871 -125.998957) (xy 66.839993 -125.952307) (xy 66.889637 -125.911583)
			(xy 66.944013 -125.877433) (xy 67.002256 -125.850401) (xy 67.063438 -125.830916) (xy 67.126587 -125.819289)
			(xy 67.190697 -125.815704) (xy 67.254748 -125.82022) (xy 67.317721 -125.832763) (xy 67.378614 -125.853134)
			(xy 67.436458 -125.88101) (xy 67.490332 -125.915946) (xy 67.539379 -125.957387) (xy 67.56146 -125.980698)
			(xy 67.577672 -125.997583) (xy 67.615089 -126.0257) (xy 67.657022 -126.046491) (xy 67.702052 -126.059253)
			(xy 67.748658 -126.063556) (xy 67.795264 -126.059253) (xy 67.840294 -126.046491) (xy 67.882227 -126.0257)
			(xy 67.919644 -125.997583) (xy 67.935856 -125.980698) (xy 67.958304 -125.957051) (xy 68.008198 -125.915076)
			(xy 68.063049 -125.879825) (xy 68.121958 -125.851877) (xy 68.183956 -125.83169) (xy 68.248026 -125.819595)
			(xy 68.313117 -125.815791) (xy 68.37816 -125.820341) (xy 68.442087 -125.833169) (xy 68.50385 -125.854066)
			(xy 68.562434 -125.882688) (xy 68.616878 -125.918565) (xy 68.666287 -125.961109) (xy 68.688458 -125.985016)
			(xy 68.704701 -126.0023) (xy 68.742389 -126.031088) (xy 68.784758 -126.052394) (xy 68.830342 -126.06548)
			(xy 68.877561 -126.069893) (xy 68.92478 -126.06548) (xy 68.970364 -126.052394) (xy 69.012733 -126.031088)
			(xy 69.050421 -126.0023) (xy 69.066664 -125.985016) (xy 69.088666 -125.961282) (xy 69.137665 -125.919003)
			(xy 69.191634 -125.883285) (xy 69.249701 -125.854707) (xy 69.310925 -125.83373) (xy 69.374317 -125.820695)
			(xy 69.438851 -125.815812) (xy 69.503482 -125.819159) (xy 69.567166 -125.830684) (xy 69.628872 -125.850199)
			(xy 69.687601 -125.877389) (xy 69.742405 -125.911813) (xy 69.792395 -125.952916) (xy 69.814948 -125.976126)
			(xy 69.831113 -125.992559) (xy 69.868243 -126.019867) (xy 69.909686 -126.040038) (xy 69.954085 -126.052411)
			(xy 69.999987 -126.056581) (xy 70.045889 -126.052411) (xy 70.090288 -126.040038) (xy 70.131731 -126.019867)
			(xy 70.168861 -125.992559) (xy 70.185026 -125.976126) (xy 70.207219 -125.953147) (xy 70.256487 -125.912475)
			(xy 70.310463 -125.878297) (xy 70.368295 -125.85115) (xy 70.429073 -125.831463) (xy 70.491839 -125.819545)
			(xy 70.555603 -125.815586) (xy 70.619361 -125.819646) (xy 70.682107 -125.831663) (xy 70.742854 -125.851446)
			(xy 70.800643 -125.878684) (xy 70.854565 -125.912948) (xy 70.903769 -125.953698) (xy 70.947479 -126.000291)
			(xy 70.985008 -126.051994) (xy 71.015763 -126.107991) (xy 71.03926 -126.1674) (xy 71.055128 -126.229285)
			(xy 71.063118 -126.29267) (xy 71.063612 -126.324614) (xy 71.063612 -127.233426) (xy 71.063072 -127.26616)
			(xy 71.05464 -127.331084) (xy 71.037946 -127.394389) (xy 71.013264 -127.455027) (xy 70.981004 -127.511996)
			(xy 70.961758 -127.53848) (xy 70.936612 -127.572262) (xy 70.936612 -127.58928) (xy 70.921118 -127.58928)
			(xy 70.885304 -127.61976) (xy 70.860127 -127.640613) (xy 70.805395 -127.676364) (xy 70.74653 -127.704803)
			(xy 70.684505 -127.725458) (xy 70.620343 -127.737989) (xy 70.555104 -127.742189) (xy 70.489865 -127.737989)
			(xy 70.425703 -127.725458) (xy 70.363678 -127.704803) (xy 70.304813 -127.676364) (xy 70.250081 -127.640613)
			(xy 70.224904 -127.61976) (xy 70.18909 -127.58928) (xy 70.173596 -127.58928) (xy 70.173596 -127.572262)
			(xy 70.14845 -127.53848) (xy 70.138202 -127.524638) (xy 70.119389 -127.495784) (xy 70.110858 -127.480822)
			(xy 70.102198 -127.466303) (xy 70.078611 -127.442102) (xy 70.049489 -127.424955) (xy 70.016884 -127.416068)
			(xy 69.98309 -127.416068) (xy 69.950485 -127.424955) (xy 69.921363 -127.442102) (xy 69.897776 -127.466303)
			(xy 69.889116 -127.480822) (xy 69.88058 -127.495781) (xy 69.861767 -127.524634) (xy 69.851524 -127.53848)
			(xy 69.826124 -127.572262) (xy 69.826124 -127.58928) (xy 69.810884 -127.58928) (xy 69.77507 -127.61976)
			(xy 69.749893 -127.640613) (xy 69.695161 -127.676364) (xy 69.636296 -127.704803) (xy 69.574271 -127.725458)
			(xy 69.510109 -127.737989) (xy 69.44487 -127.742189) (xy 69.379631 -127.737989) (xy 69.315469 -127.725458)
			(xy 69.253444 -127.704803) (xy 69.194579 -127.676364) (xy 69.139847 -127.640613) (xy 69.11467 -127.61976)
			(xy 69.078856 -127.58928) (xy 69.063616 -127.58928) (xy 69.063616 -127.572262) (xy 69.038216 -127.53848)
			(xy 69.024959 -127.520365) (xy 69.0013 -127.482211) (xy 68.990972 -127.46228) (xy 68.98356 -127.448534)
			(xy 68.963186 -127.424878) (xy 68.937671 -127.406886) (xy 68.908546 -127.39564) (xy 68.877561 -127.391815)
			(xy 68.846576 -127.39564) (xy 68.817451 -127.406886) (xy 68.791936 -127.424878) (xy 68.771562 -127.448534)
			(xy 68.76415 -127.46228) (xy 68.753841 -127.482222) (xy 68.730185 -127.52038) (xy 68.716906 -127.53848)
			(xy 68.69176 -127.572262) (xy 68.69176 -127.58928) (xy 68.676266 -127.58928) (xy 68.640452 -127.61976)
			(xy 68.615275 -127.640613) (xy 68.560543 -127.676364) (xy 68.501678 -127.704803) (xy 68.439653 -127.725458)
			(xy 68.375491 -127.737989) (xy 68.310252 -127.742189) (xy 68.245013 -127.737989) (xy 68.180851 -127.725458)
			(xy 68.118826 -127.704803) (xy 68.059961 -127.676364) (xy 68.005229 -127.640613) (xy 67.980052 -127.61976)
			(xy 67.944238 -127.58928) (xy 67.928744 -127.58928) (xy 67.928744 -127.572262) (xy 67.903598 -127.53848)
			(xy 67.891792 -127.522401) (xy 67.870429 -127.488709) (xy 67.860926 -127.47117) (xy 67.853355 -127.457846)
			(xy 67.832976 -127.434972) (xy 67.807729 -127.417619) (xy 67.779072 -127.40679) (xy 67.748658 -127.40311)
			(xy 67.718244 -127.40679) (xy 67.689587 -127.417619) (xy 67.66434 -127.434972) (xy 67.643961 -127.457846)
			(xy 67.63639 -127.47117) (xy 67.626896 -127.488714) (xy 67.605536 -127.522409) (xy 67.593718 -127.53848)
			(xy 67.568572 -127.572262) (xy 67.568572 -127.58928) (xy 67.553078 -127.58928) (xy 67.517264 -127.61976)
			(xy 67.492087 -127.640613) (xy 67.437355 -127.676364) (xy 67.37849 -127.704803) (xy 67.316465 -127.725458)
			(xy 67.252303 -127.737989) (xy 67.187064 -127.742189) (xy 67.121825 -127.737989) (xy 67.057663 -127.725458)
			(xy 66.995638 -127.704803) (xy 66.936773 -127.676364) (xy 66.882041 -127.640613) (xy 66.856864 -127.61976)
			(xy 66.82105 -127.58928) (xy 66.805556 -127.58928) (xy 66.805556 -127.572262) (xy 66.78041 -127.53848)
			(xy 66.761145 -127.512009) (xy 66.728885 -127.455037) (xy 66.704204 -127.394395) (xy 66.68751 -127.331088)
			(xy 66.679079 -127.266162) (xy 66.678556 -127.233426) (xy 27.89936 -127.233426) (xy 27.89936 -128.593358)
			(xy 29.519874 -128.593358) (xy 29.519874 -128.506458) (xy 29.527892 -128.419929) (xy 29.54386 -128.334509)
			(xy 29.567641 -128.250927) (xy 29.599033 -128.169895) (xy 29.637767 -128.092106) (xy 29.683514 -128.018222)
			(xy 29.735883 -127.948875) (xy 29.794427 -127.884655) (xy 29.858647 -127.826111) (xy 29.927994 -127.773742)
			(xy 30.001878 -127.727995) (xy 30.079667 -127.689261) (xy 30.160699 -127.657869) (xy 30.244281 -127.634088)
			(xy 30.329701 -127.61812) (xy 30.41623 -127.610102) (xy 30.50313 -127.610102) (xy 30.589659 -127.61812)
			(xy 30.675079 -127.634088) (xy 30.758661 -127.657869) (xy 30.839693 -127.689261) (xy 30.917482 -127.727995)
			(xy 30.991366 -127.773742) (xy 31.060713 -127.826111) (xy 31.124933 -127.884655) (xy 31.183477 -127.948875)
			(xy 31.235846 -128.018222) (xy 31.281593 -128.092106) (xy 31.320327 -128.169895) (xy 31.351719 -128.250927)
			(xy 31.3755 -128.334509) (xy 31.391468 -128.419929) (xy 31.399486 -128.506458) (xy 31.399988 -128.549908)
			(xy 31.399486 -128.593358) (xy 34.599874 -128.593358) (xy 34.599874 -128.506458) (xy 34.607892 -128.419929)
			(xy 34.62386 -128.334509) (xy 34.647641 -128.250927) (xy 34.679033 -128.169895) (xy 34.717767 -128.092106)
			(xy 34.763514 -128.018222) (xy 34.815883 -127.948875) (xy 34.874427 -127.884655) (xy 34.938647 -127.826111)
			(xy 35.007994 -127.773742) (xy 35.081878 -127.727995) (xy 35.159667 -127.689261) (xy 35.240699 -127.657869)
			(xy 35.324281 -127.634088) (xy 35.409701 -127.61812) (xy 35.49623 -127.610102) (xy 35.58313 -127.610102)
			(xy 35.669659 -127.61812) (xy 35.755079 -127.634088) (xy 35.838661 -127.657869) (xy 35.919693 -127.689261)
			(xy 35.997482 -127.727995) (xy 36.071366 -127.773742) (xy 36.140713 -127.826111) (xy 36.144501 -127.829564)
			(xy 51.074828 -127.829564) (xy 52.726336 -127.829564) (xy 52.726336 -128.467593) (xy 57.879918 -128.467593)
			(xy 57.883806 -128.413245) (xy 57.895389 -128.360004) (xy 57.914432 -128.308953) (xy 57.940545 -128.261132)
			(xy 57.973199 -128.217514) (xy 58.011728 -128.178987) (xy 58.055347 -128.146335) (xy 58.10317 -128.120224)
			(xy 58.154222 -128.101184) (xy 58.207463 -128.089604) (xy 58.261811 -128.085718) (xy 58.316159 -128.089607)
			(xy 58.3694 -128.101191) (xy 58.420451 -128.120233) (xy 58.468272 -128.146348) (xy 58.490358 -128.162304)
			(xy 58.50937 -128.1759) (xy 58.551253 -128.196632) (xy 58.596221 -128.209358) (xy 58.642758 -128.213648)
			(xy 58.689295 -128.209358) (xy 58.734263 -128.196632) (xy 58.776146 -128.1759) (xy 58.795158 -128.162304)
			(xy 58.817236 -128.146324) (xy 58.865065 -128.120195) (xy 58.916126 -128.10114) (xy 58.969379 -128.089546)
			(xy 59.023741 -128.085649) (xy 59.078103 -128.089529) (xy 59.13136 -128.101106) (xy 59.182427 -128.120146)
			(xy 59.230265 -128.14626) (xy 59.273898 -128.178917) (xy 59.312439 -128.217452) (xy 59.345104 -128.26108)
			(xy 59.371226 -128.308912) (xy 59.390275 -128.359976) (xy 59.401862 -128.413231) (xy 59.405751 -128.467593)
			(xy 60.120893 -128.467593) (xy 60.124782 -128.413239) (xy 60.136366 -128.359993) (xy 60.155411 -128.308937)
			(xy 60.181529 -128.261111) (xy 60.214187 -128.217489) (xy 60.252721 -128.178959) (xy 60.296347 -128.146306)
			(xy 60.344175 -128.120194) (xy 60.395233 -128.101155) (xy 60.448481 -128.089576) (xy 60.502835 -128.085693)
			(xy 60.557188 -128.089586) (xy 60.610434 -128.101174) (xy 60.661489 -128.120223) (xy 60.709313 -128.146344)
			(xy 60.7314 -128.162304) (xy 60.750412 -128.1759) (xy 60.792295 -128.196632) (xy 60.837263 -128.209358)
			(xy 60.8838 -128.213648) (xy 60.930337 -128.209358) (xy 60.975305 -128.196632) (xy 61.017188 -128.1759)
			(xy 61.0362 -128.162304) (xy 61.058277 -128.146328) (xy 61.106103 -128.120206) (xy 61.15716 -128.101156)
			(xy 61.210409 -128.089567) (xy 61.264765 -128.085674) (xy 61.319121 -128.089557) (xy 61.372372 -128.101136)
			(xy 61.423433 -128.120176) (xy 61.471264 -128.14629) (xy 61.514891 -128.178945) (xy 61.553427 -128.217476)
			(xy 61.586087 -128.261101) (xy 61.612206 -128.308929) (xy 61.631252 -128.359987) (xy 61.642837 -128.413237)
			(xy 61.646726 -128.467593) (xy 62.024903 -128.467593) (xy 62.028791 -128.413242) (xy 62.040375 -128.359997)
			(xy 62.059419 -128.308943) (xy 62.085535 -128.261119) (xy 62.118192 -128.217498) (xy 62.156724 -128.17897)
			(xy 62.200347 -128.146317) (xy 62.248173 -128.120205) (xy 62.299229 -128.101166) (xy 62.352475 -128.089586)
			(xy 62.406826 -128.085703) (xy 62.461177 -128.089594) (xy 62.514421 -128.101181) (xy 62.565474 -128.120227)
			(xy 62.613297 -128.146345) (xy 62.635384 -128.162304) (xy 62.654396 -128.1759) (xy 62.696279 -128.196632)
			(xy 62.741247 -128.209358) (xy 62.787784 -128.213648) (xy 62.834321 -128.209358) (xy 62.879289 -128.196632)
			(xy 62.921172 -128.1759) (xy 62.940184 -128.162304) (xy 62.962261 -128.146327) (xy 63.010089 -128.120202)
			(xy 63.061147 -128.10115) (xy 63.114398 -128.089559) (xy 63.168756 -128.085664) (xy 63.223115 -128.089546)
			(xy 63.276368 -128.101125) (xy 63.327431 -128.120165) (xy 63.375264 -128.146279) (xy 63.418894 -128.178934)
			(xy 63.457432 -128.217467) (xy 63.490094 -128.261093) (xy 63.516214 -128.308922) (xy 63.535261 -128.359983)
			(xy 63.546847 -128.413234) (xy 63.550736 -128.467593) (xy 63.546849 -128.521951) (xy 63.535265 -128.575203)
			(xy 63.51622 -128.626264) (xy 63.490101 -128.674095) (xy 63.457441 -128.717722) (xy 63.418905 -128.756256)
			(xy 63.375276 -128.788914) (xy 63.327444 -128.815029) (xy 63.276381 -128.834071) (xy 63.223129 -128.845652)
			(xy 63.16877 -128.849536) (xy 63.114412 -128.845643) (xy 63.061161 -128.834054) (xy 63.010102 -128.815004)
			(xy 62.962273 -128.788881) (xy 62.940184 -128.77292) (xy 62.921172 -128.759324) (xy 62.879289 -128.738592)
			(xy 62.834321 -128.725866) (xy 62.787784 -128.721576) (xy 62.741247 -128.725866) (xy 62.696279 -128.738592)
			(xy 62.654396 -128.759324) (xy 62.635384 -128.77292) (xy 62.613285 -128.788862) (xy 62.565461 -128.814979)
			(xy 62.514407 -128.834024) (xy 62.461163 -128.845608) (xy 62.406812 -128.849497) (xy 62.35246 -128.845612)
			(xy 62.299215 -128.83403) (xy 62.24816 -128.814989) (xy 62.200335 -128.788875) (xy 62.156713 -128.756221)
			(xy 62.118182 -128.717691) (xy 62.085527 -128.674069) (xy 62.059413 -128.626244) (xy 62.040371 -128.575189)
			(xy 62.028789 -128.521944) (xy 62.024903 -128.467593) (xy 61.646726 -128.467593) (xy 61.642839 -128.521949)
			(xy 61.631256 -128.575199) (xy 61.612212 -128.626258) (xy 61.586095 -128.674087) (xy 61.553437 -128.717713)
			(xy 61.514902 -128.756246) (xy 61.471276 -128.788902) (xy 61.423446 -128.815018) (xy 61.372386 -128.83406)
			(xy 61.319136 -128.845641) (xy 61.264779 -128.849526) (xy 61.210423 -128.845635) (xy 61.157174 -128.834048)
			(xy 61.106116 -128.815) (xy 61.058289 -128.78888) (xy 61.0362 -128.77292) (xy 61.017188 -128.759324)
			(xy 60.975305 -128.738592) (xy 60.930337 -128.725866) (xy 60.8838 -128.721576) (xy 60.837263 -128.725866)
			(xy 60.792295 -128.738592) (xy 60.750412 -128.759324) (xy 60.7314 -128.77292) (xy 60.709301 -128.788864)
			(xy 60.661476 -128.814983) (xy 60.61042 -128.83403) (xy 60.557174 -128.845616) (xy 60.502821 -128.849507)
			(xy 60.448467 -128.845622) (xy 60.395219 -128.834041) (xy 60.344162 -128.815) (xy 60.296334 -128.788886)
			(xy 60.25271 -128.756231) (xy 60.214178 -128.7177) (xy 60.181521 -128.674077) (xy 60.155405 -128.62625)
			(xy 60.136362 -128.575194) (xy 60.12478 -128.521946) (xy 60.120893 -128.467593) (xy 59.405751 -128.467593)
			(xy 59.401864 -128.521955) (xy 59.390279 -128.57521) (xy 59.371232 -128.626275) (xy 59.345112 -128.674108)
			(xy 59.312449 -128.717737) (xy 59.273909 -128.756273) (xy 59.230277 -128.788932) (xy 59.18244 -128.815048)
			(xy 59.131374 -128.83409) (xy 59.078118 -128.845669) (xy 59.023755 -128.849551) (xy 58.969394 -128.845657)
			(xy 58.91614 -128.834064) (xy 58.865078 -128.815011) (xy 58.817248 -128.788883) (xy 58.795158 -128.77292)
			(xy 58.776146 -128.759324) (xy 58.734263 -128.738592) (xy 58.689295 -128.725866) (xy 58.642758 -128.721576)
			(xy 58.596221 -128.725866) (xy 58.551253 -128.738592) (xy 58.50937 -128.759324) (xy 58.490358 -128.77292)
			(xy 58.46826 -128.78886) (xy 58.420438 -128.814973) (xy 58.369386 -128.834013) (xy 58.316145 -128.845595)
			(xy 58.261797 -128.849482) (xy 58.207449 -128.845594) (xy 58.154208 -128.834012) (xy 58.103157 -128.81497)
			(xy 58.055335 -128.788857) (xy 58.011717 -128.756204) (xy 57.97319 -128.717675) (xy 57.940538 -128.674056)
			(xy 57.914426 -128.626234) (xy 57.895385 -128.575182) (xy 57.883804 -128.521941) (xy 57.879918 -128.467593)
			(xy 52.726336 -128.467593) (xy 52.726336 -129.481072) (xy 51.074828 -129.481072) (xy 51.074828 -127.829564)
			(xy 36.144501 -127.829564) (xy 36.204933 -127.884655) (xy 36.263477 -127.948875) (xy 36.315846 -128.018222)
			(xy 36.361593 -128.092106) (xy 36.400327 -128.169895) (xy 36.431719 -128.250927) (xy 36.4555 -128.334509)
			(xy 36.471468 -128.419929) (xy 36.479486 -128.506458) (xy 36.479988 -128.549908) (xy 36.479486 -128.593358)
			(xy 36.476285 -128.627908) (xy 39.307881 -128.627908) (xy 39.311767 -128.573554) (xy 39.32335 -128.520305)
			(xy 39.342393 -128.469248) (xy 39.368508 -128.42142) (xy 39.401165 -128.377795) (xy 39.439698 -128.339263)
			(xy 39.483322 -128.306607) (xy 39.531151 -128.280491) (xy 39.582209 -128.261449) (xy 39.635457 -128.249867)
			(xy 39.689812 -128.245981) (xy 39.744166 -128.24987) (xy 39.797414 -128.261455) (xy 39.848471 -128.280501)
			(xy 39.896297 -128.306619) (xy 39.918386 -128.322578) (xy 39.937398 -128.336174) (xy 39.979281 -128.356906)
			(xy 40.024249 -128.369632) (xy 40.070786 -128.373922) (xy 40.117323 -128.369632) (xy 40.162291 -128.356906)
			(xy 40.204174 -128.336174) (xy 40.223186 -128.322578) (xy 40.245288 -128.306636) (xy 40.293113 -128.280515)
			(xy 40.34417 -128.261466) (xy 40.397417 -128.249878) (xy 40.451772 -128.245986) (xy 40.506128 -128.24987)
			(xy 40.559377 -128.261451) (xy 40.610437 -128.280492) (xy 40.658266 -128.306606) (xy 40.701892 -128.339262)
			(xy 40.740426 -128.377794) (xy 40.773084 -128.421418) (xy 40.7992 -128.469246) (xy 40.818244 -128.520304)
			(xy 40.829827 -128.573553) (xy 40.833714 -128.627908) (xy 40.829825 -128.682264) (xy 40.826864 -128.695873)
			(xy 47.574952 -128.695873) (xy 47.574952 -128.614763) (xy 47.582902 -128.534044) (xy 47.598725 -128.454493)
			(xy 47.62227 -128.376877) (xy 47.653309 -128.301941) (xy 47.691544 -128.230409) (xy 47.736606 -128.162969)
			(xy 47.788061 -128.10027) (xy 47.845414 -128.042917) (xy 47.908113 -127.991462) (xy 47.975553 -127.9464)
			(xy 48.047085 -127.908165) (xy 48.122021 -127.877126) (xy 48.199637 -127.853581) (xy 48.279188 -127.837758)
			(xy 48.359907 -127.829808) (xy 48.441017 -127.829808) (xy 48.521736 -127.837758) (xy 48.601287 -127.853581)
			(xy 48.678903 -127.877126) (xy 48.753839 -127.908165) (xy 48.825371 -127.9464) (xy 48.892811 -127.991462)
			(xy 48.95551 -128.042917) (xy 49.012863 -128.10027) (xy 49.064318 -128.162969) (xy 49.10938 -128.230409)
			(xy 49.147615 -128.301941) (xy 49.178654 -128.376877) (xy 49.202199 -128.454493) (xy 49.218022 -128.534044)
			(xy 49.225972 -128.614763) (xy 49.22647 -128.655318) (xy 49.225972 -128.695873) (xy 49.218022 -128.776592)
			(xy 49.202199 -128.856143) (xy 49.178654 -128.933759) (xy 49.147615 -129.008695) (xy 49.10938 -129.080227)
			(xy 49.064318 -129.147667) (xy 49.012863 -129.210366) (xy 48.95551 -129.267719) (xy 48.892811 -129.319174)
			(xy 48.825371 -129.364236) (xy 48.753839 -129.402471) (xy 48.678903 -129.43351) (xy 48.601287 -129.457055)
			(xy 48.521736 -129.472878) (xy 48.441017 -129.480828) (xy 48.359907 -129.480828) (xy 48.279188 -129.472878)
			(xy 48.199637 -129.457055) (xy 48.122021 -129.43351) (xy 48.047085 -129.402471) (xy 47.975553 -129.364236)
			(xy 47.908113 -129.319174) (xy 47.845414 -129.267719) (xy 47.788061 -129.210366) (xy 47.736606 -129.147667)
			(xy 47.691544 -129.080227) (xy 47.653309 -129.008695) (xy 47.62227 -128.933759) (xy 47.598725 -128.856143)
			(xy 47.582902 -128.776592) (xy 47.574952 -128.695873) (xy 40.826864 -128.695873) (xy 40.818239 -128.735512)
			(xy 40.799193 -128.786569) (xy 40.773075 -128.834396) (xy 40.740415 -128.878019) (xy 40.701879 -128.916549)
			(xy 40.658252 -128.949203) (xy 40.610421 -128.975315) (xy 40.559361 -128.994354) (xy 40.506111 -129.005932)
			(xy 40.451756 -129.009814) (xy 40.397401 -129.00592) (xy 40.344154 -128.994329) (xy 40.293098 -128.975278)
			(xy 40.245273 -128.949155) (xy 40.223186 -128.933194) (xy 40.204174 -128.919598) (xy 40.162291 -128.898866)
			(xy 40.117323 -128.88614) (xy 40.070786 -128.88185) (xy 40.024249 -128.88614) (xy 39.979281 -128.898866)
			(xy 39.937398 -128.919598) (xy 39.918386 -128.933194) (xy 39.896311 -128.949172) (xy 39.848486 -128.975292)
			(xy 39.79743 -128.99434) (xy 39.744183 -129.005928) (xy 39.689828 -129.009819) (xy 39.635474 -129.005936)
			(xy 39.582225 -128.994356) (xy 39.531166 -128.975316) (xy 39.483337 -128.949202) (xy 39.439711 -128.916548)
			(xy 39.401176 -128.878017) (xy 39.368517 -128.834394) (xy 39.3424 -128.786568) (xy 39.323354 -128.735511)
			(xy 39.31177 -128.682263) (xy 39.307881 -128.627908) (xy 36.476285 -128.627908) (xy 36.471468 -128.679887)
			(xy 36.4555 -128.765307) (xy 36.431719 -128.848889) (xy 36.400327 -128.929921) (xy 36.361593 -129.00771)
			(xy 36.315846 -129.081594) (xy 36.263477 -129.150941) (xy 36.204933 -129.215161) (xy 36.140713 -129.273705)
			(xy 36.071366 -129.326074) (xy 35.997482 -129.371821) (xy 35.919693 -129.410555) (xy 35.838661 -129.441947)
			(xy 35.755079 -129.465728) (xy 35.669659 -129.481696) (xy 35.58313 -129.489714) (xy 35.49623 -129.489714)
			(xy 35.409701 -129.481696) (xy 35.324281 -129.465728) (xy 35.240699 -129.441947) (xy 35.159667 -129.410555)
			(xy 35.081878 -129.371821) (xy 35.007994 -129.326074) (xy 34.938647 -129.273705) (xy 34.874427 -129.215161)
			(xy 34.815883 -129.150941) (xy 34.763514 -129.081594) (xy 34.717767 -129.00771) (xy 34.679033 -128.929921)
			(xy 34.647641 -128.848889) (xy 34.62386 -128.765307) (xy 34.607892 -128.679887) (xy 34.599874 -128.593358)
			(xy 31.399486 -128.593358) (xy 31.391468 -128.679887) (xy 31.3755 -128.765307) (xy 31.351719 -128.848889)
			(xy 31.320327 -128.929921) (xy 31.281593 -129.00771) (xy 31.235846 -129.081594) (xy 31.183477 -129.150941)
			(xy 31.124933 -129.215161) (xy 31.060713 -129.273705) (xy 30.991366 -129.326074) (xy 30.917482 -129.371821)
			(xy 30.839693 -129.410555) (xy 30.758661 -129.441947) (xy 30.675079 -129.465728) (xy 30.589659 -129.481696)
			(xy 30.50313 -129.489714) (xy 30.41623 -129.489714) (xy 30.329701 -129.481696) (xy 30.244281 -129.465728)
			(xy 30.160699 -129.441947) (xy 30.079667 -129.410555) (xy 30.001878 -129.371821) (xy 29.927994 -129.326074)
			(xy 29.858647 -129.273705) (xy 29.794427 -129.215161) (xy 29.735883 -129.150941) (xy 29.683514 -129.081594)
			(xy 29.637767 -129.00771) (xy 29.599033 -128.929921) (xy 29.567641 -128.848889) (xy 29.54386 -128.765307)
			(xy 29.527892 -128.679887) (xy 29.519874 -128.593358) (xy 27.89936 -128.593358) (xy 27.89936 -131.133358)
			(xy 29.519874 -131.133358) (xy 29.519874 -131.046458) (xy 29.527892 -130.959929) (xy 29.54386 -130.874509)
			(xy 29.567641 -130.790927) (xy 29.599033 -130.709895) (xy 29.637767 -130.632106) (xy 29.683514 -130.558222)
			(xy 29.735883 -130.488875) (xy 29.794427 -130.424655) (xy 29.858647 -130.366111) (xy 29.927994 -130.313742)
			(xy 30.001878 -130.267995) (xy 30.079667 -130.229261) (xy 30.160699 -130.197869) (xy 30.244281 -130.174088)
			(xy 30.329701 -130.15812) (xy 30.41623 -130.150102) (xy 30.50313 -130.150102) (xy 30.589659 -130.15812)
			(xy 30.675079 -130.174088) (xy 30.758661 -130.197869) (xy 30.839693 -130.229261) (xy 30.917482 -130.267995)
			(xy 30.991366 -130.313742) (xy 31.060713 -130.366111) (xy 31.124933 -130.424655) (xy 31.183477 -130.488875)
			(xy 31.235846 -130.558222) (xy 31.281593 -130.632106) (xy 31.320327 -130.709895) (xy 31.351719 -130.790927)
			(xy 31.3755 -130.874509) (xy 31.391468 -130.959929) (xy 31.399486 -131.046458) (xy 31.399988 -131.089908)
			(xy 31.399486 -131.133358) (xy 34.599874 -131.133358) (xy 34.599874 -131.046458) (xy 34.607892 -130.959929)
			(xy 34.62386 -130.874509) (xy 34.647641 -130.790927) (xy 34.679033 -130.709895) (xy 34.717767 -130.632106)
			(xy 34.763514 -130.558222) (xy 34.815883 -130.488875) (xy 34.874427 -130.424655) (xy 34.938647 -130.366111)
			(xy 35.007994 -130.313742) (xy 35.081878 -130.267995) (xy 35.159667 -130.229261) (xy 35.240699 -130.197869)
			(xy 35.324281 -130.174088) (xy 35.409701 -130.15812) (xy 35.49623 -130.150102) (xy 35.58313 -130.150102)
			(xy 35.669659 -130.15812) (xy 35.755079 -130.174088) (xy 35.838661 -130.197869) (xy 35.919693 -130.229261)
			(xy 35.997482 -130.267995) (xy 36.071366 -130.313742) (xy 36.140713 -130.366111) (xy 36.204933 -130.424655)
			(xy 36.263477 -130.488875) (xy 36.300343 -130.537693) (xy 39.307901 -130.537693) (xy 39.31179 -130.483341)
			(xy 39.323374 -130.430096) (xy 39.342418 -130.379042) (xy 39.368534 -130.331218) (xy 39.401191 -130.287597)
			(xy 39.439723 -130.249068) (xy 39.483347 -130.216416) (xy 39.531173 -130.190304) (xy 39.582229 -130.171264)
			(xy 39.635475 -130.159685) (xy 39.689827 -130.155801) (xy 39.744179 -130.159693) (xy 39.797423 -130.17128)
			(xy 39.848476 -130.190326) (xy 39.896299 -130.216445) (xy 39.918386 -130.232404) (xy 39.937398 -130.246)
			(xy 39.979281 -130.266732) (xy 40.024249 -130.279458) (xy 40.070786 -130.283748) (xy 40.117323 -130.279458)
			(xy 40.162291 -130.266732) (xy 40.204174 -130.246) (xy 40.223186 -130.232404) (xy 40.245263 -130.216427)
			(xy 40.29309 -130.190302) (xy 40.344149 -130.171251) (xy 40.397399 -130.15966) (xy 40.451757 -130.155765)
			(xy 40.506115 -130.159647) (xy 40.559368 -130.171226) (xy 40.610431 -130.190266) (xy 40.658264 -130.21638)
			(xy 40.701894 -130.249036) (xy 40.740431 -130.287568) (xy 40.773093 -130.331194) (xy 40.798314 -130.377377)
			(xy 57.879939 -130.377377) (xy 57.883829 -130.323033) (xy 57.895414 -130.269795) (xy 57.914457 -130.218747)
			(xy 57.940571 -130.17093) (xy 57.973225 -130.127316) (xy 58.011753 -130.088792) (xy 58.055372 -130.056144)
			(xy 58.103193 -130.030036) (xy 58.154242 -130.011) (xy 58.207482 -129.999422) (xy 58.261827 -129.995539)
			(xy 58.316172 -129.99943) (xy 58.369409 -130.011015) (xy 58.420456 -130.030059) (xy 58.468274 -130.056174)
			(xy 58.490358 -130.07213) (xy 58.50937 -130.085726) (xy 58.551253 -130.106458) (xy 58.596221 -130.119184)
			(xy 58.642758 -130.123474) (xy 58.689295 -130.119184) (xy 58.734263 -130.106458) (xy 58.776146 -130.085726)
			(xy 58.795158 -130.07213) (xy 58.817212 -130.056115) (xy 58.865042 -130.029983) (xy 58.916105 -130.010924)
			(xy 58.969361 -129.999327) (xy 59.023725 -129.995428) (xy 59.078091 -129.999306) (xy 59.131351 -130.010882)
			(xy 59.182422 -130.029921) (xy 59.230263 -130.056034) (xy 59.2739 -130.088691) (xy 59.312445 -130.127226)
			(xy 59.345113 -130.170855) (xy 59.371239 -130.218689) (xy 59.39029 -130.269755) (xy 59.40188 -130.323012)
			(xy 59.405772 -130.377377) (xy 60.120914 -130.377377) (xy 60.124805 -130.323027) (xy 60.136391 -130.269783)
			(xy 60.155437 -130.218731) (xy 60.181555 -130.170909) (xy 60.214213 -130.127291) (xy 60.252747 -130.088765)
			(xy 60.296371 -130.056115) (xy 60.344198 -130.030006) (xy 60.395254 -130.01097) (xy 60.4485 -129.999394)
			(xy 60.502851 -129.995514) (xy 60.557201 -129.999409) (xy 60.610443 -130.010999) (xy 60.661494 -130.030048)
			(xy 60.709315 -130.05617) (xy 60.7314 -130.07213) (xy 60.750412 -130.085726) (xy 60.792295 -130.106458)
			(xy 60.837263 -130.119184) (xy 60.8838 -130.123474) (xy 60.930337 -130.119184) (xy 60.975305 -130.106458)
			(xy 61.017188 -130.085726) (xy 61.0362 -130.07213) (xy 61.058253 -130.056119) (xy 61.10608 -130.029993)
			(xy 61.157139 -130.01094) (xy 61.21039 -129.999348) (xy 61.264749 -129.995453) (xy 61.319109 -129.999334)
			(xy 61.372363 -130.010912) (xy 61.423427 -130.029951) (xy 61.471262 -130.056064) (xy 61.514893 -130.088719)
			(xy 61.553433 -130.127251) (xy 61.586096 -130.170876) (xy 61.612219 -130.218706) (xy 61.631268 -130.269766)
			(xy 61.642856 -130.323018) (xy 61.646747 -130.377377) (xy 62.024923 -130.377377) (xy 62.028814 -130.323029)
			(xy 62.0404 -130.269788) (xy 62.059445 -130.218737) (xy 62.085561 -130.170917) (xy 62.118218 -130.1273)
			(xy 62.156749 -130.088775) (xy 62.200371 -130.056126) (xy 62.248196 -130.030018) (xy 62.29925 -130.010981)
			(xy 62.352493 -129.999405) (xy 62.406842 -129.995523) (xy 62.46119 -129.999417) (xy 62.51443 -130.011005)
			(xy 62.56548 -130.030052) (xy 62.613299 -130.056171) (xy 62.635384 -130.07213) (xy 62.654396 -130.085726)
			(xy 62.696279 -130.106458) (xy 62.741247 -130.119184) (xy 62.787784 -130.123474) (xy 62.834321 -130.119184)
			(xy 62.879289 -130.106458) (xy 62.921172 -130.085726) (xy 62.940184 -130.07213) (xy 62.962237 -130.056117)
			(xy 63.010066 -130.029989) (xy 63.061126 -130.010934) (xy 63.114379 -129.99934) (xy 63.16874 -129.995443)
			(xy 63.223102 -129.999323) (xy 63.276359 -130.0109) (xy 63.327425 -130.029939) (xy 63.375262 -130.056053)
			(xy 63.418896 -130.088708) (xy 63.457437 -130.127242) (xy 63.490103 -130.170868) (xy 63.516226 -130.2187)
			(xy 63.535276 -130.269762) (xy 63.546865 -130.323016) (xy 63.550757 -130.377377) (xy 63.546872 -130.431739)
			(xy 63.535289 -130.484994) (xy 63.516245 -130.536059) (xy 63.490127 -130.583893) (xy 63.457467 -130.627524)
			(xy 63.41893 -130.666062) (xy 63.375301 -130.698723) (xy 63.327467 -130.724842) (xy 63.276402 -130.743887)
			(xy 63.223147 -130.75547) (xy 63.168786 -130.759357) (xy 63.114424 -130.755466) (xy 63.06117 -130.743879)
			(xy 63.010107 -130.72483) (xy 62.962275 -130.698707) (xy 62.940184 -130.682746) (xy 62.921172 -130.66915)
			(xy 62.879289 -130.648418) (xy 62.834321 -130.635692) (xy 62.787784 -130.631402) (xy 62.741247 -130.635692)
			(xy 62.696279 -130.648418) (xy 62.654396 -130.66915) (xy 62.635384 -130.682746) (xy 62.613261 -130.698653)
			(xy 62.565438 -130.724767) (xy 62.514387 -130.743808) (xy 62.461145 -130.75539) (xy 62.406796 -130.759277)
			(xy 62.352448 -130.755389) (xy 62.299206 -130.743806) (xy 62.248155 -130.724763) (xy 62.200333 -130.698649)
			(xy 62.156715 -130.665995) (xy 62.118188 -130.627465) (xy 62.085536 -130.583845) (xy 62.059426 -130.536021)
			(xy 62.040387 -130.484968) (xy 62.028807 -130.431726) (xy 62.024923 -130.377377) (xy 61.646747 -130.377377)
			(xy 61.642862 -130.431737) (xy 61.63128 -130.48499) (xy 61.612237 -130.536053) (xy 61.586121 -130.583885)
			(xy 61.553463 -130.627514) (xy 61.514928 -130.666051) (xy 61.4713 -130.698712) (xy 61.423469 -130.72483)
			(xy 61.372407 -130.743875) (xy 61.319154 -130.75546) (xy 61.264795 -130.759347) (xy 61.210436 -130.755458)
			(xy 61.157183 -130.743872) (xy 61.106122 -130.724826) (xy 61.058291 -130.698706) (xy 61.0362 -130.682746)
			(xy 61.017188 -130.66915) (xy 60.975305 -130.648418) (xy 60.930337 -130.635692) (xy 60.8838 -130.631402)
			(xy 60.837263 -130.635692) (xy 60.792295 -130.648418) (xy 60.750412 -130.66915) (xy 60.7314 -130.682746)
			(xy 60.709276 -130.698655) (xy 60.661453 -130.72477) (xy 60.6104 -130.743814) (xy 60.557156 -130.755398)
			(xy 60.502805 -130.759286) (xy 60.448455 -130.755399) (xy 60.39521 -130.743817) (xy 60.344157 -130.724775)
			(xy 60.296333 -130.69866) (xy 60.252712 -130.666005) (xy 60.214183 -130.627475) (xy 60.18153 -130.583853)
			(xy 60.155418 -130.536027) (xy 60.136378 -130.484973) (xy 60.124798 -130.431728) (xy 60.120914 -130.377377)
			(xy 59.405772 -130.377377) (xy 59.401887 -130.431742) (xy 59.390303 -130.485001) (xy 59.371258 -130.536069)
			(xy 59.345138 -130.583906) (xy 59.312475 -130.627539) (xy 59.273934 -130.666079) (xy 59.230301 -130.698741)
			(xy 59.182463 -130.72486) (xy 59.131395 -130.743905) (xy 59.078136 -130.755488) (xy 59.023771 -130.759372)
			(xy 58.969406 -130.755479) (xy 58.916149 -130.743889) (xy 58.865084 -130.724836) (xy 58.81725 -130.698709)
			(xy 58.795158 -130.682746) (xy 58.776146 -130.66915) (xy 58.734263 -130.648418) (xy 58.689295 -130.635692)
			(xy 58.642758 -130.631402) (xy 58.596221 -130.635692) (xy 58.551253 -130.648418) (xy 58.50937 -130.66915)
			(xy 58.490358 -130.682746) (xy 58.468235 -130.698651) (xy 58.420415 -130.72476) (xy 58.369365 -130.743798)
			(xy 58.316126 -130.755377) (xy 58.261781 -130.759261) (xy 58.207437 -130.755371) (xy 58.154199 -130.743787)
			(xy 58.103151 -130.724745) (xy 58.055333 -130.698631) (xy 58.011719 -130.665978) (xy 57.973195 -130.62745)
			(xy 57.940547 -130.583832) (xy 57.914438 -130.536011) (xy 57.895401 -130.484962) (xy 57.883823 -130.431722)
			(xy 57.879939 -130.377377) (xy 40.798314 -130.377377) (xy 40.799213 -130.379023) (xy 40.81826 -130.430083)
			(xy 40.829845 -130.483335) (xy 40.833735 -130.537693) (xy 40.829848 -130.592051) (xy 40.818264 -130.645303)
			(xy 40.799219 -130.696364) (xy 40.773101 -130.744194) (xy 40.740441 -130.787821) (xy 40.701905 -130.826355)
			(xy 40.658276 -130.859012) (xy 40.610444 -130.885128) (xy 40.559382 -130.90417) (xy 40.50613 -130.915751)
			(xy 40.451771 -130.919635) (xy 40.397413 -130.915742) (xy 40.344163 -130.904154) (xy 40.293104 -130.885104)
			(xy 40.245275 -130.858981) (xy 40.223186 -130.84302) (xy 40.204174 -130.829424) (xy 40.162291 -130.808692)
			(xy 40.117323 -130.795966) (xy 40.070786 -130.791676) (xy 40.024249 -130.795966) (xy 39.979281 -130.808692)
			(xy 39.937398 -130.829424) (xy 39.918386 -130.84302) (xy 39.896287 -130.858963) (xy 39.848463 -130.885079)
			(xy 39.797409 -130.904124) (xy 39.744164 -130.915709) (xy 39.689813 -130.919599) (xy 39.635461 -130.915713)
			(xy 39.582216 -130.904132) (xy 39.53116 -130.88509) (xy 39.483335 -130.858976) (xy 39.439712 -130.826322)
			(xy 39.401182 -130.787792) (xy 39.368527 -130.74417) (xy 39.342412 -130.696345) (xy 39.32337 -130.64529)
			(xy 39.311788 -130.592045) (xy 39.307901 -130.537693) (xy 36.300343 -130.537693) (xy 36.315846 -130.558222)
			(xy 36.361593 -130.632106) (xy 36.400327 -130.709895) (xy 36.431719 -130.790927) (xy 36.4555 -130.874509)
			(xy 36.471468 -130.959929) (xy 36.479486 -131.046458) (xy 36.479988 -131.089908) (xy 36.479486 -131.133358)
			(xy 36.471468 -131.219887) (xy 36.4555 -131.305307) (xy 36.431719 -131.388889) (xy 36.400327 -131.469921)
			(xy 36.361593 -131.54771) (xy 36.315846 -131.621594) (xy 36.263477 -131.690941) (xy 36.204933 -131.755161)
			(xy 36.140713 -131.813705) (xy 36.071366 -131.866074) (xy 35.997482 -131.911821) (xy 35.919693 -131.950555)
			(xy 35.838661 -131.981947) (xy 35.755079 -132.005728) (xy 35.669659 -132.021696) (xy 35.58313 -132.029714)
			(xy 35.49623 -132.029714) (xy 35.409701 -132.021696) (xy 35.324281 -132.005728) (xy 35.240699 -131.981947)
			(xy 35.159667 -131.950555) (xy 35.081878 -131.911821) (xy 35.007994 -131.866074) (xy 34.938647 -131.813705)
			(xy 34.874427 -131.755161) (xy 34.815883 -131.690941) (xy 34.763514 -131.621594) (xy 34.717767 -131.54771)
			(xy 34.679033 -131.469921) (xy 34.647641 -131.388889) (xy 34.62386 -131.305307) (xy 34.607892 -131.219887)
			(xy 34.599874 -131.133358) (xy 31.399486 -131.133358) (xy 31.391468 -131.219887) (xy 31.3755 -131.305307)
			(xy 31.351719 -131.388889) (xy 31.320327 -131.469921) (xy 31.281593 -131.54771) (xy 31.235846 -131.621594)
			(xy 31.183477 -131.690941) (xy 31.124933 -131.755161) (xy 31.060713 -131.813705) (xy 30.991366 -131.866074)
			(xy 30.917482 -131.911821) (xy 30.839693 -131.950555) (xy 30.758661 -131.981947) (xy 30.675079 -132.005728)
			(xy 30.589659 -132.021696) (xy 30.50313 -132.029714) (xy 30.41623 -132.029714) (xy 30.329701 -132.021696)
			(xy 30.244281 -132.005728) (xy 30.160699 -131.981947) (xy 30.079667 -131.950555) (xy 30.001878 -131.911821)
			(xy 29.927994 -131.866074) (xy 29.858647 -131.813705) (xy 29.794427 -131.755161) (xy 29.735883 -131.690941)
			(xy 29.683514 -131.621594) (xy 29.637767 -131.54771) (xy 29.599033 -131.469921) (xy 29.567641 -131.388889)
			(xy 29.54386 -131.305307) (xy 29.527892 -131.219887) (xy 29.519874 -131.133358) (xy 27.89936 -131.133358)
			(xy 27.89936 -133.673358) (xy 29.519874 -133.673358) (xy 29.519874 -133.586458) (xy 29.527892 -133.499929)
			(xy 29.54386 -133.414509) (xy 29.567641 -133.330927) (xy 29.599033 -133.249895) (xy 29.637767 -133.172106)
			(xy 29.683514 -133.098222) (xy 29.735883 -133.028875) (xy 29.794427 -132.964655) (xy 29.858647 -132.906111)
			(xy 29.927994 -132.853742) (xy 30.001878 -132.807995) (xy 30.079667 -132.769261) (xy 30.160699 -132.737869)
			(xy 30.244281 -132.714088) (xy 30.329701 -132.69812) (xy 30.41623 -132.690102) (xy 30.50313 -132.690102)
			(xy 30.589659 -132.69812) (xy 30.675079 -132.714088) (xy 30.758661 -132.737869) (xy 30.839693 -132.769261)
			(xy 30.917482 -132.807995) (xy 30.991366 -132.853742) (xy 31.060713 -132.906111) (xy 31.124933 -132.964655)
			(xy 31.183477 -133.028875) (xy 31.235846 -133.098222) (xy 31.281593 -133.172106) (xy 31.320327 -133.249895)
			(xy 31.351719 -133.330927) (xy 31.3755 -133.414509) (xy 31.391468 -133.499929) (xy 31.399486 -133.586458)
			(xy 31.399988 -133.629908) (xy 31.399486 -133.673358) (xy 34.599874 -133.673358) (xy 34.599874 -133.586458)
			(xy 34.607892 -133.499929) (xy 34.62386 -133.414509) (xy 34.647641 -133.330927) (xy 34.679033 -133.249895)
			(xy 34.717767 -133.172106) (xy 34.763514 -133.098222) (xy 34.815883 -133.028875) (xy 34.874427 -132.964655)
			(xy 34.938647 -132.906111) (xy 35.007994 -132.853742) (xy 35.081878 -132.807995) (xy 35.159667 -132.769261)
			(xy 35.240699 -132.737869) (xy 35.324281 -132.714088) (xy 35.409701 -132.69812) (xy 35.49623 -132.690102)
			(xy 35.58313 -132.690102) (xy 35.669659 -132.69812) (xy 35.755079 -132.714088) (xy 35.838661 -132.737869)
			(xy 35.919693 -132.769261) (xy 35.997482 -132.807995) (xy 36.071366 -132.853742) (xy 36.140713 -132.906111)
			(xy 36.204933 -132.964655) (xy 36.263477 -133.028875) (xy 36.315846 -133.098222) (xy 36.361593 -133.172106)
			(xy 36.400327 -133.249895) (xy 36.431719 -133.330927) (xy 36.4555 -133.414509) (xy 36.471468 -133.499929)
			(xy 36.479486 -133.586458) (xy 36.479988 -133.629908) (xy 36.479486 -133.673358) (xy 36.471468 -133.759887)
			(xy 36.4555 -133.845307) (xy 36.431719 -133.928889) (xy 36.400327 -134.009921) (xy 36.361593 -134.08771)
			(xy 36.315846 -134.161594) (xy 36.263477 -134.230941) (xy 36.204933 -134.295161) (xy 36.140713 -134.353705)
			(xy 36.071366 -134.406074) (xy 35.997482 -134.451821) (xy 35.919693 -134.490555) (xy 35.838661 -134.521947)
			(xy 35.755079 -134.545728) (xy 35.669659 -134.561696) (xy 35.58313 -134.569714) (xy 35.49623 -134.569714)
			(xy 35.409701 -134.561696) (xy 35.324281 -134.545728) (xy 35.240699 -134.521947) (xy 35.159667 -134.490555)
			(xy 35.081878 -134.451821) (xy 35.007994 -134.406074) (xy 34.938647 -134.353705) (xy 34.874427 -134.295161)
			(xy 34.815883 -134.230941) (xy 34.763514 -134.161594) (xy 34.717767 -134.08771) (xy 34.679033 -134.009921)
			(xy 34.647641 -133.928889) (xy 34.62386 -133.845307) (xy 34.607892 -133.759887) (xy 34.599874 -133.673358)
			(xy 31.399486 -133.673358) (xy 31.391468 -133.759887) (xy 31.3755 -133.845307) (xy 31.351719 -133.928889)
			(xy 31.320327 -134.009921) (xy 31.281593 -134.08771) (xy 31.235846 -134.161594) (xy 31.183477 -134.230941)
			(xy 31.124933 -134.295161) (xy 31.060713 -134.353705) (xy 30.991366 -134.406074) (xy 30.917482 -134.451821)
			(xy 30.839693 -134.490555) (xy 30.758661 -134.521947) (xy 30.675079 -134.545728) (xy 30.589659 -134.561696)
			(xy 30.50313 -134.569714) (xy 30.41623 -134.569714) (xy 30.329701 -134.561696) (xy 30.244281 -134.545728)
			(xy 30.160699 -134.521947) (xy 30.079667 -134.490555) (xy 30.001878 -134.451821) (xy 29.927994 -134.406074)
			(xy 29.858647 -134.353705) (xy 29.794427 -134.295161) (xy 29.735883 -134.230941) (xy 29.683514 -134.161594)
			(xy 29.637767 -134.08771) (xy 29.599033 -134.009921) (xy 29.567641 -133.928889) (xy 29.54386 -133.845307)
			(xy 29.527892 -133.759887) (xy 29.519874 -133.673358) (xy 27.89936 -133.673358) (xy 27.89936 -136.213358)
			(xy 29.519874 -136.213358) (xy 29.519874 -136.126458) (xy 29.527892 -136.039929) (xy 29.54386 -135.954509)
			(xy 29.567641 -135.870927) (xy 29.599033 -135.789895) (xy 29.637767 -135.712106) (xy 29.683514 -135.638222)
			(xy 29.735883 -135.568875) (xy 29.794427 -135.504655) (xy 29.858647 -135.446111) (xy 29.927994 -135.393742)
			(xy 30.001878 -135.347995) (xy 30.079667 -135.309261) (xy 30.160699 -135.277869) (xy 30.244281 -135.254088)
			(xy 30.329701 -135.23812) (xy 30.41623 -135.230102) (xy 30.50313 -135.230102) (xy 30.589659 -135.23812)
			(xy 30.675079 -135.254088) (xy 30.758661 -135.277869) (xy 30.839693 -135.309261) (xy 30.917482 -135.347995)
			(xy 30.991366 -135.393742) (xy 31.060713 -135.446111) (xy 31.124933 -135.504655) (xy 31.183477 -135.568875)
			(xy 31.235846 -135.638222) (xy 31.281593 -135.712106) (xy 31.320327 -135.789895) (xy 31.351719 -135.870927)
			(xy 31.3755 -135.954509) (xy 31.391468 -136.039929) (xy 31.399486 -136.126458) (xy 31.399988 -136.169908)
			(xy 31.399486 -136.213358) (xy 34.599874 -136.213358) (xy 34.599874 -136.126458) (xy 34.607892 -136.039929)
			(xy 34.62386 -135.954509) (xy 34.647641 -135.870927) (xy 34.679033 -135.789895) (xy 34.717767 -135.712106)
			(xy 34.763514 -135.638222) (xy 34.815883 -135.568875) (xy 34.874427 -135.504655) (xy 34.938647 -135.446111)
			(xy 35.007994 -135.393742) (xy 35.081878 -135.347995) (xy 35.159667 -135.309261) (xy 35.240699 -135.277869)
			(xy 35.324281 -135.254088) (xy 35.409701 -135.23812) (xy 35.49623 -135.230102) (xy 35.58313 -135.230102)
			(xy 35.669659 -135.23812) (xy 35.755079 -135.254088) (xy 35.838661 -135.277869) (xy 35.919693 -135.309261)
			(xy 35.997482 -135.347995) (xy 36.071366 -135.393742) (xy 36.140713 -135.446111) (xy 36.204933 -135.504655)
			(xy 36.263477 -135.568875) (xy 36.315846 -135.638222) (xy 36.361593 -135.712106) (xy 36.400327 -135.789895)
			(xy 36.431719 -135.870927) (xy 36.4555 -135.954509) (xy 36.471468 -136.039929) (xy 36.479486 -136.126458)
			(xy 36.479988 -136.169908) (xy 36.479486 -136.213358) (xy 36.471468 -136.299887) (xy 36.4555 -136.385307)
			(xy 36.431719 -136.468889) (xy 36.400327 -136.549921) (xy 36.361593 -136.62771) (xy 36.315846 -136.701594)
			(xy 36.263477 -136.770941) (xy 36.204933 -136.835161) (xy 36.140713 -136.893705) (xy 36.071366 -136.946074)
			(xy 35.997482 -136.991821) (xy 35.919693 -137.030555) (xy 35.838661 -137.061947) (xy 35.755079 -137.085728)
			(xy 35.669659 -137.101696) (xy 35.58313 -137.109714) (xy 35.49623 -137.109714) (xy 35.409701 -137.101696)
			(xy 35.324281 -137.085728) (xy 35.240699 -137.061947) (xy 35.159667 -137.030555) (xy 35.081878 -136.991821)
			(xy 35.007994 -136.946074) (xy 34.938647 -136.893705) (xy 34.874427 -136.835161) (xy 34.815883 -136.770941)
			(xy 34.763514 -136.701594) (xy 34.717767 -136.62771) (xy 34.679033 -136.549921) (xy 34.647641 -136.468889)
			(xy 34.62386 -136.385307) (xy 34.607892 -136.299887) (xy 34.599874 -136.213358) (xy 31.399486 -136.213358)
			(xy 31.391468 -136.299887) (xy 31.3755 -136.385307) (xy 31.351719 -136.468889) (xy 31.320327 -136.549921)
			(xy 31.281593 -136.62771) (xy 31.235846 -136.701594) (xy 31.183477 -136.770941) (xy 31.124933 -136.835161)
			(xy 31.060713 -136.893705) (xy 30.991366 -136.946074) (xy 30.917482 -136.991821) (xy 30.839693 -137.030555)
			(xy 30.758661 -137.061947) (xy 30.675079 -137.085728) (xy 30.589659 -137.101696) (xy 30.50313 -137.109714)
			(xy 30.41623 -137.109714) (xy 30.329701 -137.101696) (xy 30.244281 -137.085728) (xy 30.160699 -137.061947)
			(xy 30.079667 -137.030555) (xy 30.001878 -136.991821) (xy 29.927994 -136.946074) (xy 29.858647 -136.893705)
			(xy 29.794427 -136.835161) (xy 29.735883 -136.770941) (xy 29.683514 -136.701594) (xy 29.637767 -136.62771)
			(xy 29.599033 -136.549921) (xy 29.567641 -136.468889) (xy 29.54386 -136.385307) (xy 29.527892 -136.299887)
			(xy 29.519874 -136.213358) (xy 27.89936 -136.213358) (xy 27.89936 -138.753358) (xy 29.519874 -138.753358)
			(xy 29.519874 -138.666458) (xy 29.527892 -138.579929) (xy 29.54386 -138.494509) (xy 29.567641 -138.410927)
			(xy 29.599033 -138.329895) (xy 29.637767 -138.252106) (xy 29.683514 -138.178222) (xy 29.735883 -138.108875)
			(xy 29.794427 -138.044655) (xy 29.858647 -137.986111) (xy 29.927994 -137.933742) (xy 30.001878 -137.887995)
			(xy 30.079667 -137.849261) (xy 30.160699 -137.817869) (xy 30.244281 -137.794088) (xy 30.329701 -137.77812)
			(xy 30.41623 -137.770102) (xy 30.50313 -137.770102) (xy 30.589659 -137.77812) (xy 30.675079 -137.794088)
			(xy 30.758661 -137.817869) (xy 30.839693 -137.849261) (xy 30.917482 -137.887995) (xy 30.991366 -137.933742)
			(xy 31.060713 -137.986111) (xy 31.124933 -138.044655) (xy 31.183477 -138.108875) (xy 31.235846 -138.178222)
			(xy 31.281593 -138.252106) (xy 31.320327 -138.329895) (xy 31.351719 -138.410927) (xy 31.3755 -138.494509)
			(xy 31.391468 -138.579929) (xy 31.399486 -138.666458) (xy 31.399988 -138.709908) (xy 31.399486 -138.753358)
			(xy 34.599874 -138.753358) (xy 34.599874 -138.666458) (xy 34.607892 -138.579929) (xy 34.62386 -138.494509)
			(xy 34.647641 -138.410927) (xy 34.679033 -138.329895) (xy 34.717767 -138.252106) (xy 34.763514 -138.178222)
			(xy 34.815883 -138.108875) (xy 34.874427 -138.044655) (xy 34.938647 -137.986111) (xy 35.007994 -137.933742)
			(xy 35.081878 -137.887995) (xy 35.159667 -137.849261) (xy 35.240699 -137.817869) (xy 35.324281 -137.794088)
			(xy 35.409701 -137.77812) (xy 35.49623 -137.770102) (xy 35.58313 -137.770102) (xy 35.669659 -137.77812)
			(xy 35.755079 -137.794088) (xy 35.838661 -137.817869) (xy 35.919693 -137.849261) (xy 35.997482 -137.887995)
			(xy 36.071366 -137.933742) (xy 36.140713 -137.986111) (xy 36.204933 -138.044655) (xy 36.263477 -138.108875)
			(xy 36.315846 -138.178222) (xy 36.361593 -138.252106) (xy 36.400327 -138.329895) (xy 36.431719 -138.410927)
			(xy 36.4555 -138.494509) (xy 36.471468 -138.579929) (xy 36.479486 -138.666458) (xy 36.479988 -138.709908)
			(xy 36.479486 -138.753358) (xy 36.471468 -138.839887) (xy 36.4555 -138.925307) (xy 36.431719 -139.008889)
			(xy 36.400327 -139.089921) (xy 36.361593 -139.16771) (xy 36.315846 -139.241594) (xy 36.263477 -139.310941)
			(xy 36.204933 -139.375161) (xy 36.140713 -139.433705) (xy 36.071366 -139.486074) (xy 35.997482 -139.531821)
			(xy 35.919693 -139.570555) (xy 35.838661 -139.601947) (xy 35.755079 -139.625728) (xy 35.669659 -139.641696)
			(xy 35.58313 -139.649714) (xy 35.49623 -139.649714) (xy 35.409701 -139.641696) (xy 35.324281 -139.625728)
			(xy 35.240699 -139.601947) (xy 35.159667 -139.570555) (xy 35.081878 -139.531821) (xy 35.007994 -139.486074)
			(xy 34.938647 -139.433705) (xy 34.874427 -139.375161) (xy 34.815883 -139.310941) (xy 34.763514 -139.241594)
			(xy 34.717767 -139.16771) (xy 34.679033 -139.089921) (xy 34.647641 -139.008889) (xy 34.62386 -138.925307)
			(xy 34.607892 -138.839887) (xy 34.599874 -138.753358) (xy 31.399486 -138.753358) (xy 31.391468 -138.839887)
			(xy 31.3755 -138.925307) (xy 31.351719 -139.008889) (xy 31.320327 -139.089921) (xy 31.281593 -139.16771)
			(xy 31.235846 -139.241594) (xy 31.183477 -139.310941) (xy 31.124933 -139.375161) (xy 31.060713 -139.433705)
			(xy 30.991366 -139.486074) (xy 30.917482 -139.531821) (xy 30.839693 -139.570555) (xy 30.758661 -139.601947)
			(xy 30.675079 -139.625728) (xy 30.589659 -139.641696) (xy 30.50313 -139.649714) (xy 30.41623 -139.649714)
			(xy 30.329701 -139.641696) (xy 30.244281 -139.625728) (xy 30.160699 -139.601947) (xy 30.079667 -139.570555)
			(xy 30.001878 -139.531821) (xy 29.927994 -139.486074) (xy 29.858647 -139.433705) (xy 29.794427 -139.375161)
			(xy 29.735883 -139.310941) (xy 29.683514 -139.241594) (xy 29.637767 -139.16771) (xy 29.599033 -139.089921)
			(xy 29.567641 -139.008889) (xy 29.54386 -138.925307) (xy 29.527892 -138.839887) (xy 29.519874 -138.753358)
			(xy 27.89936 -138.753358) (xy 27.89936 -140.254228) (xy 39.818818 -140.254228) (xy 39.819523 -140.195605)
			(xy 39.828091 -140.078667) (xy 39.844787 -139.962611) (xy 39.86953 -139.848001) (xy 39.902199 -139.735393)
			(xy 39.942635 -139.625335) (xy 39.990642 -139.518363) (xy 40.045986 -139.414996) (xy 40.108399 -139.315737)
			(xy 40.177577 -139.221068) (xy 40.253183 -139.13145) (xy 40.334851 -139.047318) (xy 40.422182 -138.969081)
			(xy 40.514753 -138.89712) (xy 40.612113 -138.831784) (xy 40.713789 -138.773392) (xy 40.819288 -138.722226)
			(xy 40.928095 -138.678537) (xy 41.039682 -138.642535) (xy 41.153506 -138.614397) (xy 41.269014 -138.594259)
			(xy 41.385645 -138.582218) (xy 41.502832 -138.578334) (xy 41.620004 -138.582625) (xy 41.736593 -138.595071)
			(xy 41.85203 -138.615611) (xy 41.965756 -138.644144) (xy 42.077217 -138.680533) (xy 42.185872 -138.724601)
			(xy 42.291192 -138.776133) (xy 42.392665 -138.834878) (xy 42.489797 -138.900552) (xy 42.501941 -138.91006)
			(xy 43.327831 -138.91006) (xy 43.331866 -138.834356) (xy 43.343925 -138.759511) (xy 43.363871 -138.68637)
			(xy 43.391478 -138.615765) (xy 43.426434 -138.548494) (xy 43.468342 -138.485319) (xy 43.516728 -138.426957)
			(xy 43.571044 -138.374069) (xy 43.630673 -138.327254) (xy 43.694941 -138.287042) (xy 43.763118 -138.25389)
			(xy 43.834434 -138.228172) (xy 43.908079 -138.21018) (xy 43.983219 -138.200118) (xy 44.059003 -138.198099)
			(xy 44.134573 -138.204148) (xy 44.209071 -138.218195) (xy 44.281654 -138.240081) (xy 44.3515 -138.269558)
			(xy 44.417817 -138.306293) (xy 44.479853 -138.349868) (xy 44.536906 -138.39979) (xy 44.58833 -138.455494)
			(xy 44.633541 -138.516349) (xy 44.672028 -138.581664) (xy 44.703354 -138.6507) (xy 44.727164 -138.722675)
			(xy 44.743189 -138.796773) (xy 44.751248 -138.872154) (xy 44.751752 -138.91006) (xy 45.867831 -138.91006)
			(xy 45.871866 -138.834356) (xy 45.883925 -138.759511) (xy 45.903871 -138.68637) (xy 45.931478 -138.615765)
			(xy 45.966434 -138.548494) (xy 46.008342 -138.485319) (xy 46.056728 -138.426957) (xy 46.111044 -138.374069)
			(xy 46.170673 -138.327254) (xy 46.234941 -138.287042) (xy 46.303118 -138.25389) (xy 46.374434 -138.228172)
			(xy 46.448079 -138.21018) (xy 46.523219 -138.200118) (xy 46.599003 -138.198099) (xy 46.674573 -138.204148)
			(xy 46.749071 -138.218195) (xy 46.821654 -138.240081) (xy 46.8915 -138.269558) (xy 46.957817 -138.306293)
			(xy 47.019853 -138.349868) (xy 47.076906 -138.39979) (xy 47.12833 -138.455494) (xy 47.173541 -138.516349)
			(xy 47.212028 -138.581664) (xy 47.243354 -138.6507) (xy 47.267164 -138.722675) (xy 47.283189 -138.796773)
			(xy 47.291248 -138.872154) (xy 47.291752 -138.91006) (xy 48.407831 -138.91006) (xy 48.411866 -138.834356)
			(xy 48.423925 -138.759511) (xy 48.443871 -138.68637) (xy 48.471478 -138.615765) (xy 48.506434 -138.548494)
			(xy 48.548342 -138.485319) (xy 48.596728 -138.426957) (xy 48.651044 -138.374069) (xy 48.710673 -138.327254)
			(xy 48.774941 -138.287042) (xy 48.843118 -138.25389) (xy 48.914434 -138.228172) (xy 48.988079 -138.21018)
			(xy 49.063219 -138.200118) (xy 49.139003 -138.198099) (xy 49.214573 -138.204148) (xy 49.289071 -138.218195)
			(xy 49.361654 -138.240081) (xy 49.4315 -138.269558) (xy 49.497817 -138.306293) (xy 49.559853 -138.349868)
			(xy 49.616906 -138.39979) (xy 49.66833 -138.455494) (xy 49.713541 -138.516349) (xy 49.752028 -138.581664)
			(xy 49.783354 -138.6507) (xy 49.807164 -138.722675) (xy 49.823189 -138.796773) (xy 49.831248 -138.872154)
			(xy 49.831752 -138.91006) (xy 50.947831 -138.91006) (xy 50.951866 -138.834356) (xy 50.963925 -138.759511)
			(xy 50.983871 -138.68637) (xy 51.011478 -138.615765) (xy 51.046434 -138.548494) (xy 51.088342 -138.485319)
			(xy 51.136728 -138.426957) (xy 51.191044 -138.374069) (xy 51.250673 -138.327254) (xy 51.314941 -138.287042)
			(xy 51.383118 -138.25389) (xy 51.454434 -138.228172) (xy 51.528079 -138.21018) (xy 51.603219 -138.200118)
			(xy 51.679003 -138.198099) (xy 51.754573 -138.204148) (xy 51.829071 -138.218195) (xy 51.901654 -138.240081)
			(xy 51.9715 -138.269558) (xy 52.037817 -138.306293) (xy 52.099853 -138.349868) (xy 52.156906 -138.39979)
			(xy 52.20833 -138.455494) (xy 52.253541 -138.516349) (xy 52.292028 -138.581664) (xy 52.323354 -138.6507)
			(xy 52.347164 -138.722675) (xy 52.363189 -138.796773) (xy 52.371248 -138.872154) (xy 52.371752 -138.91006)
			(xy 53.487831 -138.91006) (xy 53.491866 -138.834356) (xy 53.503925 -138.759511) (xy 53.523871 -138.68637)
			(xy 53.551478 -138.615765) (xy 53.586434 -138.548494) (xy 53.628342 -138.485319) (xy 53.676728 -138.426957)
			(xy 53.731044 -138.374069) (xy 53.790673 -138.327254) (xy 53.854941 -138.287042) (xy 53.923118 -138.25389)
			(xy 53.994434 -138.228172) (xy 54.068079 -138.21018) (xy 54.143219 -138.200118) (xy 54.219003 -138.198099)
			(xy 54.294573 -138.204148) (xy 54.369071 -138.218195) (xy 54.441654 -138.240081) (xy 54.5115 -138.269558)
			(xy 54.577817 -138.306293) (xy 54.639853 -138.349868) (xy 54.696906 -138.39979) (xy 54.74833 -138.455494)
			(xy 54.793541 -138.516349) (xy 54.832028 -138.581664) (xy 54.863354 -138.6507) (xy 54.887164 -138.722675)
			(xy 54.903189 -138.796773) (xy 54.911248 -138.872154) (xy 54.911752 -138.91006) (xy 56.027831 -138.91006)
			(xy 56.031866 -138.834356) (xy 56.043925 -138.759511) (xy 56.063871 -138.68637) (xy 56.091478 -138.615765)
			(xy 56.126434 -138.548494) (xy 56.168342 -138.485319) (xy 56.216728 -138.426957) (xy 56.271044 -138.374069)
			(xy 56.330673 -138.327254) (xy 56.394941 -138.287042) (xy 56.463118 -138.25389) (xy 56.534434 -138.228172)
			(xy 56.608079 -138.21018) (xy 56.683219 -138.200118) (xy 56.759003 -138.198099) (xy 56.834573 -138.204148)
			(xy 56.909071 -138.218195) (xy 56.981654 -138.240081) (xy 57.0515 -138.269558) (xy 57.117817 -138.306293)
			(xy 57.179853 -138.349868) (xy 57.236906 -138.39979) (xy 57.28833 -138.455494) (xy 57.333541 -138.516349)
			(xy 57.372028 -138.581664) (xy 57.403354 -138.6507) (xy 57.427164 -138.722675) (xy 57.443189 -138.796773)
			(xy 57.451248 -138.872154) (xy 57.451752 -138.91006) (xy 58.567831 -138.91006) (xy 58.571866 -138.834356)
			(xy 58.583925 -138.759511) (xy 58.603871 -138.68637) (xy 58.631478 -138.615765) (xy 58.666434 -138.548494)
			(xy 58.708342 -138.485319) (xy 58.756728 -138.426957) (xy 58.811044 -138.374069) (xy 58.870673 -138.327254)
			(xy 58.934941 -138.287042) (xy 59.003118 -138.25389) (xy 59.074434 -138.228172) (xy 59.148079 -138.21018)
			(xy 59.223219 -138.200118) (xy 59.299003 -138.198099) (xy 59.374573 -138.204148) (xy 59.449071 -138.218195)
			(xy 59.521654 -138.240081) (xy 59.5915 -138.269558) (xy 59.657817 -138.306293) (xy 59.719853 -138.349868)
			(xy 59.776906 -138.39979) (xy 59.82833 -138.455494) (xy 59.873541 -138.516349) (xy 59.912028 -138.581664)
			(xy 59.943354 -138.6507) (xy 59.967164 -138.722675) (xy 59.983189 -138.796773) (xy 59.991248 -138.872154)
			(xy 59.991752 -138.91006) (xy 61.107831 -138.91006) (xy 61.111866 -138.834356) (xy 61.123925 -138.759511)
			(xy 61.143871 -138.68637) (xy 61.171478 -138.615765) (xy 61.206434 -138.548494) (xy 61.248342 -138.485319)
			(xy 61.296728 -138.426957) (xy 61.351044 -138.374069) (xy 61.410673 -138.327254) (xy 61.474941 -138.287042)
			(xy 61.543118 -138.25389) (xy 61.614434 -138.228172) (xy 61.688079 -138.21018) (xy 61.763219 -138.200118)
			(xy 61.839003 -138.198099) (xy 61.914573 -138.204148) (xy 61.989071 -138.218195) (xy 62.061654 -138.240081)
			(xy 62.1315 -138.269558) (xy 62.197817 -138.306293) (xy 62.259853 -138.349868) (xy 62.265798 -138.35507)
			(xy 86.197951 -138.35507) (xy 86.201986 -138.279366) (xy 86.214045 -138.204521) (xy 86.233991 -138.13138)
			(xy 86.261598 -138.060775) (xy 86.296554 -137.993504) (xy 86.338462 -137.930329) (xy 86.386848 -137.871967)
			(xy 86.441164 -137.819079) (xy 86.500793 -137.772264) (xy 86.565061 -137.732052) (xy 86.633238 -137.6989)
			(xy 86.704554 -137.673182) (xy 86.778199 -137.65519) (xy 86.853339 -137.645128) (xy 86.929123 -137.643109)
			(xy 87.004693 -137.649158) (xy 87.079191 -137.663205) (xy 87.151774 -137.685091) (xy 87.22162 -137.714568)
			(xy 87.287937 -137.751303) (xy 87.349973 -137.794878) (xy 87.407026 -137.8448) (xy 87.45845 -137.900504)
			(xy 87.503661 -137.961359) (xy 87.542148 -138.026674) (xy 87.573474 -138.09571) (xy 87.597284 -138.167685)
			(xy 87.613309 -138.241783) (xy 87.621368 -138.317164) (xy 87.621872 -138.35507) (xy 88.737951 -138.35507)
			(xy 88.741986 -138.279366) (xy 88.754045 -138.204521) (xy 88.773991 -138.13138) (xy 88.801598 -138.060775)
			(xy 88.836554 -137.993504) (xy 88.878462 -137.930329) (xy 88.926848 -137.871967) (xy 88.981164 -137.819079)
			(xy 89.040793 -137.772264) (xy 89.105061 -137.732052) (xy 89.173238 -137.6989) (xy 89.244554 -137.673182)
			(xy 89.318199 -137.65519) (xy 89.393339 -137.645128) (xy 89.469123 -137.643109) (xy 89.544693 -137.649158)
			(xy 89.619191 -137.663205) (xy 89.691774 -137.685091) (xy 89.76162 -137.714568) (xy 89.827937 -137.751303)
			(xy 89.889973 -137.794878) (xy 89.947026 -137.8448) (xy 89.99845 -137.900504) (xy 90.043661 -137.961359)
			(xy 90.082148 -138.026674) (xy 90.113474 -138.09571) (xy 90.137284 -138.167685) (xy 90.153309 -138.241783)
			(xy 90.161368 -138.317164) (xy 90.161872 -138.35507) (xy 91.277951 -138.35507) (xy 91.281986 -138.279366)
			(xy 91.294045 -138.204521) (xy 91.313991 -138.13138) (xy 91.341598 -138.060775) (xy 91.376554 -137.993504)
			(xy 91.418462 -137.930329) (xy 91.466848 -137.871967) (xy 91.521164 -137.819079) (xy 91.580793 -137.772264)
			(xy 91.645061 -137.732052) (xy 91.713238 -137.6989) (xy 91.784554 -137.673182) (xy 91.858199 -137.65519)
			(xy 91.933339 -137.645128) (xy 92.009123 -137.643109) (xy 92.084693 -137.649158) (xy 92.159191 -137.663205)
			(xy 92.231774 -137.685091) (xy 92.30162 -137.714568) (xy 92.367937 -137.751303) (xy 92.429973 -137.794878)
			(xy 92.487026 -137.8448) (xy 92.53845 -137.900504) (xy 92.583661 -137.961359) (xy 92.622148 -138.026674)
			(xy 92.653474 -138.09571) (xy 92.677284 -138.167685) (xy 92.693309 -138.241783) (xy 92.701368 -138.317164)
			(xy 92.701872 -138.35507) (xy 92.701368 -138.392976) (xy 92.693309 -138.468357) (xy 92.677284 -138.542455)
			(xy 92.653474 -138.61443) (xy 92.622148 -138.683466) (xy 92.583661 -138.748781) (xy 92.53845 -138.809636)
			(xy 92.487026 -138.86534) (xy 92.429973 -138.915262) (xy 92.367937 -138.958837) (xy 92.30162 -138.995572)
			(xy 92.231774 -139.025049) (xy 92.159191 -139.046935) (xy 92.084693 -139.060982) (xy 92.009123 -139.067031)
			(xy 91.933339 -139.065012) (xy 91.858199 -139.05495) (xy 91.784554 -139.036958) (xy 91.713238 -139.01124)
			(xy 91.645061 -138.978088) (xy 91.580793 -138.937876) (xy 91.521164 -138.891061) (xy 91.466848 -138.838173)
			(xy 91.418462 -138.779811) (xy 91.376554 -138.716636) (xy 91.341598 -138.649365) (xy 91.313991 -138.57876)
			(xy 91.294045 -138.505619) (xy 91.281986 -138.430774) (xy 91.277951 -138.35507) (xy 90.161872 -138.35507)
			(xy 90.161368 -138.392976) (xy 90.153309 -138.468357) (xy 90.137284 -138.542455) (xy 90.113474 -138.61443)
			(xy 90.082148 -138.683466) (xy 90.043661 -138.748781) (xy 89.99845 -138.809636) (xy 89.947026 -138.86534)
			(xy 89.889973 -138.915262) (xy 89.827937 -138.958837) (xy 89.76162 -138.995572) (xy 89.691774 -139.025049)
			(xy 89.619191 -139.046935) (xy 89.544693 -139.060982) (xy 89.469123 -139.067031) (xy 89.393339 -139.065012)
			(xy 89.318199 -139.05495) (xy 89.244554 -139.036958) (xy 89.173238 -139.01124) (xy 89.105061 -138.978088)
			(xy 89.040793 -138.937876) (xy 88.981164 -138.891061) (xy 88.926848 -138.838173) (xy 88.878462 -138.779811)
			(xy 88.836554 -138.716636) (xy 88.801598 -138.649365) (xy 88.773991 -138.57876) (xy 88.754045 -138.505619)
			(xy 88.741986 -138.430774) (xy 88.737951 -138.35507) (xy 87.621872 -138.35507) (xy 87.621368 -138.392976)
			(xy 87.613309 -138.468357) (xy 87.597284 -138.542455) (xy 87.573474 -138.61443) (xy 87.542148 -138.683466)
			(xy 87.503661 -138.748781) (xy 87.45845 -138.809636) (xy 87.407026 -138.86534) (xy 87.349973 -138.915262)
			(xy 87.287937 -138.958837) (xy 87.22162 -138.995572) (xy 87.151774 -139.025049) (xy 87.079191 -139.046935)
			(xy 87.004693 -139.060982) (xy 86.929123 -139.067031) (xy 86.853339 -139.065012) (xy 86.778199 -139.05495)
			(xy 86.704554 -139.036958) (xy 86.633238 -139.01124) (xy 86.565061 -138.978088) (xy 86.500793 -138.937876)
			(xy 86.441164 -138.891061) (xy 86.386848 -138.838173) (xy 86.338462 -138.779811) (xy 86.296554 -138.716636)
			(xy 86.261598 -138.649365) (xy 86.233991 -138.57876) (xy 86.214045 -138.505619) (xy 86.201986 -138.430774)
			(xy 86.197951 -138.35507) (xy 62.265798 -138.35507) (xy 62.316906 -138.39979) (xy 62.36833 -138.455494)
			(xy 62.413541 -138.516349) (xy 62.452028 -138.581664) (xy 62.483354 -138.6507) (xy 62.507164 -138.722675)
			(xy 62.523189 -138.796773) (xy 62.531248 -138.872154) (xy 62.531752 -138.91006) (xy 62.531248 -138.947966)
			(xy 62.523189 -139.023347) (xy 62.507164 -139.097445) (xy 62.483354 -139.16942) (xy 62.452028 -139.238456)
			(xy 62.413541 -139.303771) (xy 62.36833 -139.364626) (xy 62.316906 -139.42033) (xy 62.259853 -139.470252)
			(xy 62.197817 -139.513827) (xy 62.1315 -139.550562) (xy 62.061654 -139.580039) (xy 61.989071 -139.601925)
			(xy 61.914573 -139.615972) (xy 61.839003 -139.622021) (xy 61.763219 -139.620002) (xy 61.688079 -139.60994)
			(xy 61.614434 -139.591948) (xy 61.543118 -139.56623) (xy 61.474941 -139.533078) (xy 61.410673 -139.492866)
			(xy 61.351044 -139.446051) (xy 61.296728 -139.393163) (xy 61.248342 -139.334801) (xy 61.206434 -139.271626)
			(xy 61.171478 -139.204355) (xy 61.143871 -139.13375) (xy 61.123925 -139.060609) (xy 61.111866 -138.985764)
			(xy 61.107831 -138.91006) (xy 59.991752 -138.91006) (xy 59.991248 -138.947966) (xy 59.983189 -139.023347)
			(xy 59.967164 -139.097445) (xy 59.943354 -139.16942) (xy 59.912028 -139.238456) (xy 59.873541 -139.303771)
			(xy 59.82833 -139.364626) (xy 59.776906 -139.42033) (xy 59.719853 -139.470252) (xy 59.657817 -139.513827)
			(xy 59.5915 -139.550562) (xy 59.521654 -139.580039) (xy 59.449071 -139.601925) (xy 59.374573 -139.615972)
			(xy 59.299003 -139.622021) (xy 59.223219 -139.620002) (xy 59.148079 -139.60994) (xy 59.074434 -139.591948)
			(xy 59.003118 -139.56623) (xy 58.934941 -139.533078) (xy 58.870673 -139.492866) (xy 58.811044 -139.446051)
			(xy 58.756728 -139.393163) (xy 58.708342 -139.334801) (xy 58.666434 -139.271626) (xy 58.631478 -139.204355)
			(xy 58.603871 -139.13375) (xy 58.583925 -139.060609) (xy 58.571866 -138.985764) (xy 58.567831 -138.91006)
			(xy 57.451752 -138.91006) (xy 57.451248 -138.947966) (xy 57.443189 -139.023347) (xy 57.427164 -139.097445)
			(xy 57.403354 -139.16942) (xy 57.372028 -139.238456) (xy 57.333541 -139.303771) (xy 57.28833 -139.364626)
			(xy 57.236906 -139.42033) (xy 57.179853 -139.470252) (xy 57.117817 -139.513827) (xy 57.0515 -139.550562)
			(xy 56.981654 -139.580039) (xy 56.909071 -139.601925) (xy 56.834573 -139.615972) (xy 56.759003 -139.622021)
			(xy 56.683219 -139.620002) (xy 56.608079 -139.60994) (xy 56.534434 -139.591948) (xy 56.463118 -139.56623)
			(xy 56.394941 -139.533078) (xy 56.330673 -139.492866) (xy 56.271044 -139.446051) (xy 56.216728 -139.393163)
			(xy 56.168342 -139.334801) (xy 56.126434 -139.271626) (xy 56.091478 -139.204355) (xy 56.063871 -139.13375)
			(xy 56.043925 -139.060609) (xy 56.031866 -138.985764) (xy 56.027831 -138.91006) (xy 54.911752 -138.91006)
			(xy 54.911248 -138.947966) (xy 54.903189 -139.023347) (xy 54.887164 -139.097445) (xy 54.863354 -139.16942)
			(xy 54.832028 -139.238456) (xy 54.793541 -139.303771) (xy 54.74833 -139.364626) (xy 54.696906 -139.42033)
			(xy 54.639853 -139.470252) (xy 54.577817 -139.513827) (xy 54.5115 -139.550562) (xy 54.441654 -139.580039)
			(xy 54.369071 -139.601925) (xy 54.294573 -139.615972) (xy 54.219003 -139.622021) (xy 54.143219 -139.620002)
			(xy 54.068079 -139.60994) (xy 53.994434 -139.591948) (xy 53.923118 -139.56623) (xy 53.854941 -139.533078)
			(xy 53.790673 -139.492866) (xy 53.731044 -139.446051) (xy 53.676728 -139.393163) (xy 53.628342 -139.334801)
			(xy 53.586434 -139.271626) (xy 53.551478 -139.204355) (xy 53.523871 -139.13375) (xy 53.503925 -139.060609)
			(xy 53.491866 -138.985764) (xy 53.487831 -138.91006) (xy 52.371752 -138.91006) (xy 52.371248 -138.947966)
			(xy 52.363189 -139.023347) (xy 52.347164 -139.097445) (xy 52.323354 -139.16942) (xy 52.292028 -139.238456)
			(xy 52.253541 -139.303771) (xy 52.20833 -139.364626) (xy 52.156906 -139.42033) (xy 52.099853 -139.470252)
			(xy 52.037817 -139.513827) (xy 51.9715 -139.550562) (xy 51.901654 -139.580039) (xy 51.829071 -139.601925)
			(xy 51.754573 -139.615972) (xy 51.679003 -139.622021) (xy 51.603219 -139.620002) (xy 51.528079 -139.60994)
			(xy 51.454434 -139.591948) (xy 51.383118 -139.56623) (xy 51.314941 -139.533078) (xy 51.250673 -139.492866)
			(xy 51.191044 -139.446051) (xy 51.136728 -139.393163) (xy 51.088342 -139.334801) (xy 51.046434 -139.271626)
			(xy 51.011478 -139.204355) (xy 50.983871 -139.13375) (xy 50.963925 -139.060609) (xy 50.951866 -138.985764)
			(xy 50.947831 -138.91006) (xy 49.831752 -138.91006) (xy 49.831248 -138.947966) (xy 49.823189 -139.023347)
			(xy 49.807164 -139.097445) (xy 49.783354 -139.16942) (xy 49.752028 -139.238456) (xy 49.713541 -139.303771)
			(xy 49.66833 -139.364626) (xy 49.616906 -139.42033) (xy 49.559853 -139.470252) (xy 49.497817 -139.513827)
			(xy 49.4315 -139.550562) (xy 49.361654 -139.580039) (xy 49.289071 -139.601925) (xy 49.214573 -139.615972)
			(xy 49.139003 -139.622021) (xy 49.063219 -139.620002) (xy 48.988079 -139.60994) (xy 48.914434 -139.591948)
			(xy 48.843118 -139.56623) (xy 48.774941 -139.533078) (xy 48.710673 -139.492866) (xy 48.651044 -139.446051)
			(xy 48.596728 -139.393163) (xy 48.548342 -139.334801) (xy 48.506434 -139.271626) (xy 48.471478 -139.204355)
			(xy 48.443871 -139.13375) (xy 48.423925 -139.060609) (xy 48.411866 -138.985764) (xy 48.407831 -138.91006)
			(xy 47.291752 -138.91006) (xy 47.291248 -138.947966) (xy 47.283189 -139.023347) (xy 47.267164 -139.097445)
			(xy 47.243354 -139.16942) (xy 47.212028 -139.238456) (xy 47.173541 -139.303771) (xy 47.12833 -139.364626)
			(xy 47.076906 -139.42033) (xy 47.019853 -139.470252) (xy 46.957817 -139.513827) (xy 46.8915 -139.550562)
			(xy 46.821654 -139.580039) (xy 46.749071 -139.601925) (xy 46.674573 -139.615972) (xy 46.599003 -139.622021)
			(xy 46.523219 -139.620002) (xy 46.448079 -139.60994) (xy 46.374434 -139.591948) (xy 46.303118 -139.56623)
			(xy 46.234941 -139.533078) (xy 46.170673 -139.492866) (xy 46.111044 -139.446051) (xy 46.056728 -139.393163)
			(xy 46.008342 -139.334801) (xy 45.966434 -139.271626) (xy 45.931478 -139.204355) (xy 45.903871 -139.13375)
			(xy 45.883925 -139.060609) (xy 45.871866 -138.985764) (xy 45.867831 -138.91006) (xy 44.751752 -138.91006)
			(xy 44.751248 -138.947966) (xy 44.743189 -139.023347) (xy 44.727164 -139.097445) (xy 44.703354 -139.16942)
			(xy 44.672028 -139.238456) (xy 44.633541 -139.303771) (xy 44.58833 -139.364626) (xy 44.536906 -139.42033)
			(xy 44.479853 -139.470252) (xy 44.417817 -139.513827) (xy 44.3515 -139.550562) (xy 44.281654 -139.580039)
			(xy 44.209071 -139.601925) (xy 44.134573 -139.615972) (xy 44.059003 -139.622021) (xy 43.983219 -139.620002)
			(xy 43.908079 -139.60994) (xy 43.834434 -139.591948) (xy 43.763118 -139.56623) (xy 43.694941 -139.533078)
			(xy 43.630673 -139.492866) (xy 43.571044 -139.446051) (xy 43.516728 -139.393163) (xy 43.468342 -139.334801)
			(xy 43.426434 -139.271626) (xy 43.391478 -139.204355) (xy 43.363871 -139.13375) (xy 43.343925 -139.060609)
			(xy 43.331866 -138.985764) (xy 43.327831 -138.91006) (xy 42.501941 -138.91006) (xy 42.582117 -138.972834)
			(xy 42.669176 -139.051374) (xy 42.750551 -139.135789) (xy 42.825845 -139.225669) (xy 42.894694 -139.320578)
			(xy 42.956761 -139.420054) (xy 43.011746 -139.523612) (xy 43.056855 -139.62507) (xy 84.927951 -139.62507)
			(xy 84.931986 -139.549366) (xy 84.944045 -139.474521) (xy 84.963991 -139.40138) (xy 84.991598 -139.330775)
			(xy 85.026554 -139.263504) (xy 85.068462 -139.200329) (xy 85.116848 -139.141967) (xy 85.171164 -139.089079)
			(xy 85.230793 -139.042264) (xy 85.295061 -139.002052) (xy 85.363238 -138.9689) (xy 85.434554 -138.943182)
			(xy 85.508199 -138.92519) (xy 85.583339 -138.915128) (xy 85.659123 -138.913109) (xy 85.734693 -138.919158)
			(xy 85.809191 -138.933205) (xy 85.881774 -138.955091) (xy 85.95162 -138.984568) (xy 86.017937 -139.021303)
			(xy 86.079973 -139.064878) (xy 86.137026 -139.1148) (xy 86.18845 -139.170504) (xy 86.233661 -139.231359)
			(xy 86.272148 -139.296674) (xy 86.303474 -139.36571) (xy 86.327284 -139.437685) (xy 86.343309 -139.511783)
			(xy 86.351368 -139.587164) (xy 86.351872 -139.62507) (xy 87.467951 -139.62507) (xy 87.471986 -139.549366)
			(xy 87.484045 -139.474521) (xy 87.503991 -139.40138) (xy 87.531598 -139.330775) (xy 87.566554 -139.263504)
			(xy 87.608462 -139.200329) (xy 87.656848 -139.141967) (xy 87.711164 -139.089079) (xy 87.770793 -139.042264)
			(xy 87.835061 -139.002052) (xy 87.903238 -138.9689) (xy 87.974554 -138.943182) (xy 88.048199 -138.92519)
			(xy 88.123339 -138.915128) (xy 88.199123 -138.913109) (xy 88.274693 -138.919158) (xy 88.349191 -138.933205)
			(xy 88.421774 -138.955091) (xy 88.49162 -138.984568) (xy 88.557937 -139.021303) (xy 88.619973 -139.064878)
			(xy 88.677026 -139.1148) (xy 88.72845 -139.170504) (xy 88.773661 -139.231359) (xy 88.812148 -139.296674)
			(xy 88.843474 -139.36571) (xy 88.867284 -139.437685) (xy 88.883309 -139.511783) (xy 88.891368 -139.587164)
			(xy 88.891872 -139.62507) (xy 90.007951 -139.62507) (xy 90.011986 -139.549366) (xy 90.024045 -139.474521)
			(xy 90.043991 -139.40138) (xy 90.071598 -139.330775) (xy 90.106554 -139.263504) (xy 90.148462 -139.200329)
			(xy 90.196848 -139.141967) (xy 90.251164 -139.089079) (xy 90.310793 -139.042264) (xy 90.375061 -139.002052)
			(xy 90.443238 -138.9689) (xy 90.514554 -138.943182) (xy 90.588199 -138.92519) (xy 90.663339 -138.915128)
			(xy 90.739123 -138.913109) (xy 90.814693 -138.919158) (xy 90.889191 -138.933205) (xy 90.961774 -138.955091)
			(xy 91.03162 -138.984568) (xy 91.097937 -139.021303) (xy 91.159973 -139.064878) (xy 91.217026 -139.1148)
			(xy 91.26845 -139.170504) (xy 91.313661 -139.231359) (xy 91.352148 -139.296674) (xy 91.383474 -139.36571)
			(xy 91.407284 -139.437685) (xy 91.423309 -139.511783) (xy 91.431368 -139.587164) (xy 91.431872 -139.62507)
			(xy 91.431368 -139.662976) (xy 91.423309 -139.738357) (xy 91.407284 -139.812455) (xy 91.383474 -139.88443)
			(xy 91.352148 -139.953466) (xy 91.313661 -140.018781) (xy 91.26845 -140.079636) (xy 91.217026 -140.13534)
			(xy 91.159973 -140.185262) (xy 91.097937 -140.228837) (xy 91.03162 -140.265572) (xy 90.961774 -140.295049)
			(xy 90.889191 -140.316935) (xy 90.814693 -140.330982) (xy 90.739123 -140.337031) (xy 90.663339 -140.335012)
			(xy 90.588199 -140.32495) (xy 90.514554 -140.306958) (xy 90.443238 -140.28124) (xy 90.375061 -140.248088)
			(xy 90.310793 -140.207876) (xy 90.251164 -140.161061) (xy 90.196848 -140.108173) (xy 90.148462 -140.049811)
			(xy 90.106554 -139.986636) (xy 90.071598 -139.919365) (xy 90.043991 -139.84876) (xy 90.024045 -139.775619)
			(xy 90.011986 -139.700774) (xy 90.007951 -139.62507) (xy 88.891872 -139.62507) (xy 88.891368 -139.662976)
			(xy 88.883309 -139.738357) (xy 88.867284 -139.812455) (xy 88.843474 -139.88443) (xy 88.812148 -139.953466)
			(xy 88.773661 -140.018781) (xy 88.72845 -140.079636) (xy 88.677026 -140.13534) (xy 88.619973 -140.185262)
			(xy 88.557937 -140.228837) (xy 88.49162 -140.265572) (xy 88.421774 -140.295049) (xy 88.349191 -140.316935)
			(xy 88.274693 -140.330982) (xy 88.199123 -140.337031) (xy 88.123339 -140.335012) (xy 88.048199 -140.32495)
			(xy 87.974554 -140.306958) (xy 87.903238 -140.28124) (xy 87.835061 -140.248088) (xy 87.770793 -140.207876)
			(xy 87.711164 -140.161061) (xy 87.656848 -140.108173) (xy 87.608462 -140.049811) (xy 87.566554 -139.986636)
			(xy 87.531598 -139.919365) (xy 87.503991 -139.84876) (xy 87.484045 -139.775619) (xy 87.471986 -139.700774)
			(xy 87.467951 -139.62507) (xy 86.351872 -139.62507) (xy 86.351368 -139.662976) (xy 86.343309 -139.738357)
			(xy 86.327284 -139.812455) (xy 86.303474 -139.88443) (xy 86.272148 -139.953466) (xy 86.233661 -140.018781)
			(xy 86.18845 -140.079636) (xy 86.137026 -140.13534) (xy 86.079973 -140.185262) (xy 86.017937 -140.228837)
			(xy 85.95162 -140.265572) (xy 85.881774 -140.295049) (xy 85.809191 -140.316935) (xy 85.734693 -140.330982)
			(xy 85.659123 -140.337031) (xy 85.583339 -140.335012) (xy 85.508199 -140.32495) (xy 85.434554 -140.306958)
			(xy 85.363238 -140.28124) (xy 85.295061 -140.248088) (xy 85.230793 -140.207876) (xy 85.171164 -140.161061)
			(xy 85.116848 -140.108173) (xy 85.068462 -140.049811) (xy 85.026554 -139.986636) (xy 84.991598 -139.919365)
			(xy 84.963991 -139.84876) (xy 84.944045 -139.775619) (xy 84.931986 -139.700774) (xy 84.927951 -139.62507)
			(xy 43.056855 -139.62507) (xy 43.059381 -139.630751) (xy 43.099434 -139.740948) (xy 43.131712 -139.853669)
			(xy 43.156056 -139.968365) (xy 43.172348 -140.084478) (xy 43.18051 -140.201445) (xy 43.181016 -140.26007)
			(xy 43.180861 -140.290833) (xy 43.178574 -140.352316) (xy 43.176444 -140.383006) (xy 43.175682 -140.392404)
			(xy 43.170622 -140.450806) (xy 43.153396 -140.566771) (xy 43.12813 -140.681253) (xy 43.094949 -140.793697)
			(xy 43.057175 -140.89507) (xy 86.197951 -140.89507) (xy 86.201986 -140.819366) (xy 86.214045 -140.744521)
			(xy 86.233991 -140.67138) (xy 86.261598 -140.600775) (xy 86.296554 -140.533504) (xy 86.338462 -140.470329)
			(xy 86.386848 -140.411967) (xy 86.441164 -140.359079) (xy 86.500793 -140.312264) (xy 86.565061 -140.272052)
			(xy 86.633238 -140.2389) (xy 86.704554 -140.213182) (xy 86.778199 -140.19519) (xy 86.853339 -140.185128)
			(xy 86.929123 -140.183109) (xy 87.004693 -140.189158) (xy 87.079191 -140.203205) (xy 87.151774 -140.225091)
			(xy 87.22162 -140.254568) (xy 87.287937 -140.291303) (xy 87.349973 -140.334878) (xy 87.407026 -140.3848)
			(xy 87.45845 -140.440504) (xy 87.503661 -140.501359) (xy 87.542148 -140.566674) (xy 87.573474 -140.63571)
			(xy 87.597284 -140.707685) (xy 87.613309 -140.781783) (xy 87.621368 -140.857164) (xy 87.621872 -140.89507)
			(xy 88.737951 -140.89507) (xy 88.741986 -140.819366) (xy 88.754045 -140.744521) (xy 88.773991 -140.67138)
			(xy 88.801598 -140.600775) (xy 88.836554 -140.533504) (xy 88.878462 -140.470329) (xy 88.926848 -140.411967)
			(xy 88.981164 -140.359079) (xy 89.040793 -140.312264) (xy 89.105061 -140.272052) (xy 89.173238 -140.2389)
			(xy 89.244554 -140.213182) (xy 89.318199 -140.19519) (xy 89.393339 -140.185128) (xy 89.469123 -140.183109)
			(xy 89.544693 -140.189158) (xy 89.619191 -140.203205) (xy 89.691774 -140.225091) (xy 89.76162 -140.254568)
			(xy 89.827937 -140.291303) (xy 89.889973 -140.334878) (xy 89.947026 -140.3848) (xy 89.99845 -140.440504)
			(xy 90.043661 -140.501359) (xy 90.082148 -140.566674) (xy 90.113474 -140.63571) (xy 90.137284 -140.707685)
			(xy 90.153309 -140.781783) (xy 90.161368 -140.857164) (xy 90.161872 -140.89507) (xy 91.277951 -140.89507)
			(xy 91.281986 -140.819366) (xy 91.294045 -140.744521) (xy 91.313991 -140.67138) (xy 91.341598 -140.600775)
			(xy 91.376554 -140.533504) (xy 91.418462 -140.470329) (xy 91.466848 -140.411967) (xy 91.521164 -140.359079)
			(xy 91.580793 -140.312264) (xy 91.645061 -140.272052) (xy 91.713238 -140.2389) (xy 91.784554 -140.213182)
			(xy 91.858199 -140.19519) (xy 91.933339 -140.185128) (xy 92.009123 -140.183109) (xy 92.084693 -140.189158)
			(xy 92.159191 -140.203205) (xy 92.231774 -140.225091) (xy 92.30162 -140.254568) (xy 92.367937 -140.291303)
			(xy 92.429973 -140.334878) (xy 92.487026 -140.3848) (xy 92.53845 -140.440504) (xy 92.583661 -140.501359)
			(xy 92.622148 -140.566674) (xy 92.653474 -140.63571) (xy 92.677284 -140.707685) (xy 92.693309 -140.781783)
			(xy 92.701368 -140.857164) (xy 92.701872 -140.89507) (xy 92.701368 -140.932976) (xy 92.693309 -141.008357)
			(xy 92.677284 -141.082455) (xy 92.653474 -141.15443) (xy 92.622148 -141.223466) (xy 92.583661 -141.288781)
			(xy 92.53845 -141.349636) (xy 92.487026 -141.40534) (xy 92.429973 -141.455262) (xy 92.367937 -141.498837)
			(xy 92.30162 -141.535572) (xy 92.231774 -141.565049) (xy 92.159191 -141.586935) (xy 92.084693 -141.600982)
			(xy 92.009123 -141.607031) (xy 91.933339 -141.605012) (xy 91.858199 -141.59495) (xy 91.784554 -141.576958)
			(xy 91.713238 -141.55124) (xy 91.645061 -141.518088) (xy 91.580793 -141.477876) (xy 91.521164 -141.431061)
			(xy 91.466848 -141.378173) (xy 91.418462 -141.319811) (xy 91.376554 -141.256636) (xy 91.341598 -141.189365)
			(xy 91.313991 -141.11876) (xy 91.294045 -141.045619) (xy 91.281986 -140.970774) (xy 91.277951 -140.89507)
			(xy 90.161872 -140.89507) (xy 90.161368 -140.932976) (xy 90.153309 -141.008357) (xy 90.137284 -141.082455)
			(xy 90.113474 -141.15443) (xy 90.082148 -141.223466) (xy 90.043661 -141.288781) (xy 89.99845 -141.349636)
			(xy 89.947026 -141.40534) (xy 89.889973 -141.455262) (xy 89.827937 -141.498837) (xy 89.76162 -141.535572)
			(xy 89.691774 -141.565049) (xy 89.619191 -141.586935) (xy 89.544693 -141.600982) (xy 89.469123 -141.607031)
			(xy 89.393339 -141.605012) (xy 89.318199 -141.59495) (xy 89.244554 -141.576958) (xy 89.173238 -141.55124)
			(xy 89.105061 -141.518088) (xy 89.040793 -141.477876) (xy 88.981164 -141.431061) (xy 88.926848 -141.378173)
			(xy 88.878462 -141.319811) (xy 88.836554 -141.256636) (xy 88.801598 -141.189365) (xy 88.773991 -141.11876)
			(xy 88.754045 -141.045619) (xy 88.741986 -140.970774) (xy 88.737951 -140.89507) (xy 87.621872 -140.89507)
			(xy 87.621368 -140.932976) (xy 87.613309 -141.008357) (xy 87.597284 -141.082455) (xy 87.573474 -141.15443)
			(xy 87.542148 -141.223466) (xy 87.503661 -141.288781) (xy 87.45845 -141.349636) (xy 87.407026 -141.40534)
			(xy 87.349973 -141.455262) (xy 87.287937 -141.498837) (xy 87.22162 -141.535572) (xy 87.151774 -141.565049)
			(xy 87.079191 -141.586935) (xy 87.004693 -141.600982) (xy 86.929123 -141.607031) (xy 86.853339 -141.605012)
			(xy 86.778199 -141.59495) (xy 86.704554 -141.576958) (xy 86.633238 -141.55124) (xy 86.565061 -141.518088)
			(xy 86.500793 -141.477876) (xy 86.441164 -141.431061) (xy 86.386848 -141.378173) (xy 86.338462 -141.319811)
			(xy 86.296554 -141.256636) (xy 86.261598 -141.189365) (xy 86.233991 -141.11876) (xy 86.214045 -141.045619)
			(xy 86.201986 -140.970774) (xy 86.197951 -140.89507) (xy 43.057175 -140.89507) (xy 43.055945 -140.898372)
			(xy 43.328336 -140.898372) (xy 44.751752 -140.898372) (xy 44.751752 -141.61008) (xy 45.867831 -141.61008)
			(xy 45.871866 -141.534376) (xy 45.883925 -141.459531) (xy 45.903871 -141.38639) (xy 45.931478 -141.315785)
			(xy 45.966434 -141.248514) (xy 46.008342 -141.185339) (xy 46.056728 -141.126977) (xy 46.111044 -141.074089)
			(xy 46.170673 -141.027274) (xy 46.234941 -140.987062) (xy 46.303118 -140.95391) (xy 46.374434 -140.928192)
			(xy 46.448079 -140.9102) (xy 46.523219 -140.900138) (xy 46.599003 -140.898119) (xy 46.674573 -140.904168)
			(xy 46.749071 -140.918215) (xy 46.821654 -140.940101) (xy 46.8915 -140.969578) (xy 46.957817 -141.006313)
			(xy 47.019853 -141.049888) (xy 47.076906 -141.09981) (xy 47.12833 -141.155514) (xy 47.173541 -141.216369)
			(xy 47.212028 -141.281684) (xy 47.243354 -141.35072) (xy 47.267164 -141.422695) (xy 47.283189 -141.496793)
			(xy 47.291248 -141.572174) (xy 47.291752 -141.61008) (xy 48.407831 -141.61008) (xy 48.411866 -141.534376)
			(xy 48.423925 -141.459531) (xy 48.443871 -141.38639) (xy 48.471478 -141.315785) (xy 48.506434 -141.248514)
			(xy 48.548342 -141.185339) (xy 48.596728 -141.126977) (xy 48.651044 -141.074089) (xy 48.710673 -141.027274)
			(xy 48.774941 -140.987062) (xy 48.843118 -140.95391) (xy 48.914434 -140.928192) (xy 48.988079 -140.9102)
			(xy 49.063219 -140.900138) (xy 49.139003 -140.898119) (xy 49.214573 -140.904168) (xy 49.289071 -140.918215)
			(xy 49.361654 -140.940101) (xy 49.4315 -140.969578) (xy 49.497817 -141.006313) (xy 49.559853 -141.049888)
			(xy 49.616906 -141.09981) (xy 49.66833 -141.155514) (xy 49.713541 -141.216369) (xy 49.752028 -141.281684)
			(xy 49.783354 -141.35072) (xy 49.807164 -141.422695) (xy 49.823189 -141.496793) (xy 49.831248 -141.572174)
			(xy 49.831752 -141.61008) (xy 50.947831 -141.61008) (xy 50.951866 -141.534376) (xy 50.963925 -141.459531)
			(xy 50.983871 -141.38639) (xy 51.011478 -141.315785) (xy 51.046434 -141.248514) (xy 51.088342 -141.185339)
			(xy 51.136728 -141.126977) (xy 51.191044 -141.074089) (xy 51.250673 -141.027274) (xy 51.314941 -140.987062)
			(xy 51.383118 -140.95391) (xy 51.454434 -140.928192) (xy 51.528079 -140.9102) (xy 51.603219 -140.900138)
			(xy 51.679003 -140.898119) (xy 51.754573 -140.904168) (xy 51.829071 -140.918215) (xy 51.901654 -140.940101)
			(xy 51.9715 -140.969578) (xy 52.037817 -141.006313) (xy 52.099853 -141.049888) (xy 52.156906 -141.09981)
			(xy 52.20833 -141.155514) (xy 52.253541 -141.216369) (xy 52.292028 -141.281684) (xy 52.323354 -141.35072)
			(xy 52.347164 -141.422695) (xy 52.363189 -141.496793) (xy 52.371248 -141.572174) (xy 52.371752 -141.61008)
			(xy 53.487831 -141.61008) (xy 53.491866 -141.534376) (xy 53.503925 -141.459531) (xy 53.523871 -141.38639)
			(xy 53.551478 -141.315785) (xy 53.586434 -141.248514) (xy 53.628342 -141.185339) (xy 53.676728 -141.126977)
			(xy 53.731044 -141.074089) (xy 53.790673 -141.027274) (xy 53.854941 -140.987062) (xy 53.923118 -140.95391)
			(xy 53.994434 -140.928192) (xy 54.068079 -140.9102) (xy 54.143219 -140.900138) (xy 54.219003 -140.898119)
			(xy 54.294573 -140.904168) (xy 54.369071 -140.918215) (xy 54.441654 -140.940101) (xy 54.5115 -140.969578)
			(xy 54.577817 -141.006313) (xy 54.639853 -141.049888) (xy 54.696906 -141.09981) (xy 54.74833 -141.155514)
			(xy 54.793541 -141.216369) (xy 54.832028 -141.281684) (xy 54.863354 -141.35072) (xy 54.887164 -141.422695)
			(xy 54.903189 -141.496793) (xy 54.911248 -141.572174) (xy 54.911752 -141.61008) (xy 56.027831 -141.61008)
			(xy 56.031866 -141.534376) (xy 56.043925 -141.459531) (xy 56.063871 -141.38639) (xy 56.091478 -141.315785)
			(xy 56.126434 -141.248514) (xy 56.168342 -141.185339) (xy 56.216728 -141.126977) (xy 56.271044 -141.074089)
			(xy 56.330673 -141.027274) (xy 56.394941 -140.987062) (xy 56.463118 -140.95391) (xy 56.534434 -140.928192)
			(xy 56.608079 -140.9102) (xy 56.683219 -140.900138) (xy 56.759003 -140.898119) (xy 56.834573 -140.904168)
			(xy 56.909071 -140.918215) (xy 56.981654 -140.940101) (xy 57.0515 -140.969578) (xy 57.117817 -141.006313)
			(xy 57.179853 -141.049888) (xy 57.236906 -141.09981) (xy 57.28833 -141.155514) (xy 57.333541 -141.216369)
			(xy 57.372028 -141.281684) (xy 57.403354 -141.35072) (xy 57.427164 -141.422695) (xy 57.443189 -141.496793)
			(xy 57.451248 -141.572174) (xy 57.451752 -141.61008) (xy 58.567831 -141.61008) (xy 58.571866 -141.534376)
			(xy 58.583925 -141.459531) (xy 58.603871 -141.38639) (xy 58.631478 -141.315785) (xy 58.666434 -141.248514)
			(xy 58.708342 -141.185339) (xy 58.756728 -141.126977) (xy 58.811044 -141.074089) (xy 58.870673 -141.027274)
			(xy 58.934941 -140.987062) (xy 59.003118 -140.95391) (xy 59.074434 -140.928192) (xy 59.148079 -140.9102)
			(xy 59.223219 -140.900138) (xy 59.299003 -140.898119) (xy 59.374573 -140.904168) (xy 59.449071 -140.918215)
			(xy 59.521654 -140.940101) (xy 59.5915 -140.969578) (xy 59.657817 -141.006313) (xy 59.719853 -141.049888)
			(xy 59.776906 -141.09981) (xy 59.82833 -141.155514) (xy 59.873541 -141.216369) (xy 59.912028 -141.281684)
			(xy 59.943354 -141.35072) (xy 59.967164 -141.422695) (xy 59.983189 -141.496793) (xy 59.991248 -141.572174)
			(xy 59.991752 -141.61008) (xy 61.107831 -141.61008) (xy 61.111866 -141.534376) (xy 61.123925 -141.459531)
			(xy 61.143871 -141.38639) (xy 61.171478 -141.315785) (xy 61.206434 -141.248514) (xy 61.248342 -141.185339)
			(xy 61.296728 -141.126977) (xy 61.351044 -141.074089) (xy 61.410673 -141.027274) (xy 61.474941 -140.987062)
			(xy 61.543118 -140.95391) (xy 61.614434 -140.928192) (xy 61.688079 -140.9102) (xy 61.763219 -140.900138)
			(xy 61.839003 -140.898119) (xy 61.914573 -140.904168) (xy 61.989071 -140.918215) (xy 62.061654 -140.940101)
			(xy 62.1315 -140.969578) (xy 62.197817 -141.006313) (xy 62.259853 -141.049888) (xy 62.316906 -141.09981)
			(xy 62.36833 -141.155514) (xy 62.413541 -141.216369) (xy 62.452028 -141.281684) (xy 62.483354 -141.35072)
			(xy 62.507164 -141.422695) (xy 62.523189 -141.496793) (xy 62.531248 -141.572174) (xy 62.531752 -141.61008)
			(xy 62.531248 -141.647986) (xy 62.523189 -141.723367) (xy 62.507164 -141.797465) (xy 62.483354 -141.86944)
			(xy 62.452028 -141.938476) (xy 62.413541 -142.003791) (xy 62.36833 -142.064646) (xy 62.316906 -142.12035)
			(xy 62.265798 -142.16507) (xy 84.927951 -142.16507) (xy 84.931986 -142.089366) (xy 84.944045 -142.014521)
			(xy 84.963991 -141.94138) (xy 84.991598 -141.870775) (xy 85.026554 -141.803504) (xy 85.068462 -141.740329)
			(xy 85.116848 -141.681967) (xy 85.171164 -141.629079) (xy 85.230793 -141.582264) (xy 85.295061 -141.542052)
			(xy 85.363238 -141.5089) (xy 85.434554 -141.483182) (xy 85.508199 -141.46519) (xy 85.583339 -141.455128)
			(xy 85.659123 -141.453109) (xy 85.734693 -141.459158) (xy 85.809191 -141.473205) (xy 85.881774 -141.495091)
			(xy 85.95162 -141.524568) (xy 86.017937 -141.561303) (xy 86.079973 -141.604878) (xy 86.137026 -141.6548)
			(xy 86.18845 -141.710504) (xy 86.233661 -141.771359) (xy 86.272148 -141.836674) (xy 86.303474 -141.90571)
			(xy 86.327284 -141.977685) (xy 86.343309 -142.051783) (xy 86.351368 -142.127164) (xy 86.351872 -142.16507)
			(xy 87.467951 -142.16507) (xy 87.471986 -142.089366) (xy 87.484045 -142.014521) (xy 87.503991 -141.94138)
			(xy 87.531598 -141.870775) (xy 87.566554 -141.803504) (xy 87.608462 -141.740329) (xy 87.656848 -141.681967)
			(xy 87.711164 -141.629079) (xy 87.770793 -141.582264) (xy 87.835061 -141.542052) (xy 87.903238 -141.5089)
			(xy 87.974554 -141.483182) (xy 88.048199 -141.46519) (xy 88.123339 -141.455128) (xy 88.199123 -141.453109)
			(xy 88.274693 -141.459158) (xy 88.349191 -141.473205) (xy 88.421774 -141.495091) (xy 88.49162 -141.524568)
			(xy 88.557937 -141.561303) (xy 88.619973 -141.604878) (xy 88.677026 -141.6548) (xy 88.72845 -141.710504)
			(xy 88.773661 -141.771359) (xy 88.812148 -141.836674) (xy 88.843474 -141.90571) (xy 88.867284 -141.977685)
			(xy 88.883309 -142.051783) (xy 88.891368 -142.127164) (xy 88.891872 -142.16507) (xy 90.007951 -142.16507)
			(xy 90.011986 -142.089366) (xy 90.024045 -142.014521) (xy 90.043991 -141.94138) (xy 90.071598 -141.870775)
			(xy 90.106554 -141.803504) (xy 90.148462 -141.740329) (xy 90.196848 -141.681967) (xy 90.251164 -141.629079)
			(xy 90.310793 -141.582264) (xy 90.375061 -141.542052) (xy 90.443238 -141.5089) (xy 90.514554 -141.483182)
			(xy 90.588199 -141.46519) (xy 90.663339 -141.455128) (xy 90.739123 -141.453109) (xy 90.814693 -141.459158)
			(xy 90.889191 -141.473205) (xy 90.961774 -141.495091) (xy 91.03162 -141.524568) (xy 91.097937 -141.561303)
			(xy 91.159973 -141.604878) (xy 91.165918 -141.61008) (xy 93.15476 -141.61008) (xy 93.158776 -141.49381)
			(xy 93.170803 -141.378095) (xy 93.190785 -141.263485) (xy 93.218627 -141.150526) (xy 93.254196 -141.039758)
			(xy 93.297322 -140.931707) (xy 93.347799 -140.826889) (xy 93.405388 -140.725804) (xy 93.469814 -140.628932)
			(xy 93.540769 -140.536736) (xy 93.617916 -140.449655) (xy 93.700887 -140.368104) (xy 93.789287 -140.292472)
			(xy 93.882694 -140.223118) (xy 93.980663 -140.160375) (xy 94.082727 -140.104539) (xy 94.188401 -140.055878)
			(xy 94.29718 -140.014624) (xy 94.408545 -139.980973) (xy 94.521968 -139.955085) (xy 94.636905 -139.937084)
			(xy 94.752811 -139.927055) (xy 94.869133 -139.925047) (xy 94.985316 -139.931069) (xy 95.100807 -139.945092)
			(xy 95.215055 -139.96705) (xy 95.327516 -139.996837) (xy 95.437654 -140.034312) (xy 95.544944 -140.079297)
			(xy 95.648875 -140.131576) (xy 95.748951 -140.190901) (xy 95.844697 -140.256989) (xy 95.935654 -140.329525)
			(xy 96.02139 -140.408164) (xy 96.101497 -140.49253) (xy 96.175593 -140.582222) (xy 96.243323 -140.676812)
			(xy 96.304367 -140.77585) (xy 96.358432 -140.878863) (xy 96.405262 -140.98536) (xy 96.444633 -141.094835)
			(xy 96.476357 -141.206765) (xy 96.500283 -141.320617) (xy 96.516297 -141.435849) (xy 96.524324 -141.551911)
			(xy 96.524826 -141.61008) (xy 96.524324 -141.668249) (xy 96.516297 -141.784311) (xy 96.500283 -141.899543)
			(xy 96.476357 -142.013395) (xy 96.444633 -142.125325) (xy 96.405262 -142.2348) (xy 96.358432 -142.341297)
			(xy 96.304367 -142.44431) (xy 96.243323 -142.543348) (xy 96.175593 -142.637938) (xy 96.101497 -142.72763)
			(xy 96.02139 -142.811996) (xy 95.935654 -142.890635) (xy 95.844697 -142.963171) (xy 95.748951 -143.029259)
			(xy 95.648875 -143.088584) (xy 95.544944 -143.140863) (xy 95.437654 -143.185848) (xy 95.327516 -143.223323)
			(xy 95.215055 -143.25311) (xy 95.100807 -143.275068) (xy 94.985316 -143.289091) (xy 94.869133 -143.295113)
			(xy 94.752811 -143.293105) (xy 94.636905 -143.283076) (xy 94.521968 -143.265075) (xy 94.408545 -143.239187)
			(xy 94.29718 -143.205536) (xy 94.188401 -143.164282) (xy 94.082727 -143.115621) (xy 93.980663 -143.059785)
			(xy 93.882694 -142.997042) (xy 93.789287 -142.927688) (xy 93.700887 -142.852056) (xy 93.617916 -142.770505)
			(xy 93.540769 -142.683424) (xy 93.469814 -142.591228) (xy 93.405388 -142.494356) (xy 93.347799 -142.393271)
			(xy 93.297322 -142.288453) (xy 93.254196 -142.180402) (xy 93.218627 -142.069634) (xy 93.190785 -141.956675)
			(xy 93.170803 -141.842065) (xy 93.158776 -141.72635) (xy 93.15476 -141.61008) (xy 91.165918 -141.61008)
			(xy 91.217026 -141.6548) (xy 91.26845 -141.710504) (xy 91.313661 -141.771359) (xy 91.352148 -141.836674)
			(xy 91.383474 -141.90571) (xy 91.407284 -141.977685) (xy 91.423309 -142.051783) (xy 91.431368 -142.127164)
			(xy 91.431872 -142.16507) (xy 91.431368 -142.202976) (xy 91.423309 -142.278357) (xy 91.407284 -142.352455)
			(xy 91.383474 -142.42443) (xy 91.352148 -142.493466) (xy 91.313661 -142.558781) (xy 91.26845 -142.619636)
			(xy 91.217026 -142.67534) (xy 91.159973 -142.725262) (xy 91.097937 -142.768837) (xy 91.03162 -142.805572)
			(xy 90.961774 -142.835049) (xy 90.889191 -142.856935) (xy 90.814693 -142.870982) (xy 90.739123 -142.877031)
			(xy 90.663339 -142.875012) (xy 90.588199 -142.86495) (xy 90.514554 -142.846958) (xy 90.443238 -142.82124)
			(xy 90.375061 -142.788088) (xy 90.310793 -142.747876) (xy 90.251164 -142.701061) (xy 90.196848 -142.648173)
			(xy 90.148462 -142.589811) (xy 90.106554 -142.526636) (xy 90.071598 -142.459365) (xy 90.043991 -142.38876)
			(xy 90.024045 -142.315619) (xy 90.011986 -142.240774) (xy 90.007951 -142.16507) (xy 88.891872 -142.16507)
			(xy 88.891368 -142.202976) (xy 88.883309 -142.278357) (xy 88.867284 -142.352455) (xy 88.843474 -142.42443)
			(xy 88.812148 -142.493466) (xy 88.773661 -142.558781) (xy 88.72845 -142.619636) (xy 88.677026 -142.67534)
			(xy 88.619973 -142.725262) (xy 88.557937 -142.768837) (xy 88.49162 -142.805572) (xy 88.421774 -142.835049)
			(xy 88.349191 -142.856935) (xy 88.274693 -142.870982) (xy 88.199123 -142.877031) (xy 88.123339 -142.875012)
			(xy 88.048199 -142.86495) (xy 87.974554 -142.846958) (xy 87.903238 -142.82124) (xy 87.835061 -142.788088)
			(xy 87.770793 -142.747876) (xy 87.711164 -142.701061) (xy 87.656848 -142.648173) (xy 87.608462 -142.589811)
			(xy 87.566554 -142.526636) (xy 87.531598 -142.459365) (xy 87.503991 -142.38876) (xy 87.484045 -142.315619)
			(xy 87.471986 -142.240774) (xy 87.467951 -142.16507) (xy 86.351872 -142.16507) (xy 86.351368 -142.202976)
			(xy 86.343309 -142.278357) (xy 86.327284 -142.352455) (xy 86.303474 -142.42443) (xy 86.272148 -142.493466)
			(xy 86.233661 -142.558781) (xy 86.18845 -142.619636) (xy 86.137026 -142.67534) (xy 86.079973 -142.725262)
			(xy 86.017937 -142.768837) (xy 85.95162 -142.805572) (xy 85.881774 -142.835049) (xy 85.809191 -142.856935)
			(xy 85.734693 -142.870982) (xy 85.659123 -142.877031) (xy 85.583339 -142.875012) (xy 85.508199 -142.86495)
			(xy 85.434554 -142.846958) (xy 85.363238 -142.82124) (xy 85.295061 -142.788088) (xy 85.230793 -142.747876)
			(xy 85.171164 -142.701061) (xy 85.116848 -142.648173) (xy 85.068462 -142.589811) (xy 85.026554 -142.526636)
			(xy 84.991598 -142.459365) (xy 84.963991 -142.38876) (xy 84.944045 -142.315619) (xy 84.931986 -142.240774)
			(xy 84.927951 -142.16507) (xy 62.265798 -142.16507) (xy 62.259853 -142.170272) (xy 62.197817 -142.213847)
			(xy 62.1315 -142.250582) (xy 62.061654 -142.280059) (xy 61.989071 -142.301945) (xy 61.914573 -142.315992)
			(xy 61.839003 -142.322041) (xy 61.763219 -142.320022) (xy 61.688079 -142.30996) (xy 61.614434 -142.291968)
			(xy 61.543118 -142.26625) (xy 61.474941 -142.233098) (xy 61.410673 -142.192886) (xy 61.351044 -142.146071)
			(xy 61.296728 -142.093183) (xy 61.248342 -142.034821) (xy 61.206434 -141.971646) (xy 61.171478 -141.904375)
			(xy 61.143871 -141.83377) (xy 61.123925 -141.760629) (xy 61.111866 -141.685784) (xy 61.107831 -141.61008)
			(xy 59.991752 -141.61008) (xy 59.991248 -141.647986) (xy 59.983189 -141.723367) (xy 59.967164 -141.797465)
			(xy 59.943354 -141.86944) (xy 59.912028 -141.938476) (xy 59.873541 -142.003791) (xy 59.82833 -142.064646)
			(xy 59.776906 -142.12035) (xy 59.719853 -142.170272) (xy 59.657817 -142.213847) (xy 59.5915 -142.250582)
			(xy 59.521654 -142.280059) (xy 59.449071 -142.301945) (xy 59.374573 -142.315992) (xy 59.299003 -142.322041)
			(xy 59.223219 -142.320022) (xy 59.148079 -142.30996) (xy 59.074434 -142.291968) (xy 59.003118 -142.26625)
			(xy 58.934941 -142.233098) (xy 58.870673 -142.192886) (xy 58.811044 -142.146071) (xy 58.756728 -142.093183)
			(xy 58.708342 -142.034821) (xy 58.666434 -141.971646) (xy 58.631478 -141.904375) (xy 58.603871 -141.83377)
			(xy 58.583925 -141.760629) (xy 58.571866 -141.685784) (xy 58.567831 -141.61008) (xy 57.451752 -141.61008)
			(xy 57.451248 -141.647986) (xy 57.443189 -141.723367) (xy 57.427164 -141.797465) (xy 57.403354 -141.86944)
			(xy 57.372028 -141.938476) (xy 57.333541 -142.003791) (xy 57.28833 -142.064646) (xy 57.236906 -142.12035)
			(xy 57.179853 -142.170272) (xy 57.117817 -142.213847) (xy 57.0515 -142.250582) (xy 56.981654 -142.280059)
			(xy 56.909071 -142.301945) (xy 56.834573 -142.315992) (xy 56.759003 -142.322041) (xy 56.683219 -142.320022)
			(xy 56.608079 -142.30996) (xy 56.534434 -142.291968) (xy 56.463118 -142.26625) (xy 56.394941 -142.233098)
			(xy 56.330673 -142.192886) (xy 56.271044 -142.146071) (xy 56.216728 -142.093183) (xy 56.168342 -142.034821)
			(xy 56.126434 -141.971646) (xy 56.091478 -141.904375) (xy 56.063871 -141.83377) (xy 56.043925 -141.760629)
			(xy 56.031866 -141.685784) (xy 56.027831 -141.61008) (xy 54.911752 -141.61008) (xy 54.911248 -141.647986)
			(xy 54.903189 -141.723367) (xy 54.887164 -141.797465) (xy 54.863354 -141.86944) (xy 54.832028 -141.938476)
			(xy 54.793541 -142.003791) (xy 54.74833 -142.064646) (xy 54.696906 -142.12035) (xy 54.639853 -142.170272)
			(xy 54.577817 -142.213847) (xy 54.5115 -142.250582) (xy 54.441654 -142.280059) (xy 54.369071 -142.301945)
			(xy 54.294573 -142.315992) (xy 54.219003 -142.322041) (xy 54.143219 -142.320022) (xy 54.068079 -142.30996)
			(xy 53.994434 -142.291968) (xy 53.923118 -142.26625) (xy 53.854941 -142.233098) (xy 53.790673 -142.192886)
			(xy 53.731044 -142.146071) (xy 53.676728 -142.093183) (xy 53.628342 -142.034821) (xy 53.586434 -141.971646)
			(xy 53.551478 -141.904375) (xy 53.523871 -141.83377) (xy 53.503925 -141.760629) (xy 53.491866 -141.685784)
			(xy 53.487831 -141.61008) (xy 52.371752 -141.61008) (xy 52.371248 -141.647986) (xy 52.363189 -141.723367)
			(xy 52.347164 -141.797465) (xy 52.323354 -141.86944) (xy 52.292028 -141.938476) (xy 52.253541 -142.003791)
			(xy 52.20833 -142.064646) (xy 52.156906 -142.12035) (xy 52.099853 -142.170272) (xy 52.037817 -142.213847)
			(xy 51.9715 -142.250582) (xy 51.901654 -142.280059) (xy 51.829071 -142.301945) (xy 51.754573 -142.315992)
			(xy 51.679003 -142.322041) (xy 51.603219 -142.320022) (xy 51.528079 -142.30996) (xy 51.454434 -142.291968)
			(xy 51.383118 -142.26625) (xy 51.314941 -142.233098) (xy 51.250673 -142.192886) (xy 51.191044 -142.146071)
			(xy 51.136728 -142.093183) (xy 51.088342 -142.034821) (xy 51.046434 -141.971646) (xy 51.011478 -141.904375)
			(xy 50.983871 -141.83377) (xy 50.963925 -141.760629) (xy 50.951866 -141.685784) (xy 50.947831 -141.61008)
			(xy 49.831752 -141.61008) (xy 49.831248 -141.647986) (xy 49.823189 -141.723367) (xy 49.807164 -141.797465)
			(xy 49.783354 -141.86944) (xy 49.752028 -141.938476) (xy 49.713541 -142.003791) (xy 49.66833 -142.064646)
			(xy 49.616906 -142.12035) (xy 49.559853 -142.170272) (xy 49.497817 -142.213847) (xy 49.4315 -142.250582)
			(xy 49.361654 -142.280059) (xy 49.289071 -142.301945) (xy 49.214573 -142.315992) (xy 49.139003 -142.322041)
			(xy 49.063219 -142.320022) (xy 48.988079 -142.30996) (xy 48.914434 -142.291968) (xy 48.843118 -142.26625)
			(xy 48.774941 -142.233098) (xy 48.710673 -142.192886) (xy 48.651044 -142.146071) (xy 48.596728 -142.093183)
			(xy 48.548342 -142.034821) (xy 48.506434 -141.971646) (xy 48.471478 -141.904375) (xy 48.443871 -141.83377)
			(xy 48.423925 -141.760629) (xy 48.411866 -141.685784) (xy 48.407831 -141.61008) (xy 47.291752 -141.61008)
			(xy 47.291248 -141.647986) (xy 47.283189 -141.723367) (xy 47.267164 -141.797465) (xy 47.243354 -141.86944)
			(xy 47.212028 -141.938476) (xy 47.173541 -142.003791) (xy 47.12833 -142.064646) (xy 47.076906 -142.12035)
			(xy 47.019853 -142.170272) (xy 46.957817 -142.213847) (xy 46.8915 -142.250582) (xy 46.821654 -142.280059)
			(xy 46.749071 -142.301945) (xy 46.674573 -142.315992) (xy 46.599003 -142.322041) (xy 46.523219 -142.320022)
			(xy 46.448079 -142.30996) (xy 46.374434 -142.291968) (xy 46.303118 -142.26625) (xy 46.234941 -142.233098)
			(xy 46.170673 -142.192886) (xy 46.111044 -142.146071) (xy 46.056728 -142.093183) (xy 46.008342 -142.034821)
			(xy 45.966434 -141.971646) (xy 45.931478 -141.904375) (xy 45.903871 -141.83377) (xy 45.883925 -141.760629)
			(xy 45.871866 -141.685784) (xy 45.867831 -141.61008) (xy 44.751752 -141.61008) (xy 44.751752 -142.321788)
			(xy 43.328336 -142.321788) (xy 43.328336 -140.898372) (xy 43.055945 -140.898372) (xy 43.054014 -140.903555)
			(xy 43.005523 -141.010294) (xy 42.949712 -141.113395) (xy 42.886853 -141.212356) (xy 42.817252 -141.306696)
			(xy 42.741246 -141.395958) (xy 42.659204 -141.479706) (xy 42.571527 -141.557535) (xy 42.47864 -141.629064)
			(xy 42.380994 -141.693948) (xy 42.279065 -141.75187) (xy 42.173347 -141.802549) (xy 42.064355 -141.845738)
			(xy 41.952619 -141.881228) (xy 41.838681 -141.908845) (xy 41.723096 -141.928457) (xy 41.606425 -141.939967)
			(xy 41.489236 -141.943319) (xy 41.372098 -141.938497) (xy 41.25558 -141.925525) (xy 41.14025 -141.904466)
			(xy 41.026668 -141.875421) (xy 40.915385 -141.838533) (xy 40.806943 -141.79398) (xy 40.70187 -141.74198)
			(xy 40.600675 -141.682784) (xy 40.50385 -141.616681) (xy 40.411868 -141.543992) (xy 40.325173 -141.46507)
			(xy 40.244189 -141.380299) (xy 40.169308 -141.290091) (xy 40.100895 -141.194885) (xy 40.039282 -141.095143)
			(xy 39.984769 -140.991351) (xy 39.937621 -140.884012) (xy 39.898066 -140.773649) (xy 39.866298 -140.660798)
			(xy 39.842471 -140.546008) (xy 39.826699 -140.429836) (xy 39.819061 -140.312848) (xy 39.818818 -140.254228)
			(xy 27.89936 -140.254228) (xy 27.89936 -141.293358) (xy 29.519874 -141.293358) (xy 29.519874 -141.206458)
			(xy 29.527892 -141.119929) (xy 29.54386 -141.034509) (xy 29.567641 -140.950927) (xy 29.599033 -140.869895)
			(xy 29.637767 -140.792106) (xy 29.683514 -140.718222) (xy 29.735883 -140.648875) (xy 29.794427 -140.584655)
			(xy 29.858647 -140.526111) (xy 29.927994 -140.473742) (xy 30.001878 -140.427995) (xy 30.079667 -140.389261)
			(xy 30.160699 -140.357869) (xy 30.244281 -140.334088) (xy 30.329701 -140.31812) (xy 30.41623 -140.310102)
			(xy 30.50313 -140.310102) (xy 30.589659 -140.31812) (xy 30.675079 -140.334088) (xy 30.758661 -140.357869)
			(xy 30.839693 -140.389261) (xy 30.917482 -140.427995) (xy 30.991366 -140.473742) (xy 31.060713 -140.526111)
			(xy 31.124933 -140.584655) (xy 31.183477 -140.648875) (xy 31.235846 -140.718222) (xy 31.281593 -140.792106)
			(xy 31.320327 -140.869895) (xy 31.351719 -140.950927) (xy 31.3755 -141.034509) (xy 31.391468 -141.119929)
			(xy 31.399486 -141.206458) (xy 31.399988 -141.249908) (xy 31.399486 -141.293358) (xy 34.599874 -141.293358)
			(xy 34.599874 -141.206458) (xy 34.607892 -141.119929) (xy 34.62386 -141.034509) (xy 34.647641 -140.950927)
			(xy 34.679033 -140.869895) (xy 34.717767 -140.792106) (xy 34.763514 -140.718222) (xy 34.815883 -140.648875)
			(xy 34.874427 -140.584655) (xy 34.938647 -140.526111) (xy 35.007994 -140.473742) (xy 35.081878 -140.427995)
			(xy 35.159667 -140.389261) (xy 35.240699 -140.357869) (xy 35.324281 -140.334088) (xy 35.409701 -140.31812)
			(xy 35.49623 -140.310102) (xy 35.58313 -140.310102) (xy 35.669659 -140.31812) (xy 35.755079 -140.334088)
			(xy 35.838661 -140.357869) (xy 35.919693 -140.389261) (xy 35.997482 -140.427995) (xy 36.071366 -140.473742)
			(xy 36.140713 -140.526111) (xy 36.204933 -140.584655) (xy 36.263477 -140.648875) (xy 36.315846 -140.718222)
			(xy 36.361593 -140.792106) (xy 36.400327 -140.869895) (xy 36.431719 -140.950927) (xy 36.4555 -141.034509)
			(xy 36.471468 -141.119929) (xy 36.479486 -141.206458) (xy 36.479988 -141.249908) (xy 36.479486 -141.293358)
			(xy 36.471468 -141.379887) (xy 36.4555 -141.465307) (xy 36.431719 -141.548889) (xy 36.400327 -141.629921)
			(xy 36.361593 -141.70771) (xy 36.315846 -141.781594) (xy 36.263477 -141.850941) (xy 36.204933 -141.915161)
			(xy 36.140713 -141.973705) (xy 36.071366 -142.026074) (xy 35.997482 -142.071821) (xy 35.919693 -142.110555)
			(xy 35.838661 -142.141947) (xy 35.755079 -142.165728) (xy 35.669659 -142.181696) (xy 35.58313 -142.189714)
			(xy 35.49623 -142.189714) (xy 35.409701 -142.181696) (xy 35.324281 -142.165728) (xy 35.240699 -142.141947)
			(xy 35.159667 -142.110555) (xy 35.081878 -142.071821) (xy 35.007994 -142.026074) (xy 34.938647 -141.973705)
			(xy 34.874427 -141.915161) (xy 34.815883 -141.850941) (xy 34.763514 -141.781594) (xy 34.717767 -141.70771)
			(xy 34.679033 -141.629921) (xy 34.647641 -141.548889) (xy 34.62386 -141.465307) (xy 34.607892 -141.379887)
			(xy 34.599874 -141.293358) (xy 31.399486 -141.293358) (xy 31.391468 -141.379887) (xy 31.3755 -141.465307)
			(xy 31.351719 -141.548889) (xy 31.320327 -141.629921) (xy 31.281593 -141.70771) (xy 31.235846 -141.781594)
			(xy 31.183477 -141.850941) (xy 31.124933 -141.915161) (xy 31.060713 -141.973705) (xy 30.991366 -142.026074)
			(xy 30.917482 -142.071821) (xy 30.839693 -142.110555) (xy 30.758661 -142.141947) (xy 30.675079 -142.165728)
			(xy 30.589659 -142.181696) (xy 30.50313 -142.189714) (xy 30.41623 -142.189714) (xy 30.329701 -142.181696)
			(xy 30.244281 -142.165728) (xy 30.160699 -142.141947) (xy 30.079667 -142.110555) (xy 30.001878 -142.071821)
			(xy 29.927994 -142.026074) (xy 29.858647 -141.973705) (xy 29.794427 -141.915161) (xy 29.735883 -141.850941)
			(xy 29.683514 -141.781594) (xy 29.637767 -141.70771) (xy 29.599033 -141.629921) (xy 29.567641 -141.548889)
			(xy 29.54386 -141.465307) (xy 29.527892 -141.379887) (xy 29.519874 -141.293358) (xy 27.89936 -141.293358)
			(xy 27.89936 -146.428714) (xy 80.994502 -146.428714) (xy 80.998573 -146.373092) (xy 81.010699 -146.318655)
			(xy 81.030622 -146.266564) (xy 81.057918 -146.217929) (xy 81.092004 -146.173786) (xy 81.132153 -146.135077)
			(xy 81.177511 -146.102626) (xy 81.227111 -146.077125) (xy 81.279895 -146.059118) (xy 81.334738 -146.048988)
			(xy 81.390472 -146.046951) (xy 81.445909 -146.053051) (xy 81.499866 -146.067157) (xy 81.551195 -146.088969)
			(xy 81.598801 -146.118023) (xy 81.641669 -146.153698) (xy 81.678886 -146.195235) (xy 81.709659 -146.241748)
			(xy 81.733331 -146.292245) (xy 81.749399 -146.345652) (xy 81.757519 -146.400828) (xy 81.758028 -146.428714)
			(xy 81.757519 -146.4566) (xy 81.749399 -146.511776) (xy 81.733331 -146.565183) (xy 81.709659 -146.61568)
			(xy 81.678886 -146.662193) (xy 81.641669 -146.70373) (xy 81.598801 -146.739405) (xy 81.551195 -146.768459)
			(xy 81.499866 -146.790271) (xy 81.445909 -146.804377) (xy 81.427415 -146.806412) (xy 85.1187 -146.806412)
			(xy 85.122771 -146.75079) (xy 85.134897 -146.696353) (xy 85.15482 -146.644262) (xy 85.182116 -146.595627)
			(xy 85.216202 -146.551484) (xy 85.256351 -146.512775) (xy 85.301709 -146.480324) (xy 85.351309 -146.454823)
			(xy 85.404093 -146.436816) (xy 85.458936 -146.426686) (xy 85.51467 -146.424649) (xy 85.570107 -146.430749)
			(xy 85.624064 -146.444855) (xy 85.675393 -146.466667) (xy 85.722999 -146.495721) (xy 85.765867 -146.531396)
			(xy 85.803084 -146.572933) (xy 85.833857 -146.619446) (xy 85.857529 -146.669943) (xy 85.873597 -146.72335)
			(xy 85.881717 -146.778526) (xy 85.882226 -146.806412) (xy 85.881717 -146.834298) (xy 85.873597 -146.889474)
			(xy 85.857529 -146.942881) (xy 85.833857 -146.993378) (xy 85.803084 -147.039891) (xy 85.765867 -147.081428)
			(xy 85.722999 -147.117103) (xy 85.675393 -147.146157) (xy 85.624064 -147.167969) (xy 85.570107 -147.182075)
			(xy 85.51467 -147.188175) (xy 85.458936 -147.186138) (xy 85.404093 -147.176008) (xy 85.351309 -147.158001)
			(xy 85.301709 -147.1325) (xy 85.256351 -147.100049) (xy 85.216202 -147.06134) (xy 85.182116 -147.017197)
			(xy 85.15482 -146.968562) (xy 85.134897 -146.916471) (xy 85.122771 -146.862034) (xy 85.1187 -146.806412)
			(xy 81.427415 -146.806412) (xy 81.390472 -146.810477) (xy 81.334738 -146.80844) (xy 81.279895 -146.79831)
			(xy 81.227111 -146.780303) (xy 81.177511 -146.754802) (xy 81.132153 -146.722351) (xy 81.092004 -146.683642)
			(xy 81.057918 -146.639499) (xy 81.030622 -146.590864) (xy 81.010699 -146.538773) (xy 80.998573 -146.484336)
			(xy 80.994502 -146.428714) (xy 27.89936 -146.428714) (xy 27.89936 -147.352004) (xy 86.714582 -147.352004)
			(xy 86.718653 -147.296382) (xy 86.730779 -147.241945) (xy 86.750702 -147.189854) (xy 86.777998 -147.141219)
			(xy 86.812084 -147.097076) (xy 86.852233 -147.058367) (xy 86.897591 -147.025916) (xy 86.947191 -147.000415)
			(xy 86.999975 -146.982408) (xy 87.054818 -146.972278) (xy 87.110552 -146.970241) (xy 87.165989 -146.976341)
			(xy 87.219946 -146.990447) (xy 87.271275 -147.012259) (xy 87.318881 -147.041313) (xy 87.361749 -147.076988)
			(xy 87.398966 -147.118525) (xy 87.429739 -147.165038) (xy 87.453411 -147.215535) (xy 87.469479 -147.268942)
			(xy 87.477599 -147.324118) (xy 87.478108 -147.352004) (xy 87.477599 -147.37989) (xy 87.469479 -147.435066)
			(xy 87.453411 -147.488473) (xy 87.429739 -147.53897) (xy 87.398966 -147.585483) (xy 87.361749 -147.62702)
			(xy 87.318881 -147.662695) (xy 87.271275 -147.691749) (xy 87.219946 -147.713561) (xy 87.165989 -147.727667)
			(xy 87.110552 -147.733767) (xy 87.054818 -147.73173) (xy 86.999975 -147.7216) (xy 86.947191 -147.703593)
			(xy 86.897591 -147.678092) (xy 86.852233 -147.645641) (xy 86.812084 -147.606932) (xy 86.777998 -147.562789)
			(xy 86.750702 -147.514154) (xy 86.730779 -147.462063) (xy 86.718653 -147.407626) (xy 86.714582 -147.352004)
			(xy 27.89936 -147.352004) (xy 27.89936 -147.856194) (xy 80.721452 -147.856194) (xy 80.725523 -147.800572)
			(xy 80.737649 -147.746135) (xy 80.757572 -147.694044) (xy 80.784868 -147.645409) (xy 80.818954 -147.601266)
			(xy 80.859103 -147.562557) (xy 80.904461 -147.530106) (xy 80.954061 -147.504605) (xy 81.006845 -147.486598)
			(xy 81.061688 -147.476468) (xy 81.117422 -147.474431) (xy 81.172859 -147.480531) (xy 81.226816 -147.494637)
			(xy 81.278145 -147.516449) (xy 81.325751 -147.545503) (xy 81.368619 -147.581178) (xy 81.405836 -147.622715)
			(xy 81.436609 -147.669228) (xy 81.460281 -147.719725) (xy 81.476349 -147.773132) (xy 81.484469 -147.828308)
			(xy 81.484978 -147.856194) (xy 81.484469 -147.88408) (xy 81.476349 -147.939256) (xy 81.460281 -147.992663)
			(xy 81.436609 -148.04316) (xy 81.405836 -148.089673) (xy 81.368619 -148.13121) (xy 81.325751 -148.166885)
			(xy 81.278145 -148.195939) (xy 81.226816 -148.217751) (xy 81.172859 -148.231857) (xy 81.117422 -148.237957)
			(xy 81.061688 -148.23592) (xy 81.006845 -148.22579) (xy 80.954061 -148.207783) (xy 80.904461 -148.182282)
			(xy 80.859103 -148.149831) (xy 80.818954 -148.111122) (xy 80.784868 -148.066979) (xy 80.757572 -148.018344)
			(xy 80.737649 -147.966253) (xy 80.725523 -147.911816) (xy 80.721452 -147.856194) (xy 27.89936 -147.856194)
			(xy 27.89936 -148.51761) (xy 83.345526 -148.51761) (xy 83.349597 -148.461988) (xy 83.361723 -148.407551)
			(xy 83.381646 -148.35546) (xy 83.408942 -148.306825) (xy 83.443028 -148.262682) (xy 83.483177 -148.223973)
			(xy 83.528535 -148.191522) (xy 83.578135 -148.166021) (xy 83.630919 -148.148014) (xy 83.685762 -148.137884)
			(xy 83.741496 -148.135847) (xy 83.796933 -148.141947) (xy 83.85089 -148.156053) (xy 83.902219 -148.177865)
			(xy 83.949825 -148.206919) (xy 83.992693 -148.242594) (xy 84.02991 -148.284131) (xy 84.060683 -148.330644)
			(xy 84.084355 -148.381141) (xy 84.100423 -148.434548) (xy 84.108543 -148.489724) (xy 84.109052 -148.51761)
			(xy 84.108543 -148.545496) (xy 84.100423 -148.600672) (xy 84.084355 -148.654079) (xy 84.060683 -148.704576)
			(xy 84.02991 -148.751089) (xy 83.992693 -148.792626) (xy 83.949825 -148.828301) (xy 83.902219 -148.857355)
			(xy 83.85089 -148.879167) (xy 83.796933 -148.893273) (xy 83.741496 -148.899373) (xy 83.685762 -148.897336)
			(xy 83.630919 -148.887206) (xy 83.578135 -148.869199) (xy 83.528535 -148.843698) (xy 83.483177 -148.811247)
			(xy 83.443028 -148.772538) (xy 83.408942 -148.728395) (xy 83.381646 -148.67976) (xy 83.361723 -148.627669)
			(xy 83.349597 -148.573232) (xy 83.345526 -148.51761) (xy 27.89936 -148.51761) (xy 27.89936 -148.90242)
			(xy 85.31428 -148.90242) (xy 85.318351 -148.846798) (xy 85.330477 -148.792361) (xy 85.3504 -148.74027)
			(xy 85.377696 -148.691635) (xy 85.411782 -148.647492) (xy 85.451931 -148.608783) (xy 85.497289 -148.576332)
			(xy 85.546889 -148.550831) (xy 85.599673 -148.532824) (xy 85.654516 -148.522694) (xy 85.71025 -148.520657)
			(xy 85.765687 -148.526757) (xy 85.819644 -148.540863) (xy 85.870973 -148.562675) (xy 85.918579 -148.591729)
			(xy 85.961447 -148.627404) (xy 85.998664 -148.668941) (xy 86.029437 -148.715454) (xy 86.053109 -148.765951)
			(xy 86.069177 -148.819358) (xy 86.077297 -148.874534) (xy 86.077806 -148.90242) (xy 86.077297 -148.930306)
			(xy 86.069177 -148.985482) (xy 86.053109 -149.038889) (xy 86.029437 -149.089386) (xy 85.998664 -149.135899)
			(xy 85.961447 -149.177436) (xy 85.918579 -149.213111) (xy 85.870973 -149.242165) (xy 85.819644 -149.263977)
			(xy 85.765687 -149.278083) (xy 85.71025 -149.284183) (xy 85.654516 -149.282146) (xy 85.599673 -149.272016)
			(xy 85.546889 -149.254009) (xy 85.497289 -149.228508) (xy 85.451931 -149.196057) (xy 85.411782 -149.157348)
			(xy 85.377696 -149.113205) (xy 85.3504 -149.06457) (xy 85.330477 -149.012479) (xy 85.318351 -148.958042)
			(xy 85.31428 -148.90242) (xy 27.89936 -148.90242) (xy 27.89936 -149.4155) (xy 80.319878 -149.4155)
			(xy 80.323949 -149.359878) (xy 80.336075 -149.305441) (xy 80.355998 -149.25335) (xy 80.383294 -149.204715)
			(xy 80.41738 -149.160572) (xy 80.457529 -149.121863) (xy 80.502887 -149.089412) (xy 80.552487 -149.063911)
			(xy 80.605271 -149.045904) (xy 80.660114 -149.035774) (xy 80.715848 -149.033737) (xy 80.771285 -149.039837)
			(xy 80.825242 -149.053943) (xy 80.876571 -149.075755) (xy 80.924177 -149.104809) (xy 80.967045 -149.140484)
			(xy 81.004262 -149.182021) (xy 81.035035 -149.228534) (xy 81.058707 -149.279031) (xy 81.074775 -149.332438)
			(xy 81.082895 -149.387614) (xy 81.083404 -149.4155) (xy 81.082895 -149.443386) (xy 81.074775 -149.498562)
			(xy 81.058707 -149.551969) (xy 81.035035 -149.602466) (xy 81.004262 -149.648979) (xy 80.967045 -149.690516)
			(xy 80.924177 -149.726191) (xy 80.876571 -149.755245) (xy 80.825242 -149.777057) (xy 80.771285 -149.791163)
			(xy 80.715848 -149.797263) (xy 80.660114 -149.795226) (xy 80.605271 -149.785096) (xy 80.552487 -149.767089)
			(xy 80.502887 -149.741588) (xy 80.457529 -149.709137) (xy 80.41738 -149.670428) (xy 80.383294 -149.626285)
			(xy 80.355998 -149.57765) (xy 80.336075 -149.525559) (xy 80.323949 -149.471122) (xy 80.319878 -149.4155)
			(xy 27.89936 -149.4155) (xy 27.89936 -149.81174) (xy 83.9122 -149.81174) (xy 83.916271 -149.756118)
			(xy 83.928397 -149.701681) (xy 83.94832 -149.64959) (xy 83.975616 -149.600955) (xy 84.009702 -149.556812)
			(xy 84.049851 -149.518103) (xy 84.095209 -149.485652) (xy 84.144809 -149.460151) (xy 84.197593 -149.442144)
			(xy 84.252436 -149.432014) (xy 84.30817 -149.429977) (xy 84.363607 -149.436077) (xy 84.417564 -149.450183)
			(xy 84.468893 -149.471995) (xy 84.516499 -149.501049) (xy 84.559367 -149.536724) (xy 84.596584 -149.578261)
			(xy 84.627357 -149.624774) (xy 84.651029 -149.675271) (xy 84.667097 -149.728678) (xy 84.675217 -149.783854)
			(xy 84.675726 -149.81174) (xy 84.675217 -149.839626) (xy 84.667097 -149.894802) (xy 84.651029 -149.948209)
			(xy 84.627357 -149.998706) (xy 84.596584 -150.045219) (xy 84.559367 -150.086756) (xy 84.516499 -150.122431)
			(xy 84.468893 -150.151485) (xy 84.417564 -150.173297) (xy 84.363607 -150.187403) (xy 84.30817 -150.193503)
			(xy 84.252436 -150.191466) (xy 84.197593 -150.181336) (xy 84.144809 -150.163329) (xy 84.095209 -150.137828)
			(xy 84.049851 -150.105377) (xy 84.009702 -150.066668) (xy 83.975616 -150.022525) (xy 83.94832 -149.97389)
			(xy 83.928397 -149.921799) (xy 83.916271 -149.867362) (xy 83.9122 -149.81174) (xy 27.89936 -149.81174)
			(xy 27.89936 -150.88342) (xy 57.520655 -150.88342) (xy 57.52454 -150.829061) (xy 57.536122 -150.775808)
			(xy 57.555165 -150.724746) (xy 57.581282 -150.676913) (xy 57.613941 -150.633285) (xy 57.652476 -150.594748)
			(xy 57.696103 -150.562088) (xy 57.743935 -150.53597) (xy 57.794997 -150.516926) (xy 57.84825 -150.505342)
			(xy 57.902609 -150.501455) (xy 57.956968 -150.505344) (xy 58.01022 -150.51693) (xy 58.061281 -150.535978)
			(xy 58.109111 -150.562098) (xy 58.131202 -150.578058) (xy 58.150214 -150.591654) (xy 58.192097 -150.612386)
			(xy 58.237065 -150.625112) (xy 58.283602 -150.629402) (xy 58.330139 -150.625112) (xy 58.375107 -150.612386)
			(xy 58.41699 -150.591654) (xy 58.436002 -150.578058) (xy 58.458122 -150.562144) (xy 58.505945 -150.536028)
			(xy 58.556999 -150.516984) (xy 58.610243 -150.5054) (xy 58.664593 -150.501512) (xy 58.718944 -150.505398)
			(xy 58.772189 -150.516981) (xy 58.823243 -150.536023) (xy 58.871067 -150.562137) (xy 58.914688 -150.594792)
			(xy 58.953217 -150.633323) (xy 58.98587 -150.676945) (xy 59.011983 -150.72477) (xy 59.031023 -150.775825)
			(xy 59.042604 -150.829069) (xy 59.046488 -150.88342) (xy 59.407348 -150.88342) (xy 59.411233 -150.82906)
			(xy 59.422816 -150.775805) (xy 59.44186 -150.724741) (xy 59.467977 -150.676907) (xy 59.500637 -150.633278)
			(xy 59.539174 -150.59474) (xy 59.582803 -150.56208) (xy 59.630637 -150.535962) (xy 59.6817 -150.516917)
			(xy 59.734955 -150.505334) (xy 59.789316 -150.501448) (xy 59.843676 -150.505338) (xy 59.89693 -150.516926)
			(xy 59.947992 -150.535975) (xy 59.995823 -150.562097) (xy 60.017914 -150.578058) (xy 60.036926 -150.591654)
			(xy 60.078809 -150.612386) (xy 60.123777 -150.625112) (xy 60.170314 -150.629402) (xy 60.216851 -150.625112)
			(xy 60.261819 -150.612386) (xy 60.303702 -150.591654) (xy 60.322714 -150.578058) (xy 60.344834 -150.562145)
			(xy 60.392656 -150.536031) (xy 60.443709 -150.516989) (xy 60.496951 -150.505406) (xy 60.5513 -150.501519)
			(xy 60.605649 -150.505406) (xy 60.658892 -150.516989) (xy 60.709944 -150.536031) (xy 60.757767 -150.562145)
			(xy 60.801386 -150.5948) (xy 60.839914 -150.63333) (xy 60.872566 -150.676951) (xy 60.898677 -150.724775)
			(xy 60.917717 -150.775828) (xy 60.929297 -150.829071) (xy 60.933181 -150.88342) (xy 61.648483 -150.88342)
			(xy 61.652367 -150.829067) (xy 61.663947 -150.77582) (xy 61.682988 -150.724764) (xy 61.7091 -150.676936)
			(xy 61.741754 -150.633312) (xy 61.780283 -150.594778) (xy 61.823904 -150.562121) (xy 61.871729 -150.536003)
			(xy 61.922784 -150.516958) (xy 61.97603 -150.505373) (xy 62.030383 -150.501483) (xy 62.084736 -150.505368)
			(xy 62.137982 -150.516948) (xy 62.189039 -150.535989) (xy 62.236866 -150.562102) (xy 62.258956 -150.578058)
			(xy 62.277968 -150.591654) (xy 62.319851 -150.612386) (xy 62.364819 -150.625112) (xy 62.411356 -150.629402)
			(xy 62.457893 -150.625112) (xy 62.502861 -150.612386) (xy 62.544744 -150.591654) (xy 62.563756 -150.578058)
			(xy 62.585877 -150.56214) (xy 62.633704 -150.536017) (xy 62.684761 -150.516967) (xy 62.738011 -150.505377)
			(xy 62.792367 -150.501484) (xy 62.846725 -150.505368) (xy 62.899976 -150.516948) (xy 62.951037 -150.53599)
			(xy 62.998868 -150.562105) (xy 63.042495 -150.594762) (xy 63.08103 -150.633296) (xy 63.113689 -150.676922)
			(xy 63.139805 -150.724752) (xy 63.158848 -150.775812) (xy 63.170431 -150.829063) (xy 63.174316 -150.88342)
			(xy 63.552332 -150.88342) (xy 63.556218 -150.829056) (xy 63.567802 -150.775798) (xy 63.586847 -150.724731)
			(xy 63.612967 -150.676894) (xy 63.64563 -150.633262) (xy 63.68417 -150.594723) (xy 63.727803 -150.562062)
			(xy 63.77564 -150.535943) (xy 63.826708 -150.516899) (xy 63.879966 -150.505317) (xy 63.93433 -150.501432)
			(xy 63.988694 -150.505325) (xy 64.041951 -150.516916) (xy 64.093015 -150.535968) (xy 64.140848 -150.562095)
			(xy 64.16294 -150.578058) (xy 64.181952 -150.591654) (xy 64.223835 -150.612386) (xy 64.268803 -150.625112)
			(xy 64.31534 -150.629402) (xy 64.361877 -150.625112) (xy 64.406845 -150.612386) (xy 64.448728 -150.591654)
			(xy 64.46774 -150.578058) (xy 64.489859 -150.562147) (xy 64.53768 -150.536037) (xy 64.58873 -150.516999)
			(xy 64.641969 -150.505419) (xy 64.696315 -150.501535) (xy 64.750661 -150.505424) (xy 64.803899 -150.517007)
			(xy 64.854948 -150.53605) (xy 64.902766 -150.562164) (xy 64.946382 -150.594817) (xy 64.984906 -150.633345)
			(xy 65.017556 -150.676964) (xy 65.043665 -150.724785) (xy 65.062703 -150.775835) (xy 65.074281 -150.829075)
			(xy 65.078165 -150.88342) (xy 65.074276 -150.937766) (xy 65.062691 -150.991004) (xy 65.043648 -151.042052)
			(xy 65.017533 -151.089871) (xy 64.98488 -151.133486) (xy 64.946351 -151.17201) (xy 64.902732 -151.204658)
			(xy 64.887812 -151.212804) (xy 84.390482 -151.212804) (xy 84.394553 -151.157182) (xy 84.406679 -151.102745)
			(xy 84.426602 -151.050654) (xy 84.453898 -151.002019) (xy 84.487984 -150.957876) (xy 84.528133 -150.919167)
			(xy 84.573491 -150.886716) (xy 84.623091 -150.861215) (xy 84.675875 -150.843208) (xy 84.730718 -150.833078)
			(xy 84.786452 -150.831041) (xy 84.841889 -150.837141) (xy 84.895846 -150.851247) (xy 84.947175 -150.873059)
			(xy 84.994781 -150.902113) (xy 85.037649 -150.937788) (xy 85.074866 -150.979325) (xy 85.105639 -151.025838)
			(xy 85.129311 -151.076335) (xy 85.145379 -151.129742) (xy 85.153499 -151.184918) (xy 85.154008 -151.212804)
			(xy 85.153499 -151.24069) (xy 85.145379 -151.295866) (xy 85.129311 -151.349273) (xy 85.105639 -151.39977)
			(xy 85.074866 -151.446283) (xy 85.037649 -151.48782) (xy 84.994781 -151.523495) (xy 84.947175 -151.552549)
			(xy 84.895846 -151.574361) (xy 84.841889 -151.588467) (xy 84.786452 -151.594567) (xy 84.730718 -151.59253)
			(xy 84.675875 -151.5824) (xy 84.623091 -151.564393) (xy 84.573491 -151.538892) (xy 84.528133 -151.506441)
			(xy 84.487984 -151.467732) (xy 84.453898 -151.423589) (xy 84.426602 -151.374954) (xy 84.406679 -151.322863)
			(xy 84.394553 -151.268426) (xy 84.390482 -151.212804) (xy 64.887812 -151.212804) (xy 64.854911 -151.230767)
			(xy 64.80386 -151.249804) (xy 64.75062 -151.261382) (xy 64.696274 -151.265265) (xy 64.641929 -151.261375)
			(xy 64.588691 -151.24979) (xy 64.537643 -151.230746) (xy 64.489825 -151.204631) (xy 64.46774 -151.188674)
			(xy 64.448728 -151.175078) (xy 64.406845 -151.154346) (xy 64.361877 -151.14162) (xy 64.31534 -151.13733)
			(xy 64.268803 -151.14162) (xy 64.223835 -151.154346) (xy 64.181952 -151.175078) (xy 64.16294 -151.188674)
			(xy 64.140883 -151.204683) (xy 64.093052 -151.230815) (xy 64.04199 -151.249873) (xy 63.988735 -151.261469)
			(xy 63.934371 -151.265368) (xy 63.880006 -151.261489) (xy 63.826747 -151.249913) (xy 63.775677 -151.230874)
			(xy 63.727837 -151.20476) (xy 63.684201 -151.172103) (xy 63.645657 -151.133569) (xy 63.612989 -151.08994)
			(xy 63.586864 -151.042106) (xy 63.567813 -150.991041) (xy 63.556224 -150.937784) (xy 63.552332 -150.88342)
			(xy 63.174316 -150.88342) (xy 63.170425 -150.937777) (xy 63.158837 -150.991027) (xy 63.139788 -151.042085)
			(xy 63.113666 -151.089913) (xy 63.081003 -151.133535) (xy 63.042464 -151.172065) (xy 62.998834 -151.204717)
			(xy 62.951 -151.230827) (xy 62.899937 -151.249863) (xy 62.846684 -151.261438) (xy 62.792327 -151.265316)
			(xy 62.73797 -151.261417) (xy 62.684722 -151.249822) (xy 62.633666 -151.230766) (xy 62.585843 -151.204638)
			(xy 62.563756 -151.188674) (xy 62.544744 -151.175078) (xy 62.502861 -151.154346) (xy 62.457893 -151.14162)
			(xy 62.411356 -151.13733) (xy 62.364819 -151.14162) (xy 62.319851 -151.154346) (xy 62.277968 -151.175078)
			(xy 62.258956 -151.188674) (xy 62.236901 -151.204676) (xy 62.189076 -151.230794) (xy 62.138022 -151.24984)
			(xy 62.084776 -151.261427) (xy 62.030423 -151.265317) (xy 61.97607 -151.261433) (xy 61.922823 -151.249853)
			(xy 61.871766 -151.230814) (xy 61.823939 -151.204701) (xy 61.780314 -151.172048) (xy 61.74178 -151.133519)
			(xy 61.709122 -151.089898) (xy 61.683005 -151.042074) (xy 61.663959 -150.991019) (xy 61.652373 -150.937773)
			(xy 61.648483 -150.88342) (xy 60.933181 -150.88342) (xy 60.929291 -150.937769) (xy 60.917705 -150.991011)
			(xy 60.89866 -151.042063) (xy 60.872544 -151.089884) (xy 60.839887 -151.133501) (xy 60.801355 -151.172027)
			(xy 60.757732 -151.204677) (xy 60.709907 -151.230786) (xy 60.658853 -151.249822) (xy 60.605609 -151.261399)
			(xy 60.55126 -151.265281) (xy 60.496911 -151.261388) (xy 60.443669 -151.2498) (xy 60.392619 -151.230752)
			(xy 60.344799 -151.204633) (xy 60.322714 -151.188674) (xy 60.303702 -151.175078) (xy 60.261819 -151.154346)
			(xy 60.216851 -151.14162) (xy 60.170314 -151.13733) (xy 60.123777 -151.14162) (xy 60.078809 -151.154346)
			(xy 60.036926 -151.175078) (xy 60.017914 -151.188674) (xy 59.995857 -151.204681) (xy 59.948029 -151.230808)
			(xy 59.896969 -151.249863) (xy 59.843717 -151.261456) (xy 59.789356 -151.265352) (xy 59.734995 -151.261472)
			(xy 59.68174 -151.249894) (xy 59.630674 -151.230855) (xy 59.582838 -151.204742) (xy 59.539205 -151.172086)
			(xy 59.500664 -151.133553) (xy 59.468 -151.089927) (xy 59.441877 -151.042096) (xy 59.422827 -150.991034)
			(xy 59.411239 -150.937781) (xy 59.407348 -150.88342) (xy 59.046488 -150.88342) (xy 59.042598 -150.937771)
			(xy 59.031012 -150.991015) (xy 59.011966 -151.042067) (xy 58.985848 -151.08989) (xy 58.95319 -151.133508)
			(xy 58.914657 -151.172035) (xy 58.871033 -151.204685) (xy 58.823206 -151.230794) (xy 58.77215 -151.249831)
			(xy 58.718904 -151.261407) (xy 58.664553 -151.265288) (xy 58.610202 -151.261394) (xy 58.55696 -151.249804)
			(xy 58.505908 -151.230755) (xy 58.458088 -151.204634) (xy 58.436002 -151.188674) (xy 58.41699 -151.175078)
			(xy 58.375107 -151.154346) (xy 58.330139 -151.14162) (xy 58.283602 -151.13733) (xy 58.237065 -151.14162)
			(xy 58.192097 -151.154346) (xy 58.150214 -151.175078) (xy 58.131202 -151.188674) (xy 58.109146 -151.20468)
			(xy 58.061318 -151.230805) (xy 58.010259 -151.249858) (xy 57.957008 -151.26145) (xy 57.90265 -151.265345)
			(xy 57.84829 -151.261464) (xy 57.795036 -151.249886) (xy 57.743972 -151.230847) (xy 57.696138 -151.204734)
			(xy 57.652507 -151.172079) (xy 57.613967 -151.133546) (xy 57.581304 -151.089921) (xy 57.555182 -151.042091)
			(xy 57.536134 -150.991031) (xy 57.524546 -150.937779) (xy 57.520655 -150.88342) (xy 27.89936 -150.88342)
			(xy 27.89936 -151.099012) (xy 51.667664 -151.099012) (xy 53.31968 -151.099012) (xy 53.31968 -152.156414)
			(xy 81.34045 -152.156414) (xy 81.344521 -152.100792) (xy 81.356647 -152.046355) (xy 81.37657 -151.994264)
			(xy 81.403866 -151.945629) (xy 81.437952 -151.901486) (xy 81.478101 -151.862777) (xy 81.523459 -151.830326)
			(xy 81.573059 -151.804825) (xy 81.625843 -151.786818) (xy 81.680686 -151.776688) (xy 81.73642 -151.774651)
			(xy 81.791857 -151.780751) (xy 81.845814 -151.794857) (xy 81.897143 -151.816669) (xy 81.944749 -151.845723)
			(xy 81.987617 -151.881398) (xy 82.024834 -151.922935) (xy 82.055607 -151.969448) (xy 82.079279 -152.019945)
			(xy 82.095347 -152.073352) (xy 82.103467 -152.128528) (xy 82.103976 -152.156414) (xy 82.103467 -152.1843)
			(xy 82.095347 -152.239476) (xy 82.079279 -152.292883) (xy 82.055607 -152.34338) (xy 82.024834 -152.389893)
			(xy 81.987617 -152.43143) (xy 81.944749 -152.467105) (xy 81.897143 -152.496159) (xy 81.845814 -152.517971)
			(xy 81.791857 -152.532077) (xy 81.73642 -152.538177) (xy 81.680686 -152.53614) (xy 81.625843 -152.52601)
			(xy 81.573059 -152.508003) (xy 81.523459 -152.482502) (xy 81.478101 -152.450051) (xy 81.437952 -152.411342)
			(xy 81.403866 -152.367199) (xy 81.37657 -152.318564) (xy 81.356647 -152.266473) (xy 81.344521 -152.212036)
			(xy 81.34045 -152.156414) (xy 53.31968 -152.156414) (xy 53.31968 -152.751028) (xy 51.667664 -152.751028)
			(xy 51.667664 -151.099012) (xy 27.89936 -151.099012) (xy 27.89936 -151.965575) (xy 48.168042 -151.965575)
			(xy 48.168042 -151.884465) (xy 48.175992 -151.803746) (xy 48.191815 -151.724195) (xy 48.21536 -151.646579)
			(xy 48.246399 -151.571643) (xy 48.284634 -151.500111) (xy 48.329696 -151.432671) (xy 48.381151 -151.369972)
			(xy 48.438504 -151.312619) (xy 48.501203 -151.261164) (xy 48.568643 -151.216102) (xy 48.640175 -151.177867)
			(xy 48.715111 -151.146828) (xy 48.792727 -151.123283) (xy 48.872278 -151.10746) (xy 48.952997 -151.09951)
			(xy 49.034107 -151.09951) (xy 49.114826 -151.10746) (xy 49.194377 -151.123283) (xy 49.271993 -151.146828)
			(xy 49.346929 -151.177867) (xy 49.418461 -151.216102) (xy 49.485901 -151.261164) (xy 49.5486 -151.312619)
			(xy 49.605953 -151.369972) (xy 49.657408 -151.432671) (xy 49.70247 -151.500111) (xy 49.740705 -151.571643)
			(xy 49.771744 -151.646579) (xy 49.795289 -151.724195) (xy 49.811112 -151.803746) (xy 49.819062 -151.884465)
			(xy 49.81956 -151.92502) (xy 49.819062 -151.965575) (xy 49.811112 -152.046294) (xy 49.795289 -152.125845)
			(xy 49.771744 -152.203461) (xy 49.740705 -152.278397) (xy 49.70247 -152.349929) (xy 49.657408 -152.417369)
			(xy 49.605953 -152.480068) (xy 49.5486 -152.537421) (xy 49.485901 -152.588876) (xy 49.418461 -152.633938)
			(xy 49.346929 -152.672173) (xy 49.271993 -152.703212) (xy 49.194377 -152.726757) (xy 49.114826 -152.74258)
			(xy 49.034107 -152.75053) (xy 48.952997 -152.75053) (xy 48.872278 -152.74258) (xy 48.792727 -152.726757)
			(xy 48.715111 -152.703212) (xy 48.640175 -152.672173) (xy 48.568643 -152.633938) (xy 48.501203 -152.588876)
			(xy 48.438504 -152.537421) (xy 48.381151 -152.480068) (xy 48.329696 -152.417369) (xy 48.284634 -152.349929)
			(xy 48.246399 -152.278397) (xy 48.21536 -152.203461) (xy 48.191815 -152.125845) (xy 48.175992 -152.046294)
			(xy 48.168042 -151.965575) (xy 27.89936 -151.965575) (xy 27.89936 -152.784299) (xy 57.520684 -152.784299)
			(xy 57.524572 -152.729944) (xy 57.536156 -152.676696) (xy 57.555201 -152.625638) (xy 57.581318 -152.577811)
			(xy 57.613977 -152.534187) (xy 57.652511 -152.495656) (xy 57.696137 -152.463001) (xy 57.743967 -152.436888)
			(xy 57.795026 -152.417847) (xy 57.848275 -152.406267) (xy 57.90263 -152.402384) (xy 57.956985 -152.406276)
			(xy 58.010232 -152.417864) (xy 58.061289 -152.436913) (xy 58.109114 -152.463034) (xy 58.131202 -152.478994)
			(xy 58.150214 -152.49259) (xy 58.192097 -152.513322) (xy 58.237065 -152.526048) (xy 58.283602 -152.530338)
			(xy 58.330139 -152.526048) (xy 58.375107 -152.513322) (xy 58.41699 -152.49259) (xy 58.436002 -152.478994)
			(xy 58.458088 -152.463032) (xy 58.505914 -152.436911) (xy 58.55697 -152.417863) (xy 58.610217 -152.406275)
			(xy 58.664572 -152.402383) (xy 58.718927 -152.406267) (xy 58.772176 -152.417847) (xy 58.823235 -152.436888)
			(xy 58.871064 -152.463001) (xy 58.91469 -152.495656) (xy 58.953225 -152.534187) (xy 58.985883 -152.577811)
			(xy 59.012 -152.625638) (xy 59.031045 -152.676696) (xy 59.042629 -152.729944) (xy 59.046517 -152.784299)
			(xy 59.407377 -152.784299) (xy 59.411265 -152.729942) (xy 59.422849 -152.676692) (xy 59.441895 -152.625633)
			(xy 59.468013 -152.577805) (xy 59.500673 -152.53418) (xy 59.539209 -152.495648) (xy 59.582837 -152.462993)
			(xy 59.630668 -152.436879) (xy 59.681729 -152.417839) (xy 59.73498 -152.406259) (xy 59.789337 -152.402377)
			(xy 59.843693 -152.40627) (xy 59.896942 -152.41786) (xy 59.947999 -152.43691) (xy 59.995826 -152.463033)
			(xy 60.017914 -152.478994) (xy 60.036926 -152.49259) (xy 60.078809 -152.513322) (xy 60.123777 -152.526048)
			(xy 60.170314 -152.530338) (xy 60.216851 -152.526048) (xy 60.261819 -152.513322) (xy 60.303702 -152.49259)
			(xy 60.322714 -152.478994) (xy 60.3448 -152.463033) (xy 60.392625 -152.436914) (xy 60.44368 -152.417867)
			(xy 60.496926 -152.406281) (xy 60.551279 -152.40239) (xy 60.605632 -152.406275) (xy 60.658879 -152.417855)
			(xy 60.709937 -152.436896) (xy 60.757764 -152.46301) (xy 60.801389 -152.495664) (xy 60.839921 -152.534195)
			(xy 60.872578 -152.577817) (xy 60.898695 -152.625643) (xy 60.917738 -152.676699) (xy 60.929322 -152.729946)
			(xy 60.93321 -152.784299) (xy 61.648511 -152.784299) (xy 61.652399 -152.72995) (xy 61.663981 -152.676708)
			(xy 61.683023 -152.625656) (xy 61.709136 -152.577834) (xy 61.74179 -152.534214) (xy 61.780318 -152.495686)
			(xy 61.823938 -152.463033) (xy 61.871761 -152.436921) (xy 61.922813 -152.41788) (xy 61.976055 -152.406298)
			(xy 62.030404 -152.402411) (xy 62.084753 -152.406299) (xy 62.137995 -152.417882) (xy 62.189047 -152.436924)
			(xy 62.236869 -152.463038) (xy 62.258956 -152.478994) (xy 62.277968 -152.49259) (xy 62.319851 -152.513322)
			(xy 62.364819 -152.526048) (xy 62.411356 -152.530338) (xy 62.457893 -152.526048) (xy 62.502861 -152.513322)
			(xy 62.544744 -152.49259) (xy 62.563756 -152.478994) (xy 62.585843 -152.463028) (xy 62.633672 -152.4369)
			(xy 62.684732 -152.417845) (xy 62.737985 -152.406252) (xy 62.792346 -152.402356) (xy 62.846707 -152.406236)
			(xy 62.899963 -152.417814) (xy 62.951029 -152.436855) (xy 62.998865 -152.462969) (xy 63.042498 -152.495626)
			(xy 63.081038 -152.53416) (xy 63.113701 -152.577788) (xy 63.139822 -152.62562) (xy 63.15887 -152.676683)
			(xy 63.170456 -152.729938) (xy 63.174344 -152.784299) (xy 63.552361 -152.784299) (xy 63.55625 -152.729939)
			(xy 63.567835 -152.676685) (xy 63.586882 -152.625623) (xy 63.613003 -152.577792) (xy 63.645666 -152.534165)
			(xy 63.684205 -152.495631) (xy 63.727836 -152.462974) (xy 63.775672 -152.43686) (xy 63.826736 -152.41782)
			(xy 63.879991 -152.406242) (xy 63.934352 -152.402361) (xy 63.988712 -152.406257) (xy 64.041963 -152.41785)
			(xy 64.093023 -152.436904) (xy 64.140851 -152.463031) (xy 64.16294 -152.478994) (xy 64.181952 -152.49259)
			(xy 64.223835 -152.513322) (xy 64.268803 -152.526048) (xy 64.31534 -152.530338) (xy 64.361877 -152.526048)
			(xy 64.406845 -152.513322) (xy 64.448728 -152.49259) (xy 64.46774 -152.478994) (xy 64.489825 -152.463035)
			(xy 64.537648 -152.43692) (xy 64.588701 -152.417877) (xy 64.641944 -152.406294) (xy 64.696294 -152.402406)
			(xy 64.750643 -152.406292) (xy 64.803887 -152.417874) (xy 64.85494 -152.436915) (xy 64.902764 -152.463028)
			(xy 64.946384 -152.495681) (xy 64.984914 -152.53421) (xy 65.017568 -152.57783) (xy 65.043682 -152.625653)
			(xy 65.062724 -152.676706) (xy 65.074307 -152.729949) (xy 65.078194 -152.784299) (xy 65.074307 -152.838648)
			(xy 65.062725 -152.891892) (xy 65.043683 -152.942945) (xy 65.017569 -152.990768) (xy 64.984916 -153.034388)
			(xy 64.946386 -153.072917) (xy 64.902766 -153.105571) (xy 64.854942 -153.131684) (xy 64.803889 -153.150726)
			(xy 64.750646 -153.162308) (xy 64.696296 -153.166194) (xy 64.641946 -153.162306) (xy 64.588703 -153.150723)
			(xy 64.53765 -153.131681) (xy 64.489827 -153.105567) (xy 64.46774 -153.08961) (xy 64.448728 -153.076014)
			(xy 64.406845 -153.055282) (xy 64.361877 -153.042556) (xy 64.31534 -153.038266) (xy 64.268803 -153.042556)
			(xy 64.223835 -153.055282) (xy 64.181952 -153.076014) (xy 64.16294 -153.08961) (xy 64.140849 -153.105571)
			(xy 64.093021 -153.131697) (xy 64.041961 -153.150751) (xy 63.988709 -153.162344) (xy 63.93435 -153.166239)
			(xy 63.879989 -153.162358) (xy 63.826734 -153.150779) (xy 63.775669 -153.131739) (xy 63.727834 -153.105624)
			(xy 63.684203 -153.072968) (xy 63.645664 -153.034433) (xy 63.613002 -152.990806) (xy 63.586881 -152.942975)
			(xy 63.567835 -152.891912) (xy 63.556249 -152.838659) (xy 63.552361 -152.784299) (xy 63.174344 -152.784299)
			(xy 63.170456 -152.83866) (xy 63.158871 -152.891914) (xy 63.139823 -152.942978) (xy 63.113702 -152.99081)
			(xy 63.081039 -153.034438) (xy 63.042499 -153.072973) (xy 62.998867 -153.10563) (xy 62.951031 -153.131744)
			(xy 62.899966 -153.150785) (xy 62.84671 -153.162364) (xy 62.792348 -153.166244) (xy 62.737988 -153.162349)
			(xy 62.684735 -153.150756) (xy 62.633674 -153.131701) (xy 62.585845 -153.105574) (xy 62.563756 -153.08961)
			(xy 62.544744 -153.076014) (xy 62.502861 -153.055282) (xy 62.457893 -153.042556) (xy 62.411356 -153.038266)
			(xy 62.364819 -153.042556) (xy 62.319851 -153.055282) (xy 62.277968 -153.076014) (xy 62.258956 -153.08961)
			(xy 62.236867 -153.105564) (xy 62.189045 -153.131677) (xy 62.137993 -153.150719) (xy 62.08475 -153.162301)
			(xy 62.030402 -153.166189) (xy 61.976053 -153.162302) (xy 61.922811 -153.15072) (xy 61.871759 -153.131678)
			(xy 61.823936 -153.105565) (xy 61.780317 -153.072912) (xy 61.741788 -153.034384) (xy 61.709135 -152.990764)
			(xy 61.683022 -152.942942) (xy 61.66398 -152.89189) (xy 61.652398 -152.838647) (xy 61.648511 -152.784299)
			(xy 60.93321 -152.784299) (xy 60.929322 -152.838652) (xy 60.917739 -152.891899) (xy 60.898696 -152.942955)
			(xy 60.87258 -152.990781) (xy 60.839923 -153.034404) (xy 60.80139 -153.072935) (xy 60.757766 -153.105589)
			(xy 60.709939 -153.131703) (xy 60.658882 -153.150744) (xy 60.605635 -153.162325) (xy 60.551281 -153.16621)
			(xy 60.496928 -153.162319) (xy 60.443682 -153.150733) (xy 60.392627 -153.131687) (xy 60.344802 -153.105569)
			(xy 60.322714 -153.08961) (xy 60.303702 -153.076014) (xy 60.261819 -153.055282) (xy 60.216851 -153.042556)
			(xy 60.170314 -153.038266) (xy 60.123777 -153.042556) (xy 60.078809 -153.055282) (xy 60.036926 -153.076014)
			(xy 60.017914 -153.08961) (xy 59.995824 -153.105568) (xy 59.947997 -153.131691) (xy 59.89694 -153.150741)
			(xy 59.843691 -153.16233) (xy 59.789335 -153.166223) (xy 59.734978 -153.16234) (xy 59.681727 -153.150761)
			(xy 59.630666 -153.13172) (xy 59.582835 -153.105606) (xy 59.539207 -153.07295) (xy 59.500672 -153.034418)
			(xy 59.468012 -152.990793) (xy 59.441894 -152.942965) (xy 59.422849 -152.891905) (xy 59.411264 -152.838655)
			(xy 59.407377 -152.784299) (xy 59.046517 -152.784299) (xy 59.042629 -152.838654) (xy 59.031046 -152.891902)
			(xy 59.012001 -152.94296) (xy 58.985884 -152.990787) (xy 58.953226 -153.034411) (xy 58.914692 -153.072942)
			(xy 58.871066 -153.105598) (xy 58.823237 -153.131711) (xy 58.772178 -153.150752) (xy 58.718929 -153.162333)
			(xy 58.664574 -153.166217) (xy 58.61022 -153.162326) (xy 58.556972 -153.150738) (xy 58.505916 -153.13169)
			(xy 58.45809 -153.10557) (xy 58.436002 -153.08961) (xy 58.41699 -153.076014) (xy 58.375107 -153.055282)
			(xy 58.330139 -153.042556) (xy 58.283602 -153.038266) (xy 58.237065 -153.042556) (xy 58.192097 -153.055282)
			(xy 58.150214 -153.076014) (xy 58.131202 -153.08961) (xy 58.109112 -153.105567) (xy 58.061286 -153.131688)
			(xy 58.01023 -153.150736) (xy 57.956983 -153.162324) (xy 57.902628 -153.166216) (xy 57.848273 -153.162332)
			(xy 57.795024 -153.150752) (xy 57.743965 -153.131711) (xy 57.696135 -153.105598) (xy 57.652509 -153.072943)
			(xy 57.613975 -153.034411) (xy 57.581317 -152.990787) (xy 57.5552 -152.94296) (xy 57.536155 -152.891902)
			(xy 57.524571 -152.838654) (xy 57.520684 -152.784299) (xy 27.89936 -152.784299) (xy 27.89936 -154.459381)
			(xy 57.520708 -154.459381) (xy 57.524598 -154.405029) (xy 57.536184 -154.351785) (xy 57.55523 -154.300732)
			(xy 57.581348 -154.252908) (xy 57.614006 -154.209289) (xy 57.65254 -154.170762) (xy 57.696165 -154.138111)
			(xy 57.743993 -154.112002) (xy 57.79505 -154.092965) (xy 57.848296 -154.081388) (xy 57.902648 -154.077508)
			(xy 57.956999 -154.081402) (xy 58.010243 -154.092992) (xy 58.061295 -154.112042) (xy 58.109116 -154.138164)
			(xy 58.131202 -154.154124) (xy 58.150214 -154.16772) (xy 58.192097 -154.188452) (xy 58.237065 -154.201178)
			(xy 58.283602 -154.205468) (xy 58.330139 -154.201178) (xy 58.375107 -154.188452) (xy 58.41699 -154.16772)
			(xy 58.436002 -154.154124) (xy 58.45806 -154.138121) (xy 58.505887 -154.111997) (xy 58.556946 -154.092945)
			(xy 58.610196 -154.081354) (xy 58.664554 -154.077459) (xy 58.718913 -154.08134) (xy 58.772166 -154.092919)
			(xy 58.823229 -154.111958) (xy 58.871062 -154.138071) (xy 58.914693 -154.170726) (xy 58.953231 -154.209258)
			(xy 58.985893 -154.252883) (xy 59.012015 -154.300712) (xy 59.031063 -154.351772) (xy 59.04265 -154.405023)
			(xy 59.046541 -154.459381) (xy 59.407401 -154.459381) (xy 59.411291 -154.405028) (xy 59.422878 -154.351782)
			(xy 59.441924 -154.300727) (xy 59.468043 -154.252902) (xy 59.500703 -154.209282) (xy 59.539239 -154.170754)
			(xy 59.582865 -154.138103) (xy 59.630695 -154.111993) (xy 59.681753 -154.092957) (xy 59.735001 -154.08138)
			(xy 59.789355 -154.077501) (xy 59.843708 -154.081396) (xy 59.896953 -154.092988) (xy 59.948006 -154.112039)
			(xy 59.995828 -154.138163) (xy 60.017914 -154.154124) (xy 60.036926 -154.16772) (xy 60.078809 -154.188452)
			(xy 60.123777 -154.201178) (xy 60.170314 -154.205468) (xy 60.216851 -154.201178) (xy 60.261819 -154.188452)
			(xy 60.303702 -154.16772) (xy 60.322714 -154.154124) (xy 60.344772 -154.138122) (xy 60.392598 -154.111999)
			(xy 60.443656 -154.092949) (xy 60.496904 -154.08136) (xy 60.551261 -154.077466) (xy 60.605618 -154.081348)
			(xy 60.658869 -154.092927) (xy 60.70993 -154.111967) (xy 60.757762 -154.13808) (xy 60.801391 -154.170734)
			(xy 60.839928 -154.209265) (xy 60.872589 -154.252889) (xy 60.898709 -154.300717) (xy 60.917756 -154.351775)
			(xy 60.929343 -154.405024) (xy 60.933234 -154.459381) (xy 61.648535 -154.459381) (xy 61.652425 -154.405036)
			(xy 61.664009 -154.351797) (xy 61.683052 -154.30075) (xy 61.709166 -154.252931) (xy 61.74182 -154.209316)
			(xy 61.780348 -154.170792) (xy 61.823966 -154.138144) (xy 61.871787 -154.112035) (xy 61.922837 -154.092998)
			(xy 61.976077 -154.081419) (xy 62.030422 -154.077535) (xy 62.084767 -154.081425) (xy 62.138006 -154.09301)
			(xy 62.189053 -154.112053) (xy 62.236871 -154.138168) (xy 62.258956 -154.154124) (xy 62.277968 -154.16772)
			(xy 62.319851 -154.188452) (xy 62.364819 -154.201178) (xy 62.411356 -154.205468) (xy 62.457893 -154.201178)
			(xy 62.502861 -154.188452) (xy 62.544744 -154.16772) (xy 62.563756 -154.154124) (xy 62.585815 -154.138117)
			(xy 62.633646 -154.111985) (xy 62.684708 -154.092927) (xy 62.737964 -154.08133) (xy 62.792328 -154.077431)
			(xy 62.846693 -154.08131) (xy 62.899953 -154.092886) (xy 62.951023 -154.111925) (xy 62.998863 -154.138039)
			(xy 63.0425 -154.170696) (xy 63.081044 -154.209231) (xy 63.113712 -154.25286) (xy 63.139837 -154.300694)
			(xy 63.158888 -154.351759) (xy 63.170477 -154.405016) (xy 63.174369 -154.459381) (xy 63.552385 -154.459381)
			(xy 63.556276 -154.405024) (xy 63.567863 -154.351775) (xy 63.586912 -154.300717) (xy 63.613033 -154.25289)
			(xy 63.645696 -154.209267) (xy 63.684234 -154.170737) (xy 63.727865 -154.138085) (xy 63.775698 -154.111975)
			(xy 63.82676 -154.092938) (xy 63.880013 -154.081363) (xy 63.93437 -154.077485) (xy 63.988726 -154.081383)
			(xy 64.041974 -154.092978) (xy 64.093029 -154.112033) (xy 64.140853 -154.138161) (xy 64.16294 -154.154124)
			(xy 64.181952 -154.16772) (xy 64.223835 -154.188452) (xy 64.268803 -154.201178) (xy 64.31534 -154.205468)
			(xy 64.361877 -154.201178) (xy 64.406845 -154.188452) (xy 64.448728 -154.16772) (xy 64.46774 -154.154124)
			(xy 64.489797 -154.138124) (xy 64.537622 -154.112006) (xy 64.588677 -154.092959) (xy 64.641923 -154.081373)
			(xy 64.696276 -154.077482) (xy 64.750629 -154.081366) (xy 64.803876 -154.092946) (xy 64.854934 -154.111985)
			(xy 64.902762 -154.138098) (xy 64.946387 -154.170751) (xy 64.98492 -154.20928) (xy 65.017579 -154.252902)
			(xy 65.043696 -154.300727) (xy 65.062742 -154.351782) (xy 65.074328 -154.405028) (xy 65.078218 -154.459381)
			(xy 65.074333 -154.513734) (xy 65.062753 -154.566981) (xy 65.043712 -154.618038) (xy 65.017599 -154.665866)
			(xy 64.984945 -154.709491) (xy 64.946416 -154.748024) (xy 64.902794 -154.780681) (xy 64.854969 -154.806799)
			(xy 64.803913 -154.825844) (xy 64.750667 -154.837429) (xy 64.696314 -154.841318) (xy 64.641961 -154.837433)
			(xy 64.588714 -154.825851) (xy 64.537657 -154.80681) (xy 64.48983 -154.780696) (xy 64.46774 -154.76474)
			(xy 64.448728 -154.751144) (xy 64.406845 -154.730412) (xy 64.361877 -154.717686) (xy 64.31534 -154.713396)
			(xy 64.268803 -154.717686) (xy 64.223835 -154.730412) (xy 64.181952 -154.751144) (xy 64.16294 -154.76474)
			(xy 64.140821 -154.78066) (xy 64.092995 -154.806783) (xy 64.041937 -154.825833) (xy 63.988688 -154.837422)
			(xy 63.934332 -154.841315) (xy 63.879975 -154.837431) (xy 63.826724 -154.825851) (xy 63.775663 -154.806809)
			(xy 63.727832 -154.780694) (xy 63.684205 -154.748038) (xy 63.645671 -154.709504) (xy 63.613012 -154.665878)
			(xy 63.586896 -154.618048) (xy 63.567853 -154.566988) (xy 63.55627 -154.513738) (xy 63.552385 -154.459381)
			(xy 63.174369 -154.459381) (xy 63.170483 -154.513746) (xy 63.158899 -154.567004) (xy 63.139853 -154.618071)
			(xy 63.113732 -154.665908) (xy 63.081069 -154.70954) (xy 63.042529 -154.748079) (xy 62.998896 -154.78074)
			(xy 62.951058 -154.806859) (xy 62.89999 -154.825903) (xy 62.846731 -154.837485) (xy 62.792366 -154.841369)
			(xy 62.738002 -154.837475) (xy 62.684745 -154.825884) (xy 62.633681 -154.806831) (xy 62.585848 -154.780704)
			(xy 62.563756 -154.76474) (xy 62.544744 -154.751144) (xy 62.502861 -154.730412) (xy 62.457893 -154.717686)
			(xy 62.411356 -154.713396) (xy 62.364819 -154.717686) (xy 62.319851 -154.730412) (xy 62.277968 -154.751144)
			(xy 62.258956 -154.76474) (xy 62.236839 -154.780653) (xy 62.189018 -154.806763) (xy 62.137969 -154.825801)
			(xy 62.084729 -154.83738) (xy 62.030384 -154.841265) (xy 61.976039 -154.837375) (xy 61.9228 -154.825792)
			(xy 61.871752 -154.806749) (xy 61.823934 -154.780636) (xy 61.780319 -154.747982) (xy 61.741794 -154.709455)
			(xy 61.709145 -154.665836) (xy 61.683036 -154.618016) (xy 61.663998 -154.566966) (xy 61.65242 -154.513726)
			(xy 61.648535 -154.459381) (xy 60.933234 -154.459381) (xy 60.929349 -154.513738) (xy 60.917767 -154.566988)
			(xy 60.898725 -154.618049) (xy 60.87261 -154.665879) (xy 60.839953 -154.709506) (xy 60.80142 -154.748041)
			(xy 60.757794 -154.7807) (xy 60.709965 -154.806817) (xy 60.658906 -154.825862) (xy 60.605656 -154.837446)
			(xy 60.551299 -154.841334) (xy 60.496942 -154.837446) (xy 60.443692 -154.825861) (xy 60.392633 -154.806817)
			(xy 60.344804 -154.780699) (xy 60.322714 -154.76474) (xy 60.303702 -154.751144) (xy 60.261819 -154.730412)
			(xy 60.216851 -154.717686) (xy 60.170314 -154.713396) (xy 60.123777 -154.717686) (xy 60.078809 -154.730412)
			(xy 60.036926 -154.751144) (xy 60.017914 -154.76474) (xy 59.995795 -154.780658) (xy 59.947971 -154.806777)
			(xy 59.896916 -154.825823) (xy 59.84367 -154.837409) (xy 59.789317 -154.841299) (xy 59.734963 -154.837414)
			(xy 59.681716 -154.825833) (xy 59.63066 -154.806791) (xy 59.582833 -154.780676) (xy 59.539209 -154.748021)
			(xy 59.500678 -154.709489) (xy 59.468023 -154.665865) (xy 59.441908 -154.618038) (xy 59.422867 -154.566981)
			(xy 59.411286 -154.513734) (xy 59.407401 -154.459381) (xy 59.046541 -154.459381) (xy 59.042656 -154.513739)
			(xy 59.031074 -154.566991) (xy 59.012031 -154.618053) (xy 58.985914 -154.665885) (xy 58.953256 -154.709513)
			(xy 58.914722 -154.748049) (xy 58.871095 -154.780708) (xy 58.823264 -154.806826) (xy 58.772203 -154.82587)
			(xy 58.718951 -154.837454) (xy 58.664592 -154.841341) (xy 58.610234 -154.837452) (xy 58.556983 -154.825866)
			(xy 58.505922 -154.806819) (xy 58.458092 -154.7807) (xy 58.436002 -154.76474) (xy 58.41699 -154.751144)
			(xy 58.375107 -154.730412) (xy 58.330139 -154.717686) (xy 58.283602 -154.713396) (xy 58.237065 -154.717686)
			(xy 58.192097 -154.730412) (xy 58.150214 -154.751144) (xy 58.131202 -154.76474) (xy 58.109084 -154.780657)
			(xy 58.06126 -154.806774) (xy 58.010206 -154.825818) (xy 57.956961 -154.837403) (xy 57.90261 -154.841292)
			(xy 57.848258 -154.837406) (xy 57.795013 -154.825824) (xy 57.743958 -154.806782) (xy 57.696133 -154.780668)
			(xy 57.652511 -154.748013) (xy 57.613981 -154.709482) (xy 57.581327 -154.665859) (xy 57.555214 -154.618033)
			(xy 57.536173 -154.566978) (xy 57.524593 -154.513733) (xy 57.520708 -154.459381) (xy 27.89936 -154.459381)
			(xy 27.89936 -155.07716) (xy 71.969884 -155.07716) (xy 71.969884 -154.168348) (xy 71.97058 -154.132282)
			(xy 71.980899 -154.060891) (xy 71.990458 -154.026108) (xy 71.995284 -154.008582) (xy 71.995284 -153.63444)
			(xy 72.9615 -153.63444) (xy 72.9615 -154.008582) (xy 72.966326 -154.026108) (xy 72.975865 -154.060895)
			(xy 72.986194 -154.132284) (xy 72.9869 -154.168348) (xy 72.9869 -154.23261) (xy 73.401428 -154.23261)
			(xy 73.401428 -153.323798) (xy 73.40192 -153.291062) (xy 73.410362 -153.226136) (xy 73.427067 -153.162831)
			(xy 73.451759 -153.102193) (xy 73.48403 -153.045226) (xy 73.503282 -153.018744) (xy 73.528428 -152.984962)
			(xy 73.528428 -152.967944) (xy 73.543922 -152.967944) (xy 73.579736 -152.937464) (xy 73.604913 -152.916611)
			(xy 73.659645 -152.88086) (xy 73.71851 -152.852421) (xy 73.780535 -152.831766) (xy 73.844697 -152.819235)
			(xy 73.909936 -152.815035) (xy 73.975175 -152.819235) (xy 74.039337 -152.831766) (xy 74.101362 -152.852421)
			(xy 74.160227 -152.88086) (xy 74.214959 -152.916611) (xy 74.240136 -152.937464) (xy 74.27595 -152.967944)
			(xy 74.291444 -152.967944) (xy 74.291444 -152.984962) (xy 74.31659 -153.018744) (xy 74.331794 -153.039556)
			(xy 74.358385 -153.083712) (xy 74.369676 -153.106882) (xy 74.37695 -153.121112) (xy 74.397344 -153.145703)
			(xy 74.423206 -153.164458) (xy 74.452915 -153.176204) (xy 74.484611 -153.180202) (xy 74.516307 -153.176204)
			(xy 74.546016 -153.164458) (xy 74.571878 -153.145703) (xy 74.592272 -153.121112) (xy 74.599546 -153.106882)
			(xy 74.610816 -153.083701) (xy 74.637416 -153.039549) (xy 74.652632 -153.018744) (xy 74.678032 -152.984962)
			(xy 74.678032 -152.967944) (xy 74.693272 -152.967944) (xy 74.729086 -152.937464) (xy 74.754263 -152.916611)
			(xy 74.808995 -152.88086) (xy 74.86786 -152.852421) (xy 74.929885 -152.831766) (xy 74.994047 -152.819235)
			(xy 75.059286 -152.815035) (xy 75.124525 -152.819235) (xy 75.188687 -152.831766) (xy 75.250712 -152.852421)
			(xy 75.309577 -152.88086) (xy 75.364309 -152.916611) (xy 75.389486 -152.937464) (xy 75.4253 -152.967944)
			(xy 75.44054 -152.967944) (xy 75.44054 -152.984962) (xy 75.46594 -153.018744) (xy 75.485154 -153.045243)
			(xy 75.517386 -153.102212) (xy 75.542029 -153.16285) (xy 75.558676 -153.226153) (xy 75.567049 -153.29107)
			(xy 75.56754 -153.323798) (xy 75.56754 -153.36012) (xy 86.39887 -153.36012) (xy 86.402874 -153.160022)
			(xy 86.414881 -152.960244) (xy 86.434872 -152.761107) (xy 86.462814 -152.562929) (xy 86.498662 -152.366027)
			(xy 86.54236 -152.170718) (xy 86.593837 -151.977313) (xy 86.653011 -151.786123) (xy 86.719787 -151.597453)
			(xy 86.794059 -151.411606) (xy 86.875706 -151.228879) (xy 86.964599 -151.049566) (xy 87.060595 -150.873952)
			(xy 87.16354 -150.70232) (xy 87.27327 -150.534944) (xy 87.389608 -150.372093) (xy 87.512369 -150.214026)
			(xy 87.641356 -150.060998) (xy 87.776363 -149.913253) (xy 87.917172 -149.771027) (xy 88.063559 -149.63455)
			(xy 88.215289 -149.504038) (xy 88.37212 -149.379702) (xy 88.533799 -149.26174) (xy 88.700069 -149.150341)
			(xy 88.870662 -149.045684) (xy 89.045306 -148.947936) (xy 89.223722 -148.857253) (xy 89.405622 -148.773782)
			(xy 89.590717 -148.697655) (xy 89.778709 -148.628995) (xy 89.969298 -148.567911) (xy 90.162178 -148.514501)
			(xy 90.35704 -148.468852) (xy 90.553573 -148.431035) (xy 90.751462 -148.401111) (xy 90.950389 -148.379129)
			(xy 91.150037 -148.365124) (xy 91.350085 -148.359118) (xy 91.550213 -148.36112) (xy 91.750101 -148.371128)
			(xy 91.949428 -148.389125) (xy 92.147876 -148.415083) (xy 92.345126 -148.44896) (xy 92.540863 -148.490702)
			(xy 92.734773 -148.540241) (xy 92.926546 -148.597499) (xy 93.115875 -148.662384) (xy 93.302455 -148.734792)
			(xy 93.48599 -148.814608) (xy 93.666184 -148.901702) (xy 93.842749 -148.995936) (xy 94.015402 -149.097159)
			(xy 94.183867 -149.205209) (xy 94.347875 -149.319912) (xy 94.507162 -149.441086) (xy 94.661473 -149.568535)
			(xy 94.810561 -149.702056) (xy 94.954188 -149.841436) (xy 95.092124 -149.98645) (xy 95.224147 -150.136867)
			(xy 95.350046 -150.292445) (xy 95.46962 -150.452937) (xy 95.582676 -150.618083) (xy 95.689035 -150.787621)
			(xy 95.788526 -150.961279) (xy 95.880989 -151.138778) (xy 95.966276 -151.319834) (xy 96.044251 -151.504158)
			(xy 96.114788 -151.691454) (xy 96.177776 -151.881422) (xy 96.233113 -152.073758) (xy 96.28071 -152.268154)
			(xy 96.320491 -152.464299) (xy 96.352393 -152.661878) (xy 96.376364 -152.860575) (xy 96.392366 -153.060073)
			(xy 96.400373 -153.260051) (xy 96.400874 -153.36012) (xy 96.400373 -153.460189) (xy 96.392366 -153.660167)
			(xy 96.376364 -153.859665) (xy 96.352393 -154.058362) (xy 96.320491 -154.255941) (xy 96.28071 -154.452086)
			(xy 96.233113 -154.646482) (xy 96.177776 -154.838818) (xy 96.114788 -155.028786) (xy 96.044251 -155.216082)
			(xy 95.966276 -155.400406) (xy 95.880989 -155.581462) (xy 95.788526 -155.758961) (xy 95.689035 -155.932619)
			(xy 95.582676 -156.102157) (xy 95.46962 -156.267303) (xy 95.350046 -156.427795) (xy 95.224147 -156.583373)
			(xy 95.092124 -156.73379) (xy 94.954188 -156.878804) (xy 94.810561 -157.018184) (xy 94.661473 -157.151705)
			(xy 94.507162 -157.279154) (xy 94.347875 -157.400328) (xy 94.183867 -157.515031) (xy 94.015402 -157.623081)
			(xy 93.842749 -157.724304) (xy 93.666184 -157.818538) (xy 93.48599 -157.905632) (xy 93.302455 -157.985448)
			(xy 93.115875 -158.057856) (xy 92.926546 -158.122741) (xy 92.734773 -158.179999) (xy 92.540863 -158.229538)
			(xy 92.345126 -158.27128) (xy 92.147876 -158.305157) (xy 91.949428 -158.331115) (xy 91.750101 -158.349112)
			(xy 91.550213 -158.35912) (xy 91.350085 -158.361122) (xy 91.150037 -158.355116) (xy 90.950389 -158.341111)
			(xy 90.751462 -158.319129) (xy 90.553573 -158.289205) (xy 90.35704 -158.251388) (xy 90.162178 -158.205739)
			(xy 89.969298 -158.152329) (xy 89.778709 -158.091245) (xy 89.590717 -158.022585) (xy 89.405622 -157.946458)
			(xy 89.223722 -157.862987) (xy 89.045306 -157.772304) (xy 88.870662 -157.674556) (xy 88.700069 -157.569899)
			(xy 88.533799 -157.4585) (xy 88.37212 -157.340538) (xy 88.215289 -157.216202) (xy 88.063559 -157.08569)
			(xy 87.917172 -156.949213) (xy 87.776363 -156.806987) (xy 87.641356 -156.659242) (xy 87.512369 -156.506214)
			(xy 87.389608 -156.348147) (xy 87.27327 -156.185296) (xy 87.16354 -156.01792) (xy 87.060595 -155.846288)
			(xy 86.964599 -155.670674) (xy 86.875706 -155.491361) (xy 86.794059 -155.308634) (xy 86.719787 -155.122787)
			(xy 86.653011 -154.934117) (xy 86.593837 -154.742927) (xy 86.54236 -154.549522) (xy 86.498662 -154.354213)
			(xy 86.462814 -154.157311) (xy 86.434872 -153.959133) (xy 86.414881 -153.759996) (xy 86.402874 -153.560218)
			(xy 86.39887 -153.36012) (xy 75.56754 -153.36012) (xy 75.56754 -154.23261) (xy 75.567145 -154.265064)
			(xy 75.558894 -154.329445) (xy 75.542516 -154.392252) (xy 75.518275 -154.452463) (xy 75.486568 -154.509099)
			(xy 75.447909 -154.561238) (xy 75.402928 -154.608032) (xy 75.352356 -154.648719) (xy 75.297017 -154.682639)
			(xy 75.23781 -154.709238) (xy 75.175698 -154.728084) (xy 75.111694 -154.738871) (xy 75.046836 -154.741423)
			(xy 74.982182 -154.735698) (xy 74.918782 -154.72179) (xy 74.857668 -154.699924) (xy 74.799835 -154.670458)
			(xy 74.746223 -154.633869) (xy 74.697704 -154.590754) (xy 74.676 -154.56662) (xy 74.661419 -154.550545)
			(xy 74.627775 -154.523135) (xy 74.589959 -154.501847) (xy 74.549073 -154.487301) (xy 74.506309 -154.47992)
			(xy 74.462913 -154.47992) (xy 74.420149 -154.487301) (xy 74.379263 -154.501847) (xy 74.341447 -154.523135)
			(xy 74.307803 -154.550545) (xy 74.293222 -154.56662) (xy 74.271591 -154.590828) (xy 74.223062 -154.633956)
			(xy 74.169437 -154.670555) (xy 74.11159 -154.70003) (xy 74.050462 -154.721902) (xy 73.987047 -154.735815)
			(xy 73.922376 -154.741543) (xy 73.857503 -154.738991) (xy 73.793482 -154.728203) (xy 73.731355 -154.709353)
			(xy 73.672133 -154.682748) (xy 73.616779 -154.648821) (xy 73.566195 -154.608124) (xy 73.521202 -154.561319)
			(xy 73.482533 -154.509167) (xy 73.450817 -154.452517) (xy 73.426571 -154.392291) (xy 73.410188 -154.329469)
			(xy 73.401935 -154.265072) (xy 73.401428 -154.23261) (xy 72.9869 -154.23261) (xy 72.9869 -155.07716)
			(xy 72.986398 -155.109121) (xy 72.978387 -155.172539) (xy 72.96249 -155.234453) (xy 72.938958 -155.293886)
			(xy 72.908164 -155.349901) (xy 72.870591 -155.401616) (xy 72.826834 -155.448213) (xy 72.777581 -155.488958)
			(xy 72.72361 -155.523209) (xy 72.665771 -155.550426) (xy 72.604978 -155.570179) (xy 72.542188 -155.582157)
			(xy 72.478392 -155.586171) (xy 72.414596 -155.582157) (xy 72.351806 -155.570179) (xy 72.291013 -155.550426)
			(xy 72.233174 -155.523209) (xy 72.179203 -155.488958) (xy 72.12995 -155.448213) (xy 72.086193 -155.401616)
			(xy 72.04862 -155.349901) (xy 72.017826 -155.293886) (xy 71.994294 -155.234453) (xy 71.978397 -155.172539)
			(xy 71.970386 -155.109121) (xy 71.969884 -155.07716) (xy 27.89936 -155.07716) (xy 27.89936 -156.470598)
			(xy 57.477306 -156.470598) (xy 57.481193 -156.416248) (xy 57.492776 -156.363004) (xy 57.511819 -156.311951)
			(xy 57.537933 -156.264127) (xy 57.570588 -156.220507) (xy 57.609118 -156.181979) (xy 57.65274 -156.149326)
			(xy 57.700564 -156.123213) (xy 57.751618 -156.104172) (xy 57.804862 -156.092591) (xy 57.859212 -156.088706)
			(xy 57.913562 -156.092595) (xy 57.966805 -156.104179) (xy 58.017858 -156.123223) (xy 58.065681 -156.149339)
			(xy 58.087768 -156.165296) (xy 58.10678 -156.178892) (xy 58.148663 -156.199624) (xy 58.193631 -156.21235)
			(xy 58.240168 -156.21664) (xy 58.286705 -156.21235) (xy 58.331673 -156.199624) (xy 58.373556 -156.178892)
			(xy 58.392568 -156.165296) (xy 58.414653 -156.149328) (xy 58.462481 -156.123202) (xy 58.513541 -156.104148)
			(xy 58.566792 -156.092556) (xy 58.621151 -156.088661) (xy 58.675512 -156.092542) (xy 58.728766 -156.104121)
			(xy 58.77983 -156.123161) (xy 58.827665 -156.149275) (xy 58.871296 -156.181932) (xy 58.909835 -156.220466)
			(xy 58.942497 -156.264092) (xy 58.968618 -156.311923) (xy 58.987665 -156.362985) (xy 58.99925 -156.416238)
			(xy 59.003139 -156.470598) (xy 59.363999 -156.470598) (xy 59.367886 -156.416246) (xy 59.37947 -156.363001)
			(xy 59.398513 -156.311946) (xy 59.424629 -156.264121) (xy 59.457285 -156.2205) (xy 59.495816 -156.181971)
			(xy 59.539439 -156.149317) (xy 59.587266 -156.123204) (xy 59.638321 -156.104164) (xy 59.691567 -156.092583)
			(xy 59.745919 -156.088699) (xy 59.800271 -156.092589) (xy 59.853515 -156.104175) (xy 59.904569 -156.12322)
			(xy 59.952393 -156.149338) (xy 59.97448 -156.165296) (xy 59.993492 -156.178892) (xy 60.035375 -156.199624)
			(xy 60.080343 -156.21235) (xy 60.12688 -156.21664) (xy 60.173417 -156.21235) (xy 60.218385 -156.199624)
			(xy 60.260268 -156.178892) (xy 60.27928 -156.165296) (xy 60.301365 -156.149329) (xy 60.349192 -156.123205)
			(xy 60.40025 -156.104153) (xy 60.453501 -156.092562) (xy 60.507858 -156.088668) (xy 60.562217 -156.09255)
			(xy 60.615469 -156.104129) (xy 60.666532 -156.12317) (xy 60.714365 -156.149284) (xy 60.757994 -156.18194)
			(xy 60.796531 -156.220473) (xy 60.829192 -156.264098) (xy 60.855312 -156.311928) (xy 60.874358 -156.362988)
			(xy 60.885943 -156.41624) (xy 60.889832 -156.470598) (xy 61.604973 -156.470598) (xy 61.608862 -156.41624)
			(xy 61.620447 -156.362989) (xy 61.639493 -156.31193) (xy 61.665612 -156.264101) (xy 61.698273 -156.220476)
			(xy 61.73681 -156.181943) (xy 61.780439 -156.149288) (xy 61.828271 -156.123174) (xy 61.879333 -156.104134)
			(xy 61.932585 -156.092555) (xy 61.986943 -156.088673) (xy 62.0413 -156.092568) (xy 62.094549 -156.104158)
			(xy 62.145607 -156.12321) (xy 62.193434 -156.149334) (xy 62.215522 -156.165296) (xy 62.234534 -156.178892)
			(xy 62.276417 -156.199624) (xy 62.321385 -156.21235) (xy 62.367922 -156.21664) (xy 62.414459 -156.21235)
			(xy 62.459427 -156.199624) (xy 62.50131 -156.178892) (xy 62.520322 -156.165296) (xy 62.542406 -156.149333)
			(xy 62.59023 -156.123215) (xy 62.641285 -156.104169) (xy 62.69453 -156.092583) (xy 62.748882 -156.088693)
			(xy 62.803235 -156.092578) (xy 62.856481 -156.104159) (xy 62.907537 -156.1232) (xy 62.955364 -156.149313)
			(xy 62.998987 -156.181967) (xy 63.03752 -156.220497) (xy 63.070176 -156.264119) (xy 63.096292 -156.311944)
			(xy 63.115335 -156.362999) (xy 63.126919 -156.416245) (xy 63.130807 -156.470598) (xy 63.508983 -156.470598)
			(xy 63.512871 -156.416242) (xy 63.524456 -156.362994) (xy 63.543501 -156.311936) (xy 63.569619 -156.264108)
			(xy 63.602277 -156.220485) (xy 63.640812 -156.181954) (xy 63.684439 -156.149299) (xy 63.732269 -156.123186)
			(xy 63.783329 -156.104145) (xy 63.836578 -156.092566) (xy 63.890934 -156.088683) (xy 63.945289 -156.092576)
			(xy 63.998536 -156.104165) (xy 64.049593 -156.123214) (xy 64.097418 -156.149336) (xy 64.119506 -156.165296)
			(xy 64.138518 -156.178892) (xy 64.180401 -156.199624) (xy 64.225369 -156.21235) (xy 64.271906 -156.21664)
			(xy 64.318443 -156.21235) (xy 64.363411 -156.199624) (xy 64.405294 -156.178892) (xy 64.424306 -156.165296)
			(xy 64.44639 -156.149331) (xy 64.494216 -156.123211) (xy 64.545272 -156.104163) (xy 64.598519 -156.092575)
			(xy 64.652873 -156.088684) (xy 64.707228 -156.092568) (xy 64.760477 -156.104148) (xy 64.811535 -156.123188)
			(xy 64.859364 -156.149302) (xy 64.90299 -156.181957) (xy 64.941524 -156.220488) (xy 64.974182 -156.264111)
			(xy 65.000299 -156.311938) (xy 65.019344 -156.362995) (xy 65.030928 -156.416243) (xy 65.034816 -156.470598)
			(xy 65.030929 -156.524952) (xy 65.019345 -156.5782) (xy 65.000301 -156.629258) (xy 64.974185 -156.677085)
			(xy 64.941527 -156.720709) (xy 64.902994 -156.75924) (xy 64.859368 -156.791895) (xy 64.81154 -156.81801)
			(xy 64.760481 -156.837051) (xy 64.707233 -156.848632) (xy 64.652878 -156.852516) (xy 64.598523 -156.848625)
			(xy 64.545276 -156.837038) (xy 64.49422 -156.817991) (xy 64.446394 -156.791871) (xy 64.424306 -156.775912)
			(xy 64.405294 -156.762316) (xy 64.363411 -156.741584) (xy 64.318443 -156.728858) (xy 64.271906 -156.724568)
			(xy 64.225369 -156.728858) (xy 64.180401 -156.741584) (xy 64.138518 -156.762316) (xy 64.119506 -156.775912)
			(xy 64.097414 -156.791867) (xy 64.049588 -156.817988) (xy 63.998532 -156.837037) (xy 63.945284 -156.848625)
			(xy 63.890929 -156.852517) (xy 63.836573 -156.848633) (xy 63.783324 -156.837053) (xy 63.732265 -156.818012)
			(xy 63.684435 -156.791898) (xy 63.640809 -156.759243) (xy 63.602274 -156.720711) (xy 63.569616 -156.677087)
			(xy 63.543499 -156.62926) (xy 63.524454 -156.578202) (xy 63.512871 -156.524953) (xy 63.508983 -156.470598)
			(xy 63.130807 -156.470598) (xy 63.126919 -156.52495) (xy 63.115337 -156.578196) (xy 63.096294 -156.629251)
			(xy 63.070178 -156.677077) (xy 63.037523 -156.720699) (xy 62.998991 -156.75923) (xy 62.955368 -156.791884)
			(xy 62.907542 -156.817998) (xy 62.856486 -156.83704) (xy 62.803239 -156.848621) (xy 62.748887 -156.852507)
			(xy 62.694535 -156.848617) (xy 62.641289 -156.837032) (xy 62.590234 -156.817987) (xy 62.54241 -156.79187)
			(xy 62.520322 -156.775912) (xy 62.50131 -156.762316) (xy 62.459427 -156.741584) (xy 62.414459 -156.728858)
			(xy 62.367922 -156.724568) (xy 62.321385 -156.728858) (xy 62.276417 -156.741584) (xy 62.234534 -156.762316)
			(xy 62.215522 -156.775912) (xy 62.19343 -156.791868) (xy 62.145603 -156.817992) (xy 62.094545 -156.837043)
			(xy 62.041295 -156.848633) (xy 61.986938 -156.852527) (xy 61.93258 -156.848644) (xy 61.879328 -156.837064)
			(xy 61.828267 -156.818024) (xy 61.780435 -156.79191) (xy 61.736806 -156.759254) (xy 61.69827 -156.720721)
			(xy 61.66561 -156.677095) (xy 61.639491 -156.629266) (xy 61.620446 -156.578206) (xy 61.608861 -156.524955)
			(xy 61.604973 -156.470598) (xy 60.889832 -156.470598) (xy 60.885944 -156.524956) (xy 60.874359 -156.578207)
			(xy 60.855314 -156.629268) (xy 60.829195 -156.677098) (xy 60.796535 -156.720724) (xy 60.757998 -156.759257)
			(xy 60.714369 -156.791914) (xy 60.666536 -156.818028) (xy 60.615474 -156.837069) (xy 60.562221 -156.848649)
			(xy 60.507863 -156.852532) (xy 60.453505 -156.848638) (xy 60.400255 -156.837048) (xy 60.349196 -156.817997)
			(xy 60.301369 -156.791874) (xy 60.27928 -156.775912) (xy 60.260268 -156.762316) (xy 60.218385 -156.741584)
			(xy 60.173417 -156.728858) (xy 60.12688 -156.724568) (xy 60.080343 -156.728858) (xy 60.035375 -156.741584)
			(xy 59.993492 -156.762316) (xy 59.97448 -156.775912) (xy 59.952389 -156.791865) (xy 59.904565 -156.817982)
			(xy 59.853511 -156.837027) (xy 59.800266 -156.848612) (xy 59.745914 -156.852501) (xy 59.691562 -156.848616)
			(xy 59.638317 -156.837035) (xy 59.587261 -156.817994) (xy 59.539435 -156.79188) (xy 59.495813 -156.759226)
			(xy 59.457282 -156.720696) (xy 59.424626 -156.677075) (xy 59.398511 -156.629249) (xy 59.379469 -156.578195)
			(xy 59.367886 -156.524949) (xy 59.363999 -156.470598) (xy 59.003139 -156.470598) (xy 58.999251 -156.524957)
			(xy 58.987666 -156.57821) (xy 58.96862 -156.629272) (xy 58.9425 -156.677104) (xy 58.909838 -156.720731)
			(xy 58.8713 -156.759265) (xy 58.827669 -156.791922) (xy 58.779835 -156.818037) (xy 58.728771 -156.837078)
			(xy 58.675516 -156.848657) (xy 58.621156 -156.852539) (xy 58.566797 -156.848644) (xy 58.513545 -156.837053)
			(xy 58.462485 -156.818) (xy 58.414657 -156.791875) (xy 58.392568 -156.775912) (xy 58.373556 -156.762316)
			(xy 58.331673 -156.741584) (xy 58.286705 -156.728858) (xy 58.240168 -156.724568) (xy 58.193631 -156.728858)
			(xy 58.148663 -156.741584) (xy 58.10678 -156.762316) (xy 58.087768 -156.775912) (xy 58.065677 -156.791864)
			(xy 58.017854 -156.817979) (xy 57.966801 -156.837022) (xy 57.913557 -156.848606) (xy 57.859207 -156.852494)
			(xy 57.804857 -156.848608) (xy 57.751613 -156.837026) (xy 57.70056 -156.817985) (xy 57.652736 -156.791872)
			(xy 57.609115 -156.759218) (xy 57.570585 -156.720689) (xy 57.537931 -156.677069) (xy 57.511817 -156.629245)
			(xy 57.492775 -156.578191) (xy 57.481193 -156.524948) (xy 57.477306 -156.470598) (xy 27.89936 -156.470598)
			(xy 27.89936 -158.361084) (xy 57.477323 -158.361084) (xy 57.481213 -158.306737) (xy 57.492797 -158.253496)
			(xy 57.51184 -158.202446) (xy 57.537955 -158.154626) (xy 57.57061 -158.111009) (xy 57.60914 -158.072483)
			(xy 57.65276 -158.039833) (xy 57.700583 -158.013723) (xy 57.751636 -157.994685) (xy 57.804878 -157.983107)
			(xy 57.859225 -157.979223) (xy 57.913573 -157.983114) (xy 57.966813 -157.9947) (xy 58.017863 -158.013745)
			(xy 58.065682 -158.039861) (xy 58.087768 -158.055818) (xy 58.10678 -158.069414) (xy 58.148663 -158.090146)
			(xy 58.193631 -158.102872) (xy 58.240168 -158.107162) (xy 58.286705 -158.102872) (xy 58.331673 -158.090146)
			(xy 58.373556 -158.069414) (xy 58.392568 -158.055818) (xy 58.414633 -158.03982) (xy 58.462462 -158.013691)
			(xy 58.513523 -157.994635) (xy 58.566777 -157.983041) (xy 58.621138 -157.979143) (xy 58.675501 -157.983023)
			(xy 58.728758 -157.9946) (xy 58.779826 -158.01364) (xy 58.827663 -158.039753) (xy 58.871297 -158.07241)
			(xy 58.909839 -158.110944) (xy 58.942505 -158.154571) (xy 58.968628 -158.202404) (xy 58.987678 -158.253467)
			(xy 58.999266 -158.306722) (xy 59.003157 -158.361084) (xy 59.364016 -158.361084) (xy 59.367906 -158.306735)
			(xy 59.379491 -158.253493) (xy 59.398535 -158.202441) (xy 59.424651 -158.15462) (xy 59.457307 -158.111002)
			(xy 59.495838 -158.072475) (xy 59.53946 -158.039825) (xy 59.587285 -158.013715) (xy 59.638339 -157.994677)
			(xy 59.691583 -157.983099) (xy 59.745932 -157.979216) (xy 59.800281 -157.983108) (xy 59.853523 -157.994695)
			(xy 59.904574 -158.013742) (xy 59.952394 -158.03986) (xy 59.97448 -158.055818) (xy 59.993492 -158.069414)
			(xy 60.035375 -158.090146) (xy 60.080343 -158.102872) (xy 60.12688 -158.107162) (xy 60.173417 -158.102872)
			(xy 60.218385 -158.090146) (xy 60.260268 -158.069414) (xy 60.27928 -158.055818) (xy 60.301344 -158.039821)
			(xy 60.349173 -158.013694) (xy 60.400233 -157.99464) (xy 60.453485 -157.983047) (xy 60.507845 -157.979151)
			(xy 60.562206 -157.983031) (xy 60.615462 -157.994609) (xy 60.666527 -158.013648) (xy 60.714363 -158.039762)
			(xy 60.757996 -158.072418) (xy 60.796536 -158.110951) (xy 60.8292 -158.154577) (xy 60.855322 -158.202409)
			(xy 60.874371 -158.253471) (xy 60.885959 -158.306724) (xy 60.889849 -158.361084) (xy 61.604991 -158.361084)
			(xy 61.608881 -158.30673) (xy 61.620468 -158.253482) (xy 61.639515 -158.202425) (xy 61.665634 -158.154599)
			(xy 61.698295 -158.110977) (xy 61.736831 -158.072448) (xy 61.780459 -158.039795) (xy 61.82829 -158.013685)
			(xy 61.879351 -157.994647) (xy 61.932601 -157.983071) (xy 61.986956 -157.979191) (xy 62.041311 -157.983087)
			(xy 62.094557 -157.994679) (xy 62.145612 -158.013731) (xy 62.193435 -158.039856) (xy 62.215522 -158.055818)
			(xy 62.234534 -158.069414) (xy 62.276417 -158.090146) (xy 62.321385 -158.102872) (xy 62.367922 -158.107162)
			(xy 62.414459 -158.102872) (xy 62.459427 -158.090146) (xy 62.50131 -158.069414) (xy 62.520322 -158.055818)
			(xy 62.542385 -158.039825) (xy 62.590211 -158.013704) (xy 62.641267 -157.994656) (xy 62.694514 -157.983068)
			(xy 62.748869 -157.979176) (xy 62.803224 -157.983059) (xy 62.856473 -157.994638) (xy 62.907533 -158.013678)
			(xy 62.955362 -158.039791) (xy 62.998989 -158.072445) (xy 63.037524 -158.110976) (xy 63.070184 -158.154598)
			(xy 63.096302 -158.202425) (xy 63.115348 -158.253482) (xy 63.126934 -158.30673) (xy 63.130824 -158.361084)
			(xy 63.509001 -158.361084) (xy 63.512891 -158.306732) (xy 63.524476 -158.253486) (xy 63.543522 -158.202431)
			(xy 63.56964 -158.154607) (xy 63.602299 -158.110987) (xy 63.640834 -158.072458) (xy 63.68446 -158.039807)
			(xy 63.732288 -158.013696) (xy 63.783346 -157.994659) (xy 63.836594 -157.983082) (xy 63.890947 -157.979201)
			(xy 63.945299 -157.983095) (xy 63.998544 -157.994685) (xy 64.049597 -158.013735) (xy 64.09742 -158.039857)
			(xy 64.119506 -158.055818) (xy 64.138518 -158.069414) (xy 64.180401 -158.090146) (xy 64.225369 -158.102872)
			(xy 64.271906 -158.107162) (xy 64.318443 -158.102872) (xy 64.363411 -158.090146) (xy 64.405294 -158.069414)
			(xy 64.424306 -158.055818) (xy 64.44637 -158.039823) (xy 64.494196 -158.0137) (xy 64.545254 -157.99465)
			(xy 64.598503 -157.98306) (xy 64.65286 -157.979166) (xy 64.707217 -157.983048) (xy 64.760469 -157.994627)
			(xy 64.811531 -158.013667) (xy 64.859363 -158.03978) (xy 64.902991 -158.072435) (xy 64.941529 -158.110966)
			(xy 64.97419 -158.15459) (xy 65.00031 -158.202419) (xy 65.019357 -158.253478) (xy 65.030944 -158.306727)
			(xy 65.034834 -158.361084) (xy 65.030948 -158.415442) (xy 65.019366 -158.468692) (xy 65.000323 -158.519753)
			(xy 64.974207 -158.567583) (xy 64.966798 -158.57748) (xy 66.784121 -158.57748) (xy 66.788012 -158.523131)
			(xy 66.799597 -158.46989) (xy 66.818642 -158.418839) (xy 66.844758 -158.371018) (xy 66.877414 -158.327401)
			(xy 66.915946 -158.288876) (xy 66.959568 -158.256226) (xy 67.007392 -158.230117) (xy 67.058446 -158.21108)
			(xy 67.111689 -158.199503) (xy 67.166038 -158.195621) (xy 67.220386 -158.199514) (xy 67.273627 -158.211102)
			(xy 67.324677 -158.230149) (xy 67.372497 -158.256268) (xy 67.394582 -158.272226) (xy 67.413594 -158.285822)
			(xy 67.455477 -158.306554) (xy 67.500445 -158.31928) (xy 67.546982 -158.32357) (xy 67.593519 -158.31928)
			(xy 67.638487 -158.306554) (xy 67.68037 -158.285822) (xy 67.699382 -158.272226) (xy 67.721439 -158.256219)
			(xy 67.769267 -158.230091) (xy 67.820328 -158.211036) (xy 67.873581 -158.199442) (xy 67.927941 -158.195545)
			(xy 67.982303 -158.199425) (xy 68.035559 -158.211003) (xy 68.086626 -158.230042) (xy 68.134463 -158.256155)
			(xy 68.178096 -158.288811) (xy 68.216637 -158.327344) (xy 68.249302 -158.370971) (xy 68.275425 -158.418802)
			(xy 68.294475 -158.469865) (xy 68.306063 -158.523119) (xy 68.309955 -158.57748) (xy 68.306069 -158.631841)
			(xy 68.300961 -158.655325) (xy 69.733264 -158.655325) (xy 69.737148 -158.600969) (xy 69.748729 -158.547718)
			(xy 69.76777 -158.496658) (xy 69.793884 -158.448827) (xy 69.82654 -158.405199) (xy 69.865072 -158.366664)
			(xy 69.908696 -158.334004) (xy 69.956525 -158.307885) (xy 70.007583 -158.288839) (xy 70.060833 -158.277254)
			(xy 70.115189 -158.273364) (xy 70.169546 -158.27725) (xy 70.222796 -158.288833) (xy 70.273856 -158.307876)
			(xy 70.321685 -158.333992) (xy 70.343776 -158.34995) (xy 70.362788 -158.363546) (xy 70.404671 -158.384278)
			(xy 70.449639 -158.397004) (xy 70.496176 -158.401294) (xy 70.542713 -158.397004) (xy 70.587681 -158.384278)
			(xy 70.629564 -158.363546) (xy 70.648576 -158.34995) (xy 70.670704 -158.334045) (xy 70.718529 -158.307926)
			(xy 70.769584 -158.288879) (xy 70.82283 -158.277293) (xy 70.877184 -158.273403) (xy 70.931537 -158.277288)
			(xy 70.984784 -158.28887) (xy 71.035841 -158.307912) (xy 71.083668 -158.334027) (xy 71.127291 -158.366683)
			(xy 71.165823 -158.405215) (xy 71.198478 -158.448839) (xy 71.224592 -158.496667) (xy 71.243633 -158.547724)
			(xy 71.255213 -158.600972) (xy 71.259097 -158.655325) (xy 71.255206 -158.709678) (xy 71.243619 -158.762924)
			(xy 71.224571 -158.813979) (xy 71.198451 -158.861803) (xy 71.16579 -158.905423) (xy 71.127253 -158.94395)
			(xy 71.083626 -158.9766) (xy 71.035795 -159.002709) (xy 70.984736 -159.021744) (xy 70.931487 -159.033319)
			(xy 70.877133 -159.037197) (xy 70.82278 -159.0333) (xy 70.769536 -159.021707) (xy 70.718483 -159.002653)
			(xy 70.670662 -158.976528) (xy 70.648576 -158.960566) (xy 70.629564 -158.94697) (xy 70.587681 -158.926238)
			(xy 70.542713 -158.913512) (xy 70.496176 -158.909222) (xy 70.449639 -158.913512) (xy 70.404671 -158.926238)
			(xy 70.362788 -158.94697) (xy 70.343776 -158.960566) (xy 70.321728 -158.976581) (xy 70.273901 -159.002703)
			(xy 70.222844 -159.021753) (xy 70.169596 -159.033342) (xy 70.11524 -159.037236) (xy 70.060883 -159.033354)
			(xy 70.007632 -159.021775) (xy 69.956571 -159.002736) (xy 69.908739 -158.976623) (xy 69.86511 -158.943969)
			(xy 69.826573 -158.905439) (xy 69.793912 -158.861816) (xy 69.767791 -158.813988) (xy 69.748743 -158.76293)
			(xy 69.737156 -158.709681) (xy 69.733264 -158.655325) (xy 68.300961 -158.655325) (xy 68.294486 -158.685096)
			(xy 68.275442 -158.736161) (xy 68.249324 -158.783995) (xy 68.216664 -158.827625) (xy 68.178127 -158.866162)
			(xy 68.134497 -158.898823) (xy 68.086663 -158.924941) (xy 68.035599 -158.943986) (xy 67.982344 -158.955569)
			(xy 67.927982 -158.959455) (xy 67.873621 -158.955564) (xy 67.820367 -158.943976) (xy 67.769305 -158.924926)
			(xy 67.721473 -158.898803) (xy 67.699382 -158.882842) (xy 67.68037 -158.869246) (xy 67.638487 -158.848514)
			(xy 67.593519 -158.835788) (xy 67.546982 -158.831498) (xy 67.500445 -158.835788) (xy 67.455477 -158.848514)
			(xy 67.413594 -158.869246) (xy 67.394582 -158.882842) (xy 67.372462 -158.898755) (xy 67.32464 -158.924868)
			(xy 67.273588 -158.94391) (xy 67.220346 -158.955492) (xy 67.165997 -158.959379) (xy 67.111649 -158.955491)
			(xy 67.058407 -158.943908) (xy 67.007355 -158.924866) (xy 66.959533 -158.898752) (xy 66.915915 -158.866098)
			(xy 66.877387 -158.827568) (xy 66.844736 -158.783947) (xy 66.818625 -158.736124) (xy 66.799585 -158.685071)
			(xy 66.788006 -158.631828) (xy 66.784121 -158.57748) (xy 64.966798 -158.57748) (xy 64.941549 -158.61121)
			(xy 64.903015 -158.649745) (xy 64.859389 -158.682403) (xy 64.811559 -158.70852) (xy 64.760499 -158.727564)
			(xy 64.707248 -158.739147) (xy 64.652891 -158.743034) (xy 64.598534 -158.739145) (xy 64.545284 -158.727559)
			(xy 64.494225 -158.708513) (xy 64.446396 -158.682393) (xy 64.424306 -158.666434) (xy 64.405294 -158.652838)
			(xy 64.363411 -158.632106) (xy 64.318443 -158.61938) (xy 64.271906 -158.61509) (xy 64.225369 -158.61938)
			(xy 64.180401 -158.632106) (xy 64.138518 -158.652838) (xy 64.119506 -158.666434) (xy 64.097393 -158.682359)
			(xy 64.049569 -158.708478) (xy 63.998514 -158.727524) (xy 63.945268 -158.739109) (xy 63.890916 -158.742999)
			(xy 63.836563 -158.739114) (xy 63.783316 -158.727533) (xy 63.73226 -158.708491) (xy 63.684433 -158.682377)
			(xy 63.64081 -158.649721) (xy 63.602279 -158.61119) (xy 63.569624 -158.567567) (xy 63.543509 -158.51974)
			(xy 63.524468 -158.468684) (xy 63.512886 -158.415437) (xy 63.509001 -158.361084) (xy 63.130824 -158.361084)
			(xy 63.126939 -158.415439) (xy 63.115357 -158.468688) (xy 63.096315 -158.519747) (xy 63.0702 -158.567575)
			(xy 63.037545 -158.611201) (xy 62.999013 -158.649734) (xy 62.955389 -158.682392) (xy 62.907561 -158.708509)
			(xy 62.856503 -158.727553) (xy 62.803255 -158.739137) (xy 62.7489 -158.743024) (xy 62.694545 -158.739137)
			(xy 62.641297 -158.727553) (xy 62.590239 -158.708509) (xy 62.542412 -158.682392) (xy 62.520322 -158.666434)
			(xy 62.50131 -158.652838) (xy 62.459427 -158.632106) (xy 62.414459 -158.61938) (xy 62.367922 -158.61509)
			(xy 62.321385 -158.61938) (xy 62.276417 -158.632106) (xy 62.234534 -158.652838) (xy 62.215522 -158.666434)
			(xy 62.193409 -158.682361) (xy 62.145583 -158.708482) (xy 62.094527 -158.72753) (xy 62.04128 -158.739118)
			(xy 61.986925 -158.743009) (xy 61.93257 -158.739125) (xy 61.879321 -158.727544) (xy 61.828262 -158.708502)
			(xy 61.780433 -158.682388) (xy 61.736808 -158.649732) (xy 61.698274 -158.611199) (xy 61.665617 -158.567575)
			(xy 61.639502 -158.519747) (xy 61.620459 -158.468688) (xy 61.608877 -158.41544) (xy 61.604991 -158.361084)
			(xy 60.889849 -158.361084) (xy 60.885963 -158.415445) (xy 60.87438 -158.468699) (xy 60.855335 -158.519763)
			(xy 60.829217 -158.567596) (xy 60.796557 -158.611225) (xy 60.758019 -158.649762) (xy 60.714389 -158.682421)
			(xy 60.666556 -158.708539) (xy 60.615492 -158.727582) (xy 60.562237 -158.739165) (xy 60.507876 -158.743049)
			(xy 60.453516 -158.739158) (xy 60.400263 -158.727569) (xy 60.349201 -158.708519) (xy 60.301371 -158.682396)
			(xy 60.27928 -158.666434) (xy 60.260268 -158.652838) (xy 60.218385 -158.632106) (xy 60.173417 -158.61938)
			(xy 60.12688 -158.61509) (xy 60.080343 -158.61938) (xy 60.035375 -158.632106) (xy 59.993492 -158.652838)
			(xy 59.97448 -158.666434) (xy 59.952368 -158.682357) (xy 59.904545 -158.708471) (xy 59.853493 -158.727514)
			(xy 59.80025 -158.739096) (xy 59.745901 -158.742984) (xy 59.691552 -158.739097) (xy 59.638309 -158.727514)
			(xy 59.587257 -158.708472) (xy 59.539434 -158.682358) (xy 59.495814 -158.649704) (xy 59.457286 -158.611175)
			(xy 59.424634 -158.567554) (xy 59.398522 -158.51973) (xy 59.379482 -158.468677) (xy 59.367901 -158.415434)
			(xy 59.364016 -158.361084) (xy 59.003157 -158.361084) (xy 58.99927 -158.415447) (xy 58.987687 -158.468703)
			(xy 58.968641 -158.519768) (xy 58.942522 -158.567602) (xy 58.90986 -158.611232) (xy 58.871321 -158.64977)
			(xy 58.82769 -158.68243) (xy 58.779854 -158.708547) (xy 58.728788 -158.727591) (xy 58.675532 -158.739173)
			(xy 58.621169 -158.743057) (xy 58.566807 -158.739164) (xy 58.513553 -158.727574) (xy 58.46249 -158.708522)
			(xy 58.414659 -158.682397) (xy 58.392568 -158.666434) (xy 58.373556 -158.652838) (xy 58.331673 -158.632106)
			(xy 58.286705 -158.61938) (xy 58.240168 -158.61509) (xy 58.193631 -158.61938) (xy 58.148663 -158.632106)
			(xy 58.10678 -158.652838) (xy 58.087768 -158.666434) (xy 58.065656 -158.682356) (xy 58.017834 -158.708468)
			(xy 57.966783 -158.727509) (xy 57.913542 -158.73909) (xy 57.859194 -158.742977) (xy 57.804847 -158.739089)
			(xy 57.751606 -158.727506) (xy 57.700555 -158.708464) (xy 57.652734 -158.68235) (xy 57.609116 -158.649696)
			(xy 57.57059 -158.611168) (xy 57.537939 -158.567548) (xy 57.511828 -158.519725) (xy 57.492788 -158.468674)
			(xy 57.481208 -158.415432) (xy 57.477323 -158.361084) (xy 27.89936 -158.361084) (xy 27.89936 -160.402318)
			(xy 57.477279 -160.402318) (xy 57.481164 -160.347964) (xy 57.492745 -160.294716) (xy 57.511786 -160.243658)
			(xy 57.5379 -160.19583) (xy 57.570554 -160.152205) (xy 57.609085 -160.113671) (xy 57.652708 -160.081014)
			(xy 57.700534 -160.054897) (xy 57.751591 -160.035852) (xy 57.804838 -160.024267) (xy 57.859192 -160.020379)
			(xy 57.913546 -160.024265) (xy 57.966794 -160.035847) (xy 58.017851 -160.05489) (xy 58.065678 -160.081005)
			(xy 58.087768 -160.096962) (xy 58.10678 -160.110558) (xy 58.148663 -160.13129) (xy 58.193631 -160.144016)
			(xy 58.240168 -160.148306) (xy 58.286705 -160.144016) (xy 58.331673 -160.13129) (xy 58.373556 -160.110558)
			(xy 58.392568 -160.096962) (xy 58.414685 -160.08104) (xy 58.462511 -160.054918) (xy 58.513568 -160.035869)
			(xy 58.566816 -160.02428) (xy 58.621172 -160.020388) (xy 58.675528 -160.024272) (xy 58.728778 -160.035853)
			(xy 58.779838 -160.054894) (xy 58.827667 -160.081009) (xy 58.871294 -160.113666) (xy 58.909828 -160.152199)
			(xy 58.942485 -160.195824) (xy 58.968601 -160.243653) (xy 58.987644 -160.294712) (xy 58.999226 -160.347962)
			(xy 59.003112 -160.402318) (xy 59.363971 -160.402318) (xy 59.367857 -160.347962) (xy 59.379438 -160.294713)
			(xy 59.39848 -160.243653) (xy 59.424595 -160.195824) (xy 59.457251 -160.152198) (xy 59.495783 -160.113663)
			(xy 59.539408 -160.081005) (xy 59.587236 -160.054888) (xy 59.638294 -160.035843) (xy 59.691543 -160.024259)
			(xy 59.745899 -160.020371) (xy 59.800254 -160.024259) (xy 59.853503 -160.035843) (xy 59.904562 -160.054887)
			(xy 59.95239 -160.081004) (xy 59.97448 -160.096962) (xy 59.993492 -160.110558) (xy 60.035375 -160.13129)
			(xy 60.080343 -160.144016) (xy 60.12688 -160.148306) (xy 60.173417 -160.144016) (xy 60.218385 -160.13129)
			(xy 60.260268 -160.110558) (xy 60.27928 -160.096962) (xy 60.301397 -160.081041) (xy 60.349222 -160.054921)
			(xy 60.400278 -160.035873) (xy 60.453525 -160.024286) (xy 60.507879 -160.020396) (xy 60.562233 -160.02428)
			(xy 60.615481 -160.035861) (xy 60.666539 -160.054903) (xy 60.714367 -160.081018) (xy 60.757992 -160.113674)
			(xy 60.796524 -160.152206) (xy 60.82918 -160.19583) (xy 60.855296 -160.243658) (xy 60.874338 -160.294715)
			(xy 60.885919 -160.347964) (xy 60.889804 -160.402318) (xy 61.604946 -160.402318) (xy 61.608832 -160.347956)
			(xy 61.620415 -160.294701) (xy 61.63946 -160.243637) (xy 61.665578 -160.195803) (xy 61.698239 -160.152173)
			(xy 61.736777 -160.113636) (xy 61.780407 -160.080976) (xy 61.828241 -160.054858) (xy 61.879306 -160.035814)
			(xy 61.932561 -160.024231) (xy 61.986923 -160.020346) (xy 62.041284 -160.024238) (xy 62.094538 -160.035827)
			(xy 62.1456 -160.054877) (xy 62.193431 -160.081) (xy 62.215522 -160.096962) (xy 62.234534 -160.110558)
			(xy 62.276417 -160.13129) (xy 62.321385 -160.144016) (xy 62.367922 -160.148306) (xy 62.414459 -160.144016)
			(xy 62.459427 -160.13129) (xy 62.50131 -160.110558) (xy 62.520322 -160.096962) (xy 62.542438 -160.081044)
			(xy 62.59026 -160.054931) (xy 62.641312 -160.03589) (xy 62.694554 -160.024308) (xy 62.748902 -160.020421)
			(xy 62.803251 -160.024308) (xy 62.856493 -160.035891) (xy 62.907545 -160.054933) (xy 62.955366 -160.081047)
			(xy 62.998985 -160.113701) (xy 63.037512 -160.15223) (xy 63.070164 -160.195851) (xy 63.096275 -160.243674)
			(xy 63.115315 -160.294727) (xy 63.126895 -160.347969) (xy 63.130779 -160.402318) (xy 63.508956 -160.402318)
			(xy 63.512841 -160.347959) (xy 63.524424 -160.294706) (xy 63.543467 -160.243643) (xy 63.569585 -160.195811)
			(xy 63.602243 -160.152183) (xy 63.640779 -160.113646) (xy 63.684407 -160.080987) (xy 63.732239 -160.054869)
			(xy 63.783301 -160.035825) (xy 63.836554 -160.024242) (xy 63.890913 -160.020356) (xy 63.945272 -160.024246)
			(xy 63.998524 -160.035833) (xy 64.049585 -160.054881) (xy 64.097416 -160.081002) (xy 64.119506 -160.096962)
			(xy 64.138518 -160.110558) (xy 64.180401 -160.13129) (xy 64.225369 -160.144016) (xy 64.271906 -160.148306)
			(xy 64.318443 -160.144016) (xy 64.363411 -160.13129) (xy 64.405294 -160.110558) (xy 64.424306 -160.096962)
			(xy 64.446422 -160.081043) (xy 64.494245 -160.054927) (xy 64.545299 -160.035883) (xy 64.598543 -160.024299)
			(xy 64.652893 -160.020411) (xy 64.707244 -160.024298) (xy 64.760488 -160.03588) (xy 64.811542 -160.054922)
			(xy 64.859367 -160.081036) (xy 64.902988 -160.113691) (xy 64.941517 -160.152221) (xy 64.97417 -160.195843)
			(xy 65.000283 -160.243668) (xy 65.019324 -160.294722) (xy 65.030904 -160.347967) (xy 65.034789 -160.402318)
			(xy 65.030899 -160.456668) (xy 65.019313 -160.509912) (xy 65.000268 -160.560965) (xy 64.974151 -160.608787)
			(xy 64.941493 -160.652406) (xy 64.90296 -160.690933) (xy 64.859336 -160.723584) (xy 64.81151 -160.749693)
			(xy 64.760454 -160.76873) (xy 64.707208 -160.780308) (xy 64.652857 -160.784189) (xy 64.598507 -160.780295)
			(xy 64.545264 -160.768706) (xy 64.494213 -160.749658) (xy 64.446392 -160.723538) (xy 64.424306 -160.707578)
			(xy 64.405294 -160.693982) (xy 64.363411 -160.67325) (xy 64.318443 -160.660524) (xy 64.271906 -160.656234)
			(xy 64.225369 -160.660524) (xy 64.180401 -160.67325) (xy 64.138518 -160.693982) (xy 64.119506 -160.707578)
			(xy 64.097446 -160.723579) (xy 64.049618 -160.749704) (xy 63.998559 -160.768757) (xy 63.945308 -160.780349)
			(xy 63.890949 -160.784244) (xy 63.83659 -160.780363) (xy 63.783336 -160.768785) (xy 63.732272 -160.749746)
			(xy 63.684437 -160.723632) (xy 63.640806 -160.690977) (xy 63.602267 -160.652445) (xy 63.569604 -160.608819)
			(xy 63.543482 -160.56099) (xy 63.524434 -160.509929) (xy 63.512846 -160.456677) (xy 63.508956 -160.402318)
			(xy 63.130779 -160.402318) (xy 63.12689 -160.456666) (xy 63.115305 -160.509908) (xy 63.09626 -160.560959)
			(xy 63.070145 -160.608779) (xy 63.037489 -160.652397) (xy 62.998958 -160.690922) (xy 62.955336 -160.723572)
			(xy 62.907512 -160.749682) (xy 62.856458 -160.768719) (xy 62.803215 -160.780297) (xy 62.748866 -160.784179)
			(xy 62.694518 -160.780287) (xy 62.641277 -160.7687) (xy 62.590227 -160.749654) (xy 62.542407 -160.723536)
			(xy 62.520322 -160.707578) (xy 62.50131 -160.693982) (xy 62.459427 -160.67325) (xy 62.414459 -160.660524)
			(xy 62.367922 -160.656234) (xy 62.321385 -160.660524) (xy 62.276417 -160.67325) (xy 62.234534 -160.693982)
			(xy 62.215522 -160.707578) (xy 62.193461 -160.72358) (xy 62.145633 -160.749708) (xy 62.094572 -160.768763)
			(xy 62.041319 -160.780357) (xy 61.986959 -160.784254) (xy 61.932597 -160.780374) (xy 61.87934 -160.768796)
			(xy 61.828274 -160.749757) (xy 61.780437 -160.723644) (xy 61.736804 -160.690988) (xy 61.698263 -160.652454)
			(xy 61.665598 -160.608827) (xy 61.639475 -160.560996) (xy 61.620425 -160.509933) (xy 61.608837 -160.456679)
			(xy 61.604946 -160.402318) (xy 60.889804 -160.402318) (xy 60.885914 -160.456672) (xy 60.874328 -160.509919)
			(xy 60.855281 -160.560975) (xy 60.829161 -160.6088) (xy 60.796501 -160.652421) (xy 60.757964 -160.69095)
			(xy 60.714337 -160.723602) (xy 60.666506 -160.749712) (xy 60.615447 -160.768749) (xy 60.562197 -160.780325)
			(xy 60.507843 -160.784204) (xy 60.453489 -160.780309) (xy 60.400243 -160.768716) (xy 60.349189 -160.749664)
			(xy 60.301366 -160.72354) (xy 60.27928 -160.707578) (xy 60.260268 -160.693982) (xy 60.218385 -160.67325)
			(xy 60.173417 -160.660524) (xy 60.12688 -160.656234) (xy 60.080343 -160.660524) (xy 60.035375 -160.67325)
			(xy 59.993492 -160.693982) (xy 59.97448 -160.707578) (xy 59.95242 -160.723577) (xy 59.904595 -160.749698)
			(xy 59.853538 -160.768747) (xy 59.80029 -160.780336) (xy 59.745935 -160.784229) (xy 59.691579 -160.780346)
			(xy 59.638329 -160.768767) (xy 59.587269 -160.749727) (xy 59.539438 -160.723614) (xy 59.49581 -160.69096)
			(xy 59.457274 -160.652429) (xy 59.424614 -160.608806) (xy 59.398495 -160.560979) (xy 59.379448 -160.509922)
			(xy 59.367862 -160.456673) (xy 59.363971 -160.402318) (xy 59.003112 -160.402318) (xy 58.999221 -160.456674)
			(xy 58.987634 -160.509922) (xy 58.968586 -160.56098) (xy 58.942466 -160.608806) (xy 58.909804 -160.652428)
			(xy 58.871266 -160.690958) (xy 58.827637 -160.72361) (xy 58.779805 -160.749721) (xy 58.728743 -160.768757)
			(xy 58.675492 -160.780333) (xy 58.621136 -160.784212) (xy 58.566781 -160.780315) (xy 58.513533 -160.768721)
			(xy 58.462478 -160.749667) (xy 58.414655 -160.723541) (xy 58.392568 -160.707578) (xy 58.373556 -160.693982)
			(xy 58.331673 -160.67325) (xy 58.286705 -160.660524) (xy 58.240168 -160.656234) (xy 58.193631 -160.660524)
			(xy 58.148663 -160.67325) (xy 58.10678 -160.693982) (xy 58.087768 -160.707578) (xy 58.065709 -160.723576)
			(xy 58.017884 -160.749695) (xy 57.966828 -160.768743) (xy 57.913582 -160.78033) (xy 57.859228 -160.784221)
			(xy 57.804874 -160.780338) (xy 57.751625 -160.768758) (xy 57.700567 -160.749718) (xy 57.652738 -160.723606)
			(xy 57.609112 -160.690952) (xy 57.570578 -160.652422) (xy 57.537919 -160.6088) (xy 57.511801 -160.560975)
			(xy 57.492755 -160.509919) (xy 57.481169 -160.456672) (xy 57.477279 -160.402318) (xy 27.89936 -160.402318)
			(xy 27.89936 -162.312102) (xy 57.477299 -162.312102) (xy 57.481186 -162.257751) (xy 57.492769 -162.204507)
			(xy 57.511811 -162.153453) (xy 57.537925 -162.105628) (xy 57.57058 -162.062007) (xy 57.609111 -162.023477)
			(xy 57.652732 -161.990823) (xy 57.700557 -161.964709) (xy 57.751612 -161.945668) (xy 57.804856 -161.934086)
			(xy 57.859207 -161.930199) (xy 57.913558 -161.934088) (xy 57.966803 -161.945672) (xy 58.017856 -161.964715)
			(xy 58.06568 -161.990831) (xy 58.087768 -162.006788) (xy 58.10678 -162.020384) (xy 58.148663 -162.041116)
			(xy 58.193631 -162.053842) (xy 58.240168 -162.058132) (xy 58.286705 -162.053842) (xy 58.331673 -162.041116)
			(xy 58.373556 -162.020384) (xy 58.392568 -162.006788) (xy 58.414661 -161.990831) (xy 58.462488 -161.964705)
			(xy 58.513547 -161.945653) (xy 58.566798 -161.934062) (xy 58.621156 -161.930168) (xy 58.675515 -161.934049)
			(xy 58.728769 -161.945628) (xy 58.779832 -161.964669) (xy 58.827666 -161.990783) (xy 58.871295 -162.02344)
			(xy 58.909833 -162.061973) (xy 58.942494 -162.1056) (xy 58.968614 -162.15343) (xy 58.98766 -162.204491)
			(xy 58.999245 -162.257744) (xy 59.003133 -162.312102) (xy 59.363992 -162.312102) (xy 59.367879 -162.25775)
			(xy 59.379462 -162.204504) (xy 59.398505 -162.153448) (xy 59.424621 -162.105622) (xy 59.457277 -162.062)
			(xy 59.495809 -162.023469) (xy 59.539432 -161.990814) (xy 59.587259 -161.9647) (xy 59.638315 -161.945659)
			(xy 59.691561 -161.934078) (xy 59.745914 -161.930192) (xy 59.800267 -161.934082) (xy 59.853512 -161.945667)
			(xy 59.904567 -161.964712) (xy 59.952392 -161.99083) (xy 59.97448 -162.006788) (xy 59.993492 -162.020384)
			(xy 60.035375 -162.041116) (xy 60.080343 -162.053842) (xy 60.12688 -162.058132) (xy 60.173417 -162.053842)
			(xy 60.218385 -162.041116) (xy 60.260268 -162.020384) (xy 60.27928 -162.006788) (xy 60.301372 -161.990832)
			(xy 60.349199 -161.964708) (xy 60.400257 -161.945658) (xy 60.453506 -161.934068) (xy 60.507863 -161.930175)
			(xy 60.562221 -161.934057) (xy 60.615472 -161.945637) (xy 60.666534 -161.964678) (xy 60.714365 -161.990792)
			(xy 60.757993 -162.023448) (xy 60.79653 -162.06198) (xy 60.82919 -162.105606) (xy 60.855308 -162.153435)
			(xy 60.874353 -162.204495) (xy 60.885938 -162.257745) (xy 60.889825 -162.312102) (xy 61.604967 -162.312102)
			(xy 61.608855 -162.257744) (xy 61.620439 -162.204492) (xy 61.639485 -162.153431) (xy 61.665604 -162.105601)
			(xy 61.698265 -162.061975) (xy 61.736802 -162.023441) (xy 61.780431 -161.990785) (xy 61.828264 -161.96467)
			(xy 61.879327 -161.945629) (xy 61.932579 -161.93405) (xy 61.986938 -161.930167) (xy 62.041296 -161.934061)
			(xy 62.094547 -161.945651) (xy 62.145605 -161.964702) (xy 62.193433 -161.990826) (xy 62.215522 -162.006788)
			(xy 62.234534 -162.020384) (xy 62.276417 -162.041116) (xy 62.321385 -162.053842) (xy 62.367922 -162.058132)
			(xy 62.414459 -162.053842) (xy 62.459427 -162.041116) (xy 62.50131 -162.020384) (xy 62.520322 -162.006788)
			(xy 62.542413 -161.990835) (xy 62.590237 -161.964719) (xy 62.641291 -161.945674) (xy 62.694536 -161.934089)
			(xy 62.748887 -161.9302) (xy 62.803238 -161.934085) (xy 62.856484 -161.945667) (xy 62.907539 -161.964708)
			(xy 62.955365 -161.990821) (xy 62.998987 -162.023475) (xy 63.037518 -162.062005) (xy 63.070173 -162.105626)
			(xy 63.096288 -162.153451) (xy 63.11533 -162.204506) (xy 63.126913 -162.257751) (xy 63.1308 -162.312102)
			(xy 63.508977 -162.312102) (xy 63.512864 -162.257746) (xy 63.524448 -162.204497) (xy 63.543493 -162.153438)
			(xy 63.569611 -162.105609) (xy 63.602269 -162.061984) (xy 63.640805 -162.023452) (xy 63.684431 -161.990796)
			(xy 63.732262 -161.964682) (xy 63.783322 -161.945641) (xy 63.836573 -161.93406) (xy 63.890929 -161.930177)
			(xy 63.945285 -161.934069) (xy 63.998534 -161.945657) (xy 64.049591 -161.964706) (xy 64.097417 -161.990828)
			(xy 64.119506 -162.006788) (xy 64.138518 -162.020384) (xy 64.180401 -162.041116) (xy 64.225369 -162.053842)
			(xy 64.271906 -162.058132) (xy 64.318443 -162.053842) (xy 64.363411 -162.041116) (xy 64.405294 -162.020384)
			(xy 64.424306 -162.006788) (xy 64.446398 -161.990834) (xy 64.494223 -161.964715) (xy 64.545278 -161.945668)
			(xy 64.598524 -161.934081) (xy 64.652878 -161.93019) (xy 64.707232 -161.934075) (xy 64.760479 -161.945655)
			(xy 64.811537 -161.964696) (xy 64.859365 -161.99081) (xy 64.902989 -162.023465) (xy 64.941522 -162.061996)
			(xy 64.974179 -162.105618) (xy 65.000296 -162.153445) (xy 65.019339 -162.204502) (xy 65.030922 -162.257749)
			(xy 65.03481 -162.312102) (xy 65.030922 -162.366456) (xy 65.019338 -162.419703) (xy 65.000294 -162.470759)
			(xy 64.974177 -162.518586) (xy 64.941519 -162.562208) (xy 64.902986 -162.600738) (xy 64.859361 -162.633393)
			(xy 64.811533 -162.659506) (xy 64.760475 -162.678546) (xy 64.707227 -162.690126) (xy 64.652873 -162.69401)
			(xy 64.59852 -162.690118) (xy 64.545273 -162.678531) (xy 64.494218 -162.659483) (xy 64.446394 -162.633363)
			(xy 64.424306 -162.617404) (xy 64.405294 -162.603808) (xy 64.363411 -162.583076) (xy 64.318443 -162.57035)
			(xy 64.271906 -162.56606) (xy 64.225369 -162.57035) (xy 64.180401 -162.583076) (xy 64.138518 -162.603808)
			(xy 64.119506 -162.617404) (xy 64.097421 -162.63337) (xy 64.049595 -162.659492) (xy 63.998538 -162.678542)
			(xy 63.94529 -162.690131) (xy 63.890934 -162.694023) (xy 63.836577 -162.69014) (xy 63.783327 -162.678561)
			(xy 63.732266 -162.65952) (xy 63.684436 -162.633406) (xy 63.640808 -162.600751) (xy 63.602273 -162.562219)
			(xy 63.569613 -162.518595) (xy 63.543495 -162.470767) (xy 63.52445 -162.419708) (xy 63.512865 -162.366459)
			(xy 63.508977 -162.312102) (xy 63.1308 -162.312102) (xy 63.126912 -162.366454) (xy 63.115329 -162.419699)
			(xy 63.096286 -162.470753) (xy 63.07017 -162.518578) (xy 63.037515 -162.562199) (xy 62.998983 -162.600728)
			(xy 62.95536 -162.633381) (xy 62.907535 -162.659494) (xy 62.856479 -162.678535) (xy 62.803234 -162.690115)
			(xy 62.748882 -162.694) (xy 62.694531 -162.69011) (xy 62.641286 -162.678525) (xy 62.590233 -162.659479)
			(xy 62.542409 -162.633362) (xy 62.520322 -162.617404) (xy 62.50131 -162.603808) (xy 62.459427 -162.583076)
			(xy 62.414459 -162.57035) (xy 62.367922 -162.56606) (xy 62.321385 -162.57035) (xy 62.276417 -162.583076)
			(xy 62.234534 -162.603808) (xy 62.215522 -162.617404) (xy 62.193437 -162.633371) (xy 62.14561 -162.659496)
			(xy 62.094551 -162.678548) (xy 62.041301 -162.690139) (xy 61.986943 -162.694033) (xy 61.932584 -162.690151)
			(xy 61.879331 -162.678572) (xy 61.828268 -162.659532) (xy 61.780435 -162.633418) (xy 61.736806 -162.600762)
			(xy 61.698268 -162.562229) (xy 61.665607 -162.518603) (xy 61.639487 -162.470773) (xy 61.620441 -162.419712)
			(xy 61.608855 -162.366461) (xy 61.604967 -162.312102) (xy 60.889825 -162.312102) (xy 60.885937 -162.36646)
			(xy 60.874352 -162.41971) (xy 60.855306 -162.470769) (xy 60.829187 -162.518598) (xy 60.796527 -162.562223)
			(xy 60.75799 -162.600756) (xy 60.714361 -162.633411) (xy 60.666529 -162.659524) (xy 60.615468 -162.678564)
			(xy 60.562216 -162.690143) (xy 60.507858 -162.694025) (xy 60.453501 -162.690131) (xy 60.400252 -162.678541)
			(xy 60.349195 -162.65949) (xy 60.301368 -162.633366) (xy 60.27928 -162.617404) (xy 60.260268 -162.603808)
			(xy 60.218385 -162.583076) (xy 60.173417 -162.57035) (xy 60.12688 -162.56606) (xy 60.080343 -162.57035)
			(xy 60.035375 -162.583076) (xy 59.993492 -162.603808) (xy 59.97448 -162.617404) (xy 59.952396 -162.633368)
			(xy 59.904572 -162.659486) (xy 59.853517 -162.678532) (xy 59.800272 -162.690118) (xy 59.745919 -162.694008)
			(xy 59.691566 -162.690123) (xy 59.63832 -162.678542) (xy 59.587263 -162.659502) (xy 59.539436 -162.633388)
			(xy 59.495812 -162.600734) (xy 59.45728 -162.562204) (xy 59.424623 -162.518582) (xy 59.398507 -162.470757)
			(xy 59.379464 -162.419701) (xy 59.36788 -162.366455) (xy 59.363992 -162.312102) (xy 59.003133 -162.312102)
			(xy 58.999244 -162.366461) (xy 58.987659 -162.419713) (xy 58.968612 -162.470774) (xy 58.942492 -162.518604)
			(xy 58.90983 -162.56223) (xy 58.871292 -162.600763) (xy 58.827662 -162.633419) (xy 58.779828 -162.659533)
			(xy 58.728764 -162.678573) (xy 58.675511 -162.690151) (xy 58.621151 -162.694032) (xy 58.566793 -162.690137)
			(xy 58.513542 -162.678545) (xy 58.462484 -162.659493) (xy 58.414657 -162.633367) (xy 58.392568 -162.617404)
			(xy 58.373556 -162.603808) (xy 58.331673 -162.583076) (xy 58.286705 -162.57035) (xy 58.240168 -162.56606)
			(xy 58.193631 -162.57035) (xy 58.148663 -162.583076) (xy 58.10678 -162.603808) (xy 58.087768 -162.617404)
			(xy 58.065684 -162.633367) (xy 58.017861 -162.659483) (xy 57.966807 -162.678527) (xy 57.913563 -162.690111)
			(xy 57.859212 -162.694001) (xy 57.804861 -162.690115) (xy 57.751616 -162.678534) (xy 57.700561 -162.659493)
			(xy 57.652736 -162.63338) (xy 57.609114 -162.600726) (xy 57.570583 -162.562197) (xy 57.537928 -162.518576)
			(xy 57.511813 -162.470752) (xy 57.49277 -162.419698) (xy 57.481187 -162.366453) (xy 57.477299 -162.312102)
			(xy 27.89936 -162.312102) (xy 27.89936 -165.65118) (xy 89.533982 -165.65118) (xy 89.538053 -165.595558)
			(xy 89.550179 -165.541121) (xy 89.570102 -165.48903) (xy 89.597398 -165.440395) (xy 89.631484 -165.396252)
			(xy 89.671633 -165.357543) (xy 89.716991 -165.325092) (xy 89.766591 -165.299591) (xy 89.819375 -165.281584)
			(xy 89.874218 -165.271454) (xy 89.929952 -165.269417) (xy 89.985389 -165.275517) (xy 90.039346 -165.289623)
			(xy 90.090675 -165.311435) (xy 90.138281 -165.340489) (xy 90.181149 -165.376164) (xy 90.218366 -165.417701)
			(xy 90.249139 -165.464214) (xy 90.272811 -165.514711) (xy 90.288879 -165.568118) (xy 90.296999 -165.623294)
			(xy 90.297508 -165.65118) (xy 90.296999 -165.679066) (xy 90.288879 -165.734242) (xy 90.272811 -165.787649)
			(xy 90.249139 -165.838146) (xy 90.218366 -165.884659) (xy 90.181149 -165.926196) (xy 90.138281 -165.961871)
			(xy 90.090675 -165.990925) (xy 90.039346 -166.012737) (xy 89.985389 -166.026843) (xy 89.929952 -166.032943)
			(xy 89.874218 -166.030906) (xy 89.819375 -166.020776) (xy 89.766591 -166.002769) (xy 89.716991 -165.977268)
			(xy 89.671633 -165.944817) (xy 89.631484 -165.906108) (xy 89.597398 -165.861965) (xy 89.570102 -165.81333)
			(xy 89.550179 -165.761239) (xy 89.538053 -165.706802) (xy 89.533982 -165.65118) (xy 27.89936 -165.65118)
			(xy 27.89936 -171.735496) (xy 68.099432 -171.735496) (xy 68.099432 -170.736768) (xy 68.09992 -170.704727)
			(xy 68.108001 -170.641157) (xy 68.124005 -170.579105) (xy 68.147679 -170.519556) (xy 68.178648 -170.463454)
			(xy 68.21642 -170.411687) (xy 68.260397 -170.365077) (xy 68.309882 -170.324362) (xy 68.364091 -170.290187)
			(xy 68.422164 -170.263094) (xy 68.483181 -170.243512) (xy 68.546175 -170.231752) (xy 68.610147 -170.228001)
			(xy 68.674084 -170.232317) (xy 68.736972 -170.244633) (xy 68.797813 -170.264752) (xy 68.855645 -170.292357)
			(xy 68.90955 -170.327009) (xy 68.958674 -170.36816) (xy 68.980812 -170.391328) (xy 68.997005 -170.408027)
			(xy 69.034305 -170.43581) (xy 69.076036 -170.456345) (xy 69.120806 -170.468946) (xy 69.167121 -170.473194)
			(xy 69.213436 -170.468946) (xy 69.258206 -170.456345) (xy 69.299937 -170.43581) (xy 69.337237 -170.408027)
			(xy 69.35343 -170.391328) (xy 69.375856 -170.367923) (xy 69.425574 -170.326332) (xy 69.480176 -170.291399)
			(xy 69.538775 -170.263688) (xy 69.60042 -170.243651) (xy 69.664113 -170.231612) (xy 69.728819 -170.227766)
			(xy 69.793489 -170.232176) (xy 69.857075 -170.244771) (xy 69.918543 -170.265344) (xy 69.976898 -170.293565)
			(xy 70.031193 -170.328973) (xy 70.080547 -170.370995) (xy 70.10273 -170.39463) (xy 70.118941 -170.411658)
			(xy 70.156456 -170.439988) (xy 70.198538 -170.460942) (xy 70.243753 -170.473807) (xy 70.290563 -170.478145)
			(xy 70.337373 -170.473807) (xy 70.382588 -170.460942) (xy 70.42467 -170.439988) (xy 70.462185 -170.411658)
			(xy 70.478396 -170.39463) (xy 70.500514 -170.371072) (xy 70.549711 -170.329175) (xy 70.603819 -170.293848)
			(xy 70.661966 -170.26566) (xy 70.723216 -170.245066) (xy 70.786581 -170.232397) (xy 70.851041 -170.227858)
			(xy 70.915556 -170.231521) (xy 70.979088 -170.243327) (xy 71.040612 -170.263087) (xy 71.099137 -170.290482)
			(xy 71.15372 -170.325071) (xy 71.203482 -170.366295) (xy 71.225918 -170.38955) (xy 71.242098 -170.406083)
			(xy 71.279299 -170.43357) (xy 71.320857 -170.453877) (xy 71.365402 -170.466336) (xy 71.411465 -170.470535)
			(xy 71.457528 -170.466336) (xy 71.502073 -170.453877) (xy 71.543631 -170.43357) (xy 71.580832 -170.406083)
			(xy 71.597012 -170.38955) (xy 71.619261 -170.366561) (xy 71.668462 -170.325668) (xy 71.722404 -170.291271)
			(xy 71.780236 -170.263914) (xy 71.841043 -170.244029) (xy 71.903864 -170.23193) (xy 71.967707 -170.227809)
			(xy 72.031563 -170.231731) (xy 72.094421 -170.243634) (xy 72.15529 -170.263329) (xy 72.213207 -170.290506)
			(xy 72.267256 -170.324735) (xy 72.316583 -170.365474) (xy 72.360409 -170.412081) (xy 72.398042 -170.463818)
			(xy 72.428885 -170.519868) (xy 72.452452 -170.579345) (xy 72.468371 -170.641309) (xy 72.476389 -170.70478)
			(xy 72.476868 -170.736768) (xy 72.476868 -171.492418) (xy 90.183968 -171.492418) (xy 90.188039 -171.436796)
			(xy 90.200165 -171.382359) (xy 90.220088 -171.330268) (xy 90.247384 -171.281633) (xy 90.28147 -171.23749)
			(xy 90.321619 -171.198781) (xy 90.366977 -171.16633) (xy 90.416577 -171.140829) (xy 90.469361 -171.122822)
			(xy 90.524204 -171.112692) (xy 90.579938 -171.110655) (xy 90.635375 -171.116755) (xy 90.689332 -171.130861)
			(xy 90.740661 -171.152673) (xy 90.788267 -171.181727) (xy 90.831135 -171.217402) (xy 90.868352 -171.258939)
			(xy 90.899125 -171.305452) (xy 90.922797 -171.355949) (xy 90.938865 -171.409356) (xy 90.946985 -171.464532)
			(xy 90.947494 -171.492418) (xy 90.946985 -171.520304) (xy 90.938865 -171.57548) (xy 90.922797 -171.628887)
			(xy 90.899125 -171.679384) (xy 90.868352 -171.725897) (xy 90.831135 -171.767434) (xy 90.788267 -171.803109)
			(xy 90.740661 -171.832163) (xy 90.689332 -171.853975) (xy 90.635375 -171.868081) (xy 90.579938 -171.874181)
			(xy 90.524204 -171.872144) (xy 90.469361 -171.862014) (xy 90.416577 -171.844007) (xy 90.366977 -171.818506)
			(xy 90.321619 -171.786055) (xy 90.28147 -171.747346) (xy 90.247384 -171.703203) (xy 90.220088 -171.654568)
			(xy 90.200165 -171.602477) (xy 90.188039 -171.54804) (xy 90.183968 -171.492418) (xy 72.476868 -171.492418)
			(xy 72.476868 -171.735496) (xy 72.476374 -171.768232) (xy 72.467933 -171.833158) (xy 72.451228 -171.896463)
			(xy 72.426536 -171.957101) (xy 72.394265 -172.014068) (xy 72.375014 -172.04055) (xy 72.349868 -172.074332)
			(xy 72.349868 -172.091604) (xy 72.334374 -172.091604) (xy 72.29856 -172.12183) (xy 72.273383 -172.142683)
			(xy 72.218651 -172.178434) (xy 72.159786 -172.206873) (xy 72.097761 -172.227528) (xy 72.033599 -172.240059)
			(xy 71.96836 -172.244259) (xy 71.903121 -172.240059) (xy 71.838959 -172.227528) (xy 71.776934 -172.206873)
			(xy 71.718069 -172.178434) (xy 71.663337 -172.142683) (xy 71.63816 -172.12183) (xy 71.602346 -172.091604)
			(xy 71.586852 -172.091604) (xy 71.586852 -172.074332) (xy 71.561706 -172.04055) (xy 71.551062 -172.02612)
			(xy 71.531614 -171.995992) (xy 71.522844 -171.980352) (xy 71.51522 -171.967283) (xy 71.494882 -171.944894)
			(xy 71.469837 -171.927933) (xy 71.441499 -171.917358) (xy 71.411465 -171.913765) (xy 71.381431 -171.917358)
			(xy 71.353093 -171.927933) (xy 71.328048 -171.944894) (xy 71.30771 -171.967283) (xy 71.300086 -171.980352)
			(xy 71.291307 -171.995986) (xy 71.271857 -172.026113) (xy 71.261224 -172.04055) (xy 71.235824 -172.074332)
			(xy 71.235824 -172.091604) (xy 71.220584 -172.091604) (xy 71.18477 -172.12183) (xy 71.159593 -172.142683)
			(xy 71.104861 -172.178434) (xy 71.045996 -172.206873) (xy 70.983971 -172.227528) (xy 70.919809 -172.240059)
			(xy 70.85457 -172.244259) (xy 70.789331 -172.240059) (xy 70.725169 -172.227528) (xy 70.663144 -172.206873)
			(xy 70.604279 -172.178434) (xy 70.549547 -172.142683) (xy 70.52437 -172.12183) (xy 70.488556 -172.091604)
			(xy 70.473316 -172.091604) (xy 70.473316 -172.074332) (xy 70.447916 -172.04055) (xy 70.435477 -172.023662)
			(xy 70.413097 -171.988184) (xy 70.403212 -171.969684) (xy 70.39574 -171.956172) (xy 70.375385 -171.932966)
			(xy 70.350043 -171.915341) (xy 70.321204 -171.904334) (xy 70.290563 -171.900591) (xy 70.259922 -171.904334)
			(xy 70.231083 -171.915341) (xy 70.205741 -171.932966) (xy 70.185386 -171.956172) (xy 70.177914 -171.969684)
			(xy 70.168039 -171.988189) (xy 70.145659 -172.023669) (xy 70.13321 -172.04055) (xy 70.108064 -172.074332)
			(xy 70.108064 -172.091604) (xy 70.09257 -172.091604) (xy 70.056756 -172.12183) (xy 70.031579 -172.142683)
			(xy 69.976847 -172.178434) (xy 69.917982 -172.206873) (xy 69.855957 -172.227528) (xy 69.791795 -172.240059)
			(xy 69.726556 -172.244259) (xy 69.661317 -172.240059) (xy 69.597155 -172.227528) (xy 69.53513 -172.206873)
			(xy 69.476265 -172.178434) (xy 69.421533 -172.142683) (xy 69.396356 -172.12183) (xy 69.360542 -172.091604)
			(xy 69.345048 -172.091604) (xy 69.345048 -172.074332) (xy 69.319902 -172.04055) (xy 69.308648 -172.02523)
			(xy 69.288179 -171.993193) (xy 69.279008 -171.976542) (xy 69.271415 -171.963327) (xy 69.251054 -171.940659)
			(xy 69.225893 -171.923473) (xy 69.197372 -171.912752) (xy 69.167121 -171.909109) (xy 69.13687 -171.912752)
			(xy 69.108349 -171.923473) (xy 69.083188 -171.940659) (xy 69.062827 -171.963327) (xy 69.055234 -171.976542)
			(xy 69.046083 -171.993205) (xy 69.025611 -172.025241) (xy 69.01434 -172.04055) (xy 68.98894 -172.074332)
			(xy 68.98894 -172.091604) (xy 68.9737 -172.091604) (xy 68.937886 -172.12183) (xy 68.912709 -172.142683)
			(xy 68.857977 -172.178434) (xy 68.799112 -172.206873) (xy 68.737087 -172.227528) (xy 68.672925 -172.240059)
			(xy 68.607686 -172.244259) (xy 68.542447 -172.240059) (xy 68.478285 -172.227528) (xy 68.41626 -172.206873)
			(xy 68.357395 -172.178434) (xy 68.302663 -172.142683) (xy 68.277486 -172.12183) (xy 68.241672 -172.091604)
			(xy 68.226432 -172.091604) (xy 68.226432 -172.074332) (xy 68.201032 -172.04055) (xy 68.181811 -172.014056)
			(xy 68.149581 -171.957085) (xy 68.124939 -171.896445) (xy 68.108294 -171.833142) (xy 68.099922 -171.768224)
			(xy 68.099432 -171.735496) (xy 27.89936 -171.735496) (xy 27.89936 -172.312076) (xy 51.141376 -172.312076)
			(xy 52.793392 -172.312076) (xy 52.793392 -173.963584) (xy 51.141376 -173.963584) (xy 51.141376 -172.312076)
			(xy 27.89936 -172.312076) (xy 27.89936 -173.178385) (xy 47.641754 -173.178385) (xy 47.641754 -173.097275)
			(xy 47.649704 -173.016556) (xy 47.665527 -172.937005) (xy 47.689072 -172.859389) (xy 47.720111 -172.784453)
			(xy 47.758346 -172.712921) (xy 47.803408 -172.645481) (xy 47.854863 -172.582782) (xy 47.912216 -172.525429)
			(xy 47.974915 -172.473974) (xy 48.042355 -172.428912) (xy 48.113887 -172.390677) (xy 48.188823 -172.359638)
			(xy 48.266439 -172.336093) (xy 48.34599 -172.32027) (xy 48.426709 -172.31232) (xy 48.507819 -172.31232)
			(xy 48.588538 -172.32027) (xy 48.668089 -172.336093) (xy 48.745705 -172.359638) (xy 48.820641 -172.390677)
			(xy 48.892173 -172.428912) (xy 48.959613 -172.473974) (xy 49.022312 -172.525429) (xy 49.079665 -172.582782)
			(xy 49.13112 -172.645481) (xy 49.176182 -172.712921) (xy 49.214417 -172.784453) (xy 49.245456 -172.859389)
			(xy 49.269001 -172.937005) (xy 49.284824 -173.016556) (xy 49.292774 -173.097275) (xy 49.293272 -173.13783)
			(xy 49.292774 -173.178385) (xy 49.284824 -173.259104) (xy 49.269001 -173.338655) (xy 49.245456 -173.416271)
			(xy 49.214417 -173.491207) (xy 49.176182 -173.562739) (xy 49.13112 -173.630179) (xy 49.079665 -173.692878)
			(xy 49.022312 -173.750231) (xy 48.959613 -173.801686) (xy 48.892173 -173.846748) (xy 48.820641 -173.884983)
			(xy 48.745705 -173.916022) (xy 48.668089 -173.939567) (xy 48.588538 -173.95539) (xy 48.507819 -173.96334)
			(xy 48.426709 -173.96334) (xy 48.34599 -173.95539) (xy 48.266439 -173.939567) (xy 48.188823 -173.916022)
			(xy 48.113887 -173.884983) (xy 48.042355 -173.846748) (xy 47.974915 -173.801686) (xy 47.912216 -173.750231)
			(xy 47.854863 -173.692878) (xy 47.803408 -173.630179) (xy 47.758346 -173.562739) (xy 47.720111 -173.491207)
			(xy 47.689072 -173.416271) (xy 47.665527 -173.338655) (xy 47.649704 -173.259104) (xy 47.641754 -173.178385)
			(xy 27.89936 -173.178385) (xy 27.89936 -177.360072) (xy 27.901429 -177.375577) (xy 27.912102 -177.404973)
			(xy 27.929568 -177.430914) (xy 27.95279 -177.45186) (xy 27.980388 -177.466569) (xy 28.010724 -177.474166)
			(xy 28.02636 -177.474626) (xy 37.475668 -177.474626) (xy 39.50335 -179.502308) (xy 39.50335 -181.794912)
			(xy 39.51732 -181.794912) (xy 39.51732 -184.704228) (xy 39.818818 -184.704228) (xy 39.819523 -184.645605)
			(xy 39.828091 -184.528667) (xy 39.844787 -184.412611) (xy 39.86953 -184.298001) (xy 39.902199 -184.185393)
			(xy 39.942635 -184.075335) (xy 39.990642 -183.968363) (xy 40.045986 -183.864996) (xy 40.108399 -183.765737)
			(xy 40.177577 -183.671068) (xy 40.253183 -183.58145) (xy 40.334851 -183.497318) (xy 40.422182 -183.419081)
			(xy 40.514753 -183.34712) (xy 40.612113 -183.281784) (xy 40.713789 -183.223392) (xy 40.819288 -183.172226)
			(xy 40.928095 -183.128537) (xy 41.039682 -183.092535) (xy 41.153506 -183.064397) (xy 41.269014 -183.044259)
			(xy 41.385645 -183.032218) (xy 41.502832 -183.028334) (xy 41.620004 -183.032625) (xy 41.736593 -183.045071)
			(xy 41.85203 -183.065611) (xy 41.965756 -183.094144) (xy 42.077217 -183.130533) (xy 42.185872 -183.174601)
			(xy 42.291192 -183.226133) (xy 42.392665 -183.284878) (xy 42.489797 -183.350552) (xy 42.501941 -183.36006)
			(xy 43.327831 -183.36006) (xy 43.331866 -183.284356) (xy 43.343925 -183.209511) (xy 43.363871 -183.13637)
			(xy 43.391478 -183.065765) (xy 43.426434 -182.998494) (xy 43.468342 -182.935319) (xy 43.516728 -182.876957)
			(xy 43.571044 -182.824069) (xy 43.630673 -182.777254) (xy 43.694941 -182.737042) (xy 43.763118 -182.70389)
			(xy 43.834434 -182.678172) (xy 43.908079 -182.66018) (xy 43.983219 -182.650118) (xy 44.059003 -182.648099)
			(xy 44.134573 -182.654148) (xy 44.209071 -182.668195) (xy 44.281654 -182.690081) (xy 44.3515 -182.719558)
			(xy 44.417817 -182.756293) (xy 44.479853 -182.799868) (xy 44.536906 -182.84979) (xy 44.58833 -182.905494)
			(xy 44.633541 -182.966349) (xy 44.672028 -183.031664) (xy 44.703354 -183.1007) (xy 44.727164 -183.172675)
			(xy 44.743189 -183.246773) (xy 44.751248 -183.322154) (xy 44.751752 -183.36006) (xy 45.867831 -183.36006)
			(xy 45.871866 -183.284356) (xy 45.883925 -183.209511) (xy 45.903871 -183.13637) (xy 45.931478 -183.065765)
			(xy 45.966434 -182.998494) (xy 46.008342 -182.935319) (xy 46.056728 -182.876957) (xy 46.111044 -182.824069)
			(xy 46.170673 -182.777254) (xy 46.234941 -182.737042) (xy 46.303118 -182.70389) (xy 46.374434 -182.678172)
			(xy 46.448079 -182.66018) (xy 46.523219 -182.650118) (xy 46.599003 -182.648099) (xy 46.674573 -182.654148)
			(xy 46.749071 -182.668195) (xy 46.821654 -182.690081) (xy 46.8915 -182.719558) (xy 46.957817 -182.756293)
			(xy 47.019853 -182.799868) (xy 47.076906 -182.84979) (xy 47.12833 -182.905494) (xy 47.173541 -182.966349)
			(xy 47.212028 -183.031664) (xy 47.243354 -183.1007) (xy 47.267164 -183.172675) (xy 47.283189 -183.246773)
			(xy 47.291248 -183.322154) (xy 47.291752 -183.36006) (xy 48.407831 -183.36006) (xy 48.411866 -183.284356)
			(xy 48.423925 -183.209511) (xy 48.443871 -183.13637) (xy 48.471478 -183.065765) (xy 48.506434 -182.998494)
			(xy 48.548342 -182.935319) (xy 48.596728 -182.876957) (xy 48.651044 -182.824069) (xy 48.710673 -182.777254)
			(xy 48.774941 -182.737042) (xy 48.843118 -182.70389) (xy 48.914434 -182.678172) (xy 48.988079 -182.66018)
			(xy 49.063219 -182.650118) (xy 49.139003 -182.648099) (xy 49.214573 -182.654148) (xy 49.289071 -182.668195)
			(xy 49.361654 -182.690081) (xy 49.4315 -182.719558) (xy 49.497817 -182.756293) (xy 49.559853 -182.799868)
			(xy 49.616906 -182.84979) (xy 49.66833 -182.905494) (xy 49.713541 -182.966349) (xy 49.752028 -183.031664)
			(xy 49.783354 -183.1007) (xy 49.807164 -183.172675) (xy 49.823189 -183.246773) (xy 49.831248 -183.322154)
			(xy 49.831752 -183.36006) (xy 50.947831 -183.36006) (xy 50.951866 -183.284356) (xy 50.963925 -183.209511)
			(xy 50.983871 -183.13637) (xy 51.011478 -183.065765) (xy 51.046434 -182.998494) (xy 51.088342 -182.935319)
			(xy 51.136728 -182.876957) (xy 51.191044 -182.824069) (xy 51.250673 -182.777254) (xy 51.314941 -182.737042)
			(xy 51.383118 -182.70389) (xy 51.454434 -182.678172) (xy 51.528079 -182.66018) (xy 51.603219 -182.650118)
			(xy 51.679003 -182.648099) (xy 51.754573 -182.654148) (xy 51.829071 -182.668195) (xy 51.901654 -182.690081)
			(xy 51.9715 -182.719558) (xy 52.037817 -182.756293) (xy 52.099853 -182.799868) (xy 52.156906 -182.84979)
			(xy 52.20833 -182.905494) (xy 52.253541 -182.966349) (xy 52.292028 -183.031664) (xy 52.323354 -183.1007)
			(xy 52.347164 -183.172675) (xy 52.363189 -183.246773) (xy 52.371248 -183.322154) (xy 52.371752 -183.36006)
			(xy 53.487831 -183.36006) (xy 53.491866 -183.284356) (xy 53.503925 -183.209511) (xy 53.523871 -183.13637)
			(xy 53.551478 -183.065765) (xy 53.586434 -182.998494) (xy 53.628342 -182.935319) (xy 53.676728 -182.876957)
			(xy 53.731044 -182.824069) (xy 53.790673 -182.777254) (xy 53.854941 -182.737042) (xy 53.923118 -182.70389)
			(xy 53.994434 -182.678172) (xy 54.068079 -182.66018) (xy 54.143219 -182.650118) (xy 54.219003 -182.648099)
			(xy 54.294573 -182.654148) (xy 54.369071 -182.668195) (xy 54.441654 -182.690081) (xy 54.5115 -182.719558)
			(xy 54.577817 -182.756293) (xy 54.639853 -182.799868) (xy 54.696906 -182.84979) (xy 54.74833 -182.905494)
			(xy 54.793541 -182.966349) (xy 54.832028 -183.031664) (xy 54.863354 -183.1007) (xy 54.887164 -183.172675)
			(xy 54.903189 -183.246773) (xy 54.911248 -183.322154) (xy 54.911752 -183.36006) (xy 56.027831 -183.36006)
			(xy 56.031866 -183.284356) (xy 56.043925 -183.209511) (xy 56.063871 -183.13637) (xy 56.091478 -183.065765)
			(xy 56.126434 -182.998494) (xy 56.168342 -182.935319) (xy 56.216728 -182.876957) (xy 56.271044 -182.824069)
			(xy 56.330673 -182.777254) (xy 56.394941 -182.737042) (xy 56.463118 -182.70389) (xy 56.534434 -182.678172)
			(xy 56.608079 -182.66018) (xy 56.683219 -182.650118) (xy 56.759003 -182.648099) (xy 56.834573 -182.654148)
			(xy 56.909071 -182.668195) (xy 56.981654 -182.690081) (xy 57.0515 -182.719558) (xy 57.117817 -182.756293)
			(xy 57.179853 -182.799868) (xy 57.236906 -182.84979) (xy 57.28833 -182.905494) (xy 57.333541 -182.966349)
			(xy 57.372028 -183.031664) (xy 57.403354 -183.1007) (xy 57.427164 -183.172675) (xy 57.443189 -183.246773)
			(xy 57.451248 -183.322154) (xy 57.451752 -183.36006) (xy 58.567831 -183.36006) (xy 58.571866 -183.284356)
			(xy 58.583925 -183.209511) (xy 58.603871 -183.13637) (xy 58.631478 -183.065765) (xy 58.666434 -182.998494)
			(xy 58.708342 -182.935319) (xy 58.756728 -182.876957) (xy 58.811044 -182.824069) (xy 58.870673 -182.777254)
			(xy 58.934941 -182.737042) (xy 59.003118 -182.70389) (xy 59.074434 -182.678172) (xy 59.148079 -182.66018)
			(xy 59.223219 -182.650118) (xy 59.299003 -182.648099) (xy 59.374573 -182.654148) (xy 59.449071 -182.668195)
			(xy 59.521654 -182.690081) (xy 59.5915 -182.719558) (xy 59.657817 -182.756293) (xy 59.719853 -182.799868)
			(xy 59.776906 -182.84979) (xy 59.82833 -182.905494) (xy 59.873541 -182.966349) (xy 59.912028 -183.031664)
			(xy 59.943354 -183.1007) (xy 59.967164 -183.172675) (xy 59.983189 -183.246773) (xy 59.991248 -183.322154)
			(xy 59.991752 -183.36006) (xy 61.107831 -183.36006) (xy 61.111866 -183.284356) (xy 61.123925 -183.209511)
			(xy 61.143871 -183.13637) (xy 61.171478 -183.065765) (xy 61.206434 -182.998494) (xy 61.248342 -182.935319)
			(xy 61.296728 -182.876957) (xy 61.351044 -182.824069) (xy 61.410673 -182.777254) (xy 61.474941 -182.737042)
			(xy 61.543118 -182.70389) (xy 61.614434 -182.678172) (xy 61.688079 -182.66018) (xy 61.763219 -182.650118)
			(xy 61.839003 -182.648099) (xy 61.914573 -182.654148) (xy 61.989071 -182.668195) (xy 62.061654 -182.690081)
			(xy 62.1315 -182.719558) (xy 62.197817 -182.756293) (xy 62.259853 -182.799868) (xy 62.265798 -182.80507)
			(xy 86.197951 -182.80507) (xy 86.201986 -182.729366) (xy 86.214045 -182.654521) (xy 86.233991 -182.58138)
			(xy 86.261598 -182.510775) (xy 86.296554 -182.443504) (xy 86.338462 -182.380329) (xy 86.386848 -182.321967)
			(xy 86.441164 -182.269079) (xy 86.500793 -182.222264) (xy 86.565061 -182.182052) (xy 86.633238 -182.1489)
			(xy 86.704554 -182.123182) (xy 86.778199 -182.10519) (xy 86.853339 -182.095128) (xy 86.929123 -182.093109)
			(xy 87.004693 -182.099158) (xy 87.079191 -182.113205) (xy 87.151774 -182.135091) (xy 87.22162 -182.164568)
			(xy 87.287937 -182.201303) (xy 87.349973 -182.244878) (xy 87.407026 -182.2948) (xy 87.45845 -182.350504)
			(xy 87.503661 -182.411359) (xy 87.542148 -182.476674) (xy 87.573474 -182.54571) (xy 87.597284 -182.617685)
			(xy 87.613309 -182.691783) (xy 87.621368 -182.767164) (xy 87.621872 -182.80507) (xy 88.737951 -182.80507)
			(xy 88.741986 -182.729366) (xy 88.754045 -182.654521) (xy 88.773991 -182.58138) (xy 88.801598 -182.510775)
			(xy 88.836554 -182.443504) (xy 88.878462 -182.380329) (xy 88.926848 -182.321967) (xy 88.981164 -182.269079)
			(xy 89.040793 -182.222264) (xy 89.105061 -182.182052) (xy 89.173238 -182.1489) (xy 89.244554 -182.123182)
			(xy 89.318199 -182.10519) (xy 89.393339 -182.095128) (xy 89.469123 -182.093109) (xy 89.544693 -182.099158)
			(xy 89.619191 -182.113205) (xy 89.691774 -182.135091) (xy 89.76162 -182.164568) (xy 89.827937 -182.201303)
			(xy 89.889973 -182.244878) (xy 89.947026 -182.2948) (xy 89.99845 -182.350504) (xy 90.043661 -182.411359)
			(xy 90.082148 -182.476674) (xy 90.113474 -182.54571) (xy 90.137284 -182.617685) (xy 90.153309 -182.691783)
			(xy 90.161368 -182.767164) (xy 90.161872 -182.80507) (xy 91.277951 -182.80507) (xy 91.281986 -182.729366)
			(xy 91.294045 -182.654521) (xy 91.313991 -182.58138) (xy 91.341598 -182.510775) (xy 91.376554 -182.443504)
			(xy 91.418462 -182.380329) (xy 91.466848 -182.321967) (xy 91.521164 -182.269079) (xy 91.580793 -182.222264)
			(xy 91.645061 -182.182052) (xy 91.713238 -182.1489) (xy 91.784554 -182.123182) (xy 91.858199 -182.10519)
			(xy 91.933339 -182.095128) (xy 92.009123 -182.093109) (xy 92.084693 -182.099158) (xy 92.159191 -182.113205)
			(xy 92.231774 -182.135091) (xy 92.30162 -182.164568) (xy 92.367937 -182.201303) (xy 92.429973 -182.244878)
			(xy 92.487026 -182.2948) (xy 92.53845 -182.350504) (xy 92.583661 -182.411359) (xy 92.622148 -182.476674)
			(xy 92.653474 -182.54571) (xy 92.677284 -182.617685) (xy 92.693309 -182.691783) (xy 92.701368 -182.767164)
			(xy 92.701872 -182.80507) (xy 92.701368 -182.842976) (xy 92.693309 -182.918357) (xy 92.677284 -182.992455)
			(xy 92.653474 -183.06443) (xy 92.622148 -183.133466) (xy 92.583661 -183.198781) (xy 92.53845 -183.259636)
			(xy 92.487026 -183.31534) (xy 92.429973 -183.365262) (xy 92.367937 -183.408837) (xy 92.30162 -183.445572)
			(xy 92.231774 -183.475049) (xy 92.159191 -183.496935) (xy 92.084693 -183.510982) (xy 92.009123 -183.517031)
			(xy 91.933339 -183.515012) (xy 91.858199 -183.50495) (xy 91.784554 -183.486958) (xy 91.713238 -183.46124)
			(xy 91.645061 -183.428088) (xy 91.580793 -183.387876) (xy 91.521164 -183.341061) (xy 91.466848 -183.288173)
			(xy 91.418462 -183.229811) (xy 91.376554 -183.166636) (xy 91.341598 -183.099365) (xy 91.313991 -183.02876)
			(xy 91.294045 -182.955619) (xy 91.281986 -182.880774) (xy 91.277951 -182.80507) (xy 90.161872 -182.80507)
			(xy 90.161368 -182.842976) (xy 90.153309 -182.918357) (xy 90.137284 -182.992455) (xy 90.113474 -183.06443)
			(xy 90.082148 -183.133466) (xy 90.043661 -183.198781) (xy 89.99845 -183.259636) (xy 89.947026 -183.31534)
			(xy 89.889973 -183.365262) (xy 89.827937 -183.408837) (xy 89.76162 -183.445572) (xy 89.691774 -183.475049)
			(xy 89.619191 -183.496935) (xy 89.544693 -183.510982) (xy 89.469123 -183.517031) (xy 89.393339 -183.515012)
			(xy 89.318199 -183.50495) (xy 89.244554 -183.486958) (xy 89.173238 -183.46124) (xy 89.105061 -183.428088)
			(xy 89.040793 -183.387876) (xy 88.981164 -183.341061) (xy 88.926848 -183.288173) (xy 88.878462 -183.229811)
			(xy 88.836554 -183.166636) (xy 88.801598 -183.099365) (xy 88.773991 -183.02876) (xy 88.754045 -182.955619)
			(xy 88.741986 -182.880774) (xy 88.737951 -182.80507) (xy 87.621872 -182.80507) (xy 87.621368 -182.842976)
			(xy 87.613309 -182.918357) (xy 87.597284 -182.992455) (xy 87.573474 -183.06443) (xy 87.542148 -183.133466)
			(xy 87.503661 -183.198781) (xy 87.45845 -183.259636) (xy 87.407026 -183.31534) (xy 87.349973 -183.365262)
			(xy 87.287937 -183.408837) (xy 87.22162 -183.445572) (xy 87.151774 -183.475049) (xy 87.079191 -183.496935)
			(xy 87.004693 -183.510982) (xy 86.929123 -183.517031) (xy 86.853339 -183.515012) (xy 86.778199 -183.50495)
			(xy 86.704554 -183.486958) (xy 86.633238 -183.46124) (xy 86.565061 -183.428088) (xy 86.500793 -183.387876)
			(xy 86.441164 -183.341061) (xy 86.386848 -183.288173) (xy 86.338462 -183.229811) (xy 86.296554 -183.166636)
			(xy 86.261598 -183.099365) (xy 86.233991 -183.02876) (xy 86.214045 -182.955619) (xy 86.201986 -182.880774)
			(xy 86.197951 -182.80507) (xy 62.265798 -182.80507) (xy 62.316906 -182.84979) (xy 62.36833 -182.905494)
			(xy 62.413541 -182.966349) (xy 62.452028 -183.031664) (xy 62.483354 -183.1007) (xy 62.507164 -183.172675)
			(xy 62.523189 -183.246773) (xy 62.531248 -183.322154) (xy 62.531752 -183.36006) (xy 62.531248 -183.397966)
			(xy 62.523189 -183.473347) (xy 62.507164 -183.547445) (xy 62.483354 -183.61942) (xy 62.452028 -183.688456)
			(xy 62.413541 -183.753771) (xy 62.36833 -183.814626) (xy 62.316906 -183.87033) (xy 62.259853 -183.920252)
			(xy 62.197817 -183.963827) (xy 62.1315 -184.000562) (xy 62.061654 -184.030039) (xy 61.989071 -184.051925)
			(xy 61.914573 -184.065972) (xy 61.839003 -184.072021) (xy 61.763219 -184.070002) (xy 61.688079 -184.05994)
			(xy 61.614434 -184.041948) (xy 61.543118 -184.01623) (xy 61.474941 -183.983078) (xy 61.410673 -183.942866)
			(xy 61.351044 -183.896051) (xy 61.296728 -183.843163) (xy 61.248342 -183.784801) (xy 61.206434 -183.721626)
			(xy 61.171478 -183.654355) (xy 61.143871 -183.58375) (xy 61.123925 -183.510609) (xy 61.111866 -183.435764)
			(xy 61.107831 -183.36006) (xy 59.991752 -183.36006) (xy 59.991248 -183.397966) (xy 59.983189 -183.473347)
			(xy 59.967164 -183.547445) (xy 59.943354 -183.61942) (xy 59.912028 -183.688456) (xy 59.873541 -183.753771)
			(xy 59.82833 -183.814626) (xy 59.776906 -183.87033) (xy 59.719853 -183.920252) (xy 59.657817 -183.963827)
			(xy 59.5915 -184.000562) (xy 59.521654 -184.030039) (xy 59.449071 -184.051925) (xy 59.374573 -184.065972)
			(xy 59.299003 -184.072021) (xy 59.223219 -184.070002) (xy 59.148079 -184.05994) (xy 59.074434 -184.041948)
			(xy 59.003118 -184.01623) (xy 58.934941 -183.983078) (xy 58.870673 -183.942866) (xy 58.811044 -183.896051)
			(xy 58.756728 -183.843163) (xy 58.708342 -183.784801) (xy 58.666434 -183.721626) (xy 58.631478 -183.654355)
			(xy 58.603871 -183.58375) (xy 58.583925 -183.510609) (xy 58.571866 -183.435764) (xy 58.567831 -183.36006)
			(xy 57.451752 -183.36006) (xy 57.451248 -183.397966) (xy 57.443189 -183.473347) (xy 57.427164 -183.547445)
			(xy 57.403354 -183.61942) (xy 57.372028 -183.688456) (xy 57.333541 -183.753771) (xy 57.28833 -183.814626)
			(xy 57.236906 -183.87033) (xy 57.179853 -183.920252) (xy 57.117817 -183.963827) (xy 57.0515 -184.000562)
			(xy 56.981654 -184.030039) (xy 56.909071 -184.051925) (xy 56.834573 -184.065972) (xy 56.759003 -184.072021)
			(xy 56.683219 -184.070002) (xy 56.608079 -184.05994) (xy 56.534434 -184.041948) (xy 56.463118 -184.01623)
			(xy 56.394941 -183.983078) (xy 56.330673 -183.942866) (xy 56.271044 -183.896051) (xy 56.216728 -183.843163)
			(xy 56.168342 -183.784801) (xy 56.126434 -183.721626) (xy 56.091478 -183.654355) (xy 56.063871 -183.58375)
			(xy 56.043925 -183.510609) (xy 56.031866 -183.435764) (xy 56.027831 -183.36006) (xy 54.911752 -183.36006)
			(xy 54.911248 -183.397966) (xy 54.903189 -183.473347) (xy 54.887164 -183.547445) (xy 54.863354 -183.61942)
			(xy 54.832028 -183.688456) (xy 54.793541 -183.753771) (xy 54.74833 -183.814626) (xy 54.696906 -183.87033)
			(xy 54.639853 -183.920252) (xy 54.577817 -183.963827) (xy 54.5115 -184.000562) (xy 54.441654 -184.030039)
			(xy 54.369071 -184.051925) (xy 54.294573 -184.065972) (xy 54.219003 -184.072021) (xy 54.143219 -184.070002)
			(xy 54.068079 -184.05994) (xy 53.994434 -184.041948) (xy 53.923118 -184.01623) (xy 53.854941 -183.983078)
			(xy 53.790673 -183.942866) (xy 53.731044 -183.896051) (xy 53.676728 -183.843163) (xy 53.628342 -183.784801)
			(xy 53.586434 -183.721626) (xy 53.551478 -183.654355) (xy 53.523871 -183.58375) (xy 53.503925 -183.510609)
			(xy 53.491866 -183.435764) (xy 53.487831 -183.36006) (xy 52.371752 -183.36006) (xy 52.371248 -183.397966)
			(xy 52.363189 -183.473347) (xy 52.347164 -183.547445) (xy 52.323354 -183.61942) (xy 52.292028 -183.688456)
			(xy 52.253541 -183.753771) (xy 52.20833 -183.814626) (xy 52.156906 -183.87033) (xy 52.099853 -183.920252)
			(xy 52.037817 -183.963827) (xy 51.9715 -184.000562) (xy 51.901654 -184.030039) (xy 51.829071 -184.051925)
			(xy 51.754573 -184.065972) (xy 51.679003 -184.072021) (xy 51.603219 -184.070002) (xy 51.528079 -184.05994)
			(xy 51.454434 -184.041948) (xy 51.383118 -184.01623) (xy 51.314941 -183.983078) (xy 51.250673 -183.942866)
			(xy 51.191044 -183.896051) (xy 51.136728 -183.843163) (xy 51.088342 -183.784801) (xy 51.046434 -183.721626)
			(xy 51.011478 -183.654355) (xy 50.983871 -183.58375) (xy 50.963925 -183.510609) (xy 50.951866 -183.435764)
			(xy 50.947831 -183.36006) (xy 49.831752 -183.36006) (xy 49.831248 -183.397966) (xy 49.823189 -183.473347)
			(xy 49.807164 -183.547445) (xy 49.783354 -183.61942) (xy 49.752028 -183.688456) (xy 49.713541 -183.753771)
			(xy 49.66833 -183.814626) (xy 49.616906 -183.87033) (xy 49.559853 -183.920252) (xy 49.497817 -183.963827)
			(xy 49.4315 -184.000562) (xy 49.361654 -184.030039) (xy 49.289071 -184.051925) (xy 49.214573 -184.065972)
			(xy 49.139003 -184.072021) (xy 49.063219 -184.070002) (xy 48.988079 -184.05994) (xy 48.914434 -184.041948)
			(xy 48.843118 -184.01623) (xy 48.774941 -183.983078) (xy 48.710673 -183.942866) (xy 48.651044 -183.896051)
			(xy 48.596728 -183.843163) (xy 48.548342 -183.784801) (xy 48.506434 -183.721626) (xy 48.471478 -183.654355)
			(xy 48.443871 -183.58375) (xy 48.423925 -183.510609) (xy 48.411866 -183.435764) (xy 48.407831 -183.36006)
			(xy 47.291752 -183.36006) (xy 47.291248 -183.397966) (xy 47.283189 -183.473347) (xy 47.267164 -183.547445)
			(xy 47.243354 -183.61942) (xy 47.212028 -183.688456) (xy 47.173541 -183.753771) (xy 47.12833 -183.814626)
			(xy 47.076906 -183.87033) (xy 47.019853 -183.920252) (xy 46.957817 -183.963827) (xy 46.8915 -184.000562)
			(xy 46.821654 -184.030039) (xy 46.749071 -184.051925) (xy 46.674573 -184.065972) (xy 46.599003 -184.072021)
			(xy 46.523219 -184.070002) (xy 46.448079 -184.05994) (xy 46.374434 -184.041948) (xy 46.303118 -184.01623)
			(xy 46.234941 -183.983078) (xy 46.170673 -183.942866) (xy 46.111044 -183.896051) (xy 46.056728 -183.843163)
			(xy 46.008342 -183.784801) (xy 45.966434 -183.721626) (xy 45.931478 -183.654355) (xy 45.903871 -183.58375)
			(xy 45.883925 -183.510609) (xy 45.871866 -183.435764) (xy 45.867831 -183.36006) (xy 44.751752 -183.36006)
			(xy 44.751248 -183.397966) (xy 44.743189 -183.473347) (xy 44.727164 -183.547445) (xy 44.703354 -183.61942)
			(xy 44.672028 -183.688456) (xy 44.633541 -183.753771) (xy 44.58833 -183.814626) (xy 44.536906 -183.87033)
			(xy 44.479853 -183.920252) (xy 44.417817 -183.963827) (xy 44.3515 -184.000562) (xy 44.281654 -184.030039)
			(xy 44.209071 -184.051925) (xy 44.134573 -184.065972) (xy 44.059003 -184.072021) (xy 43.983219 -184.070002)
			(xy 43.908079 -184.05994) (xy 43.834434 -184.041948) (xy 43.763118 -184.01623) (xy 43.694941 -183.983078)
			(xy 43.630673 -183.942866) (xy 43.571044 -183.896051) (xy 43.516728 -183.843163) (xy 43.468342 -183.784801)
			(xy 43.426434 -183.721626) (xy 43.391478 -183.654355) (xy 43.363871 -183.58375) (xy 43.343925 -183.510609)
			(xy 43.331866 -183.435764) (xy 43.327831 -183.36006) (xy 42.501941 -183.36006) (xy 42.582117 -183.422834)
			(xy 42.669176 -183.501374) (xy 42.750551 -183.585789) (xy 42.825845 -183.675669) (xy 42.894694 -183.770578)
			(xy 42.956761 -183.870054) (xy 43.011746 -183.973612) (xy 43.056855 -184.07507) (xy 84.927951 -184.07507)
			(xy 84.931986 -183.999366) (xy 84.944045 -183.924521) (xy 84.963991 -183.85138) (xy 84.991598 -183.780775)
			(xy 85.026554 -183.713504) (xy 85.068462 -183.650329) (xy 85.116848 -183.591967) (xy 85.171164 -183.539079)
			(xy 85.230793 -183.492264) (xy 85.295061 -183.452052) (xy 85.363238 -183.4189) (xy 85.434554 -183.393182)
			(xy 85.508199 -183.37519) (xy 85.583339 -183.365128) (xy 85.659123 -183.363109) (xy 85.734693 -183.369158)
			(xy 85.809191 -183.383205) (xy 85.881774 -183.405091) (xy 85.95162 -183.434568) (xy 86.017937 -183.471303)
			(xy 86.079973 -183.514878) (xy 86.137026 -183.5648) (xy 86.18845 -183.620504) (xy 86.233661 -183.681359)
			(xy 86.272148 -183.746674) (xy 86.303474 -183.81571) (xy 86.327284 -183.887685) (xy 86.343309 -183.961783)
			(xy 86.351368 -184.037164) (xy 86.351872 -184.07507) (xy 87.467951 -184.07507) (xy 87.471986 -183.999366)
			(xy 87.484045 -183.924521) (xy 87.503991 -183.85138) (xy 87.531598 -183.780775) (xy 87.566554 -183.713504)
			(xy 87.608462 -183.650329) (xy 87.656848 -183.591967) (xy 87.711164 -183.539079) (xy 87.770793 -183.492264)
			(xy 87.835061 -183.452052) (xy 87.903238 -183.4189) (xy 87.974554 -183.393182) (xy 88.048199 -183.37519)
			(xy 88.123339 -183.365128) (xy 88.199123 -183.363109) (xy 88.274693 -183.369158) (xy 88.349191 -183.383205)
			(xy 88.421774 -183.405091) (xy 88.49162 -183.434568) (xy 88.557937 -183.471303) (xy 88.619973 -183.514878)
			(xy 88.677026 -183.5648) (xy 88.72845 -183.620504) (xy 88.773661 -183.681359) (xy 88.812148 -183.746674)
			(xy 88.843474 -183.81571) (xy 88.867284 -183.887685) (xy 88.883309 -183.961783) (xy 88.891368 -184.037164)
			(xy 88.891872 -184.07507) (xy 90.007951 -184.07507) (xy 90.011986 -183.999366) (xy 90.024045 -183.924521)
			(xy 90.043991 -183.85138) (xy 90.071598 -183.780775) (xy 90.106554 -183.713504) (xy 90.148462 -183.650329)
			(xy 90.196848 -183.591967) (xy 90.251164 -183.539079) (xy 90.310793 -183.492264) (xy 90.375061 -183.452052)
			(xy 90.443238 -183.4189) (xy 90.514554 -183.393182) (xy 90.588199 -183.37519) (xy 90.663339 -183.365128)
			(xy 90.739123 -183.363109) (xy 90.814693 -183.369158) (xy 90.889191 -183.383205) (xy 90.961774 -183.405091)
			(xy 91.03162 -183.434568) (xy 91.097937 -183.471303) (xy 91.159973 -183.514878) (xy 91.217026 -183.5648)
			(xy 91.26845 -183.620504) (xy 91.313661 -183.681359) (xy 91.352148 -183.746674) (xy 91.383474 -183.81571)
			(xy 91.407284 -183.887685) (xy 91.423309 -183.961783) (xy 91.431368 -184.037164) (xy 91.431872 -184.07507)
			(xy 91.431368 -184.112976) (xy 91.423309 -184.188357) (xy 91.407284 -184.262455) (xy 91.383474 -184.33443)
			(xy 91.352148 -184.403466) (xy 91.313661 -184.468781) (xy 91.26845 -184.529636) (xy 91.217026 -184.58534)
			(xy 91.159973 -184.635262) (xy 91.097937 -184.678837) (xy 91.03162 -184.715572) (xy 90.961774 -184.745049)
			(xy 90.889191 -184.766935) (xy 90.814693 -184.780982) (xy 90.739123 -184.787031) (xy 90.663339 -184.785012)
			(xy 90.588199 -184.77495) (xy 90.514554 -184.756958) (xy 90.443238 -184.73124) (xy 90.375061 -184.698088)
			(xy 90.310793 -184.657876) (xy 90.251164 -184.611061) (xy 90.196848 -184.558173) (xy 90.148462 -184.499811)
			(xy 90.106554 -184.436636) (xy 90.071598 -184.369365) (xy 90.043991 -184.29876) (xy 90.024045 -184.225619)
			(xy 90.011986 -184.150774) (xy 90.007951 -184.07507) (xy 88.891872 -184.07507) (xy 88.891368 -184.112976)
			(xy 88.883309 -184.188357) (xy 88.867284 -184.262455) (xy 88.843474 -184.33443) (xy 88.812148 -184.403466)
			(xy 88.773661 -184.468781) (xy 88.72845 -184.529636) (xy 88.677026 -184.58534) (xy 88.619973 -184.635262)
			(xy 88.557937 -184.678837) (xy 88.49162 -184.715572) (xy 88.421774 -184.745049) (xy 88.349191 -184.766935)
			(xy 88.274693 -184.780982) (xy 88.199123 -184.787031) (xy 88.123339 -184.785012) (xy 88.048199 -184.77495)
			(xy 87.974554 -184.756958) (xy 87.903238 -184.73124) (xy 87.835061 -184.698088) (xy 87.770793 -184.657876)
			(xy 87.711164 -184.611061) (xy 87.656848 -184.558173) (xy 87.608462 -184.499811) (xy 87.566554 -184.436636)
			(xy 87.531598 -184.369365) (xy 87.503991 -184.29876) (xy 87.484045 -184.225619) (xy 87.471986 -184.150774)
			(xy 87.467951 -184.07507) (xy 86.351872 -184.07507) (xy 86.351368 -184.112976) (xy 86.343309 -184.188357)
			(xy 86.327284 -184.262455) (xy 86.303474 -184.33443) (xy 86.272148 -184.403466) (xy 86.233661 -184.468781)
			(xy 86.18845 -184.529636) (xy 86.137026 -184.58534) (xy 86.079973 -184.635262) (xy 86.017937 -184.678837)
			(xy 85.95162 -184.715572) (xy 85.881774 -184.745049) (xy 85.809191 -184.766935) (xy 85.734693 -184.780982)
			(xy 85.659123 -184.787031) (xy 85.583339 -184.785012) (xy 85.508199 -184.77495) (xy 85.434554 -184.756958)
			(xy 85.363238 -184.73124) (xy 85.295061 -184.698088) (xy 85.230793 -184.657876) (xy 85.171164 -184.611061)
			(xy 85.116848 -184.558173) (xy 85.068462 -184.499811) (xy 85.026554 -184.436636) (xy 84.991598 -184.369365)
			(xy 84.963991 -184.29876) (xy 84.944045 -184.225619) (xy 84.931986 -184.150774) (xy 84.927951 -184.07507)
			(xy 43.056855 -184.07507) (xy 43.059381 -184.080751) (xy 43.099434 -184.190948) (xy 43.131712 -184.303669)
			(xy 43.156056 -184.418365) (xy 43.172348 -184.534478) (xy 43.18051 -184.651445) (xy 43.181016 -184.71007)
			(xy 43.180861 -184.740833) (xy 43.178574 -184.802316) (xy 43.176444 -184.833006) (xy 43.175682 -184.842404)
			(xy 43.170622 -184.900806) (xy 43.153396 -185.016771) (xy 43.12813 -185.131253) (xy 43.094949 -185.243697)
			(xy 43.057175 -185.34507) (xy 86.197951 -185.34507) (xy 86.201986 -185.269366) (xy 86.214045 -185.194521)
			(xy 86.233991 -185.12138) (xy 86.261598 -185.050775) (xy 86.296554 -184.983504) (xy 86.338462 -184.920329)
			(xy 86.386848 -184.861967) (xy 86.441164 -184.809079) (xy 86.500793 -184.762264) (xy 86.565061 -184.722052)
			(xy 86.633238 -184.6889) (xy 86.704554 -184.663182) (xy 86.778199 -184.64519) (xy 86.853339 -184.635128)
			(xy 86.929123 -184.633109) (xy 87.004693 -184.639158) (xy 87.079191 -184.653205) (xy 87.151774 -184.675091)
			(xy 87.22162 -184.704568) (xy 87.287937 -184.741303) (xy 87.349973 -184.784878) (xy 87.407026 -184.8348)
			(xy 87.45845 -184.890504) (xy 87.503661 -184.951359) (xy 87.542148 -185.016674) (xy 87.573474 -185.08571)
			(xy 87.597284 -185.157685) (xy 87.613309 -185.231783) (xy 87.621368 -185.307164) (xy 87.621872 -185.34507)
			(xy 88.737951 -185.34507) (xy 88.741986 -185.269366) (xy 88.754045 -185.194521) (xy 88.773991 -185.12138)
			(xy 88.801598 -185.050775) (xy 88.836554 -184.983504) (xy 88.878462 -184.920329) (xy 88.926848 -184.861967)
			(xy 88.981164 -184.809079) (xy 89.040793 -184.762264) (xy 89.105061 -184.722052) (xy 89.173238 -184.6889)
			(xy 89.244554 -184.663182) (xy 89.318199 -184.64519) (xy 89.393339 -184.635128) (xy 89.469123 -184.633109)
			(xy 89.544693 -184.639158) (xy 89.619191 -184.653205) (xy 89.691774 -184.675091) (xy 89.76162 -184.704568)
			(xy 89.827937 -184.741303) (xy 89.889973 -184.784878) (xy 89.947026 -184.8348) (xy 89.99845 -184.890504)
			(xy 90.043661 -184.951359) (xy 90.082148 -185.016674) (xy 90.113474 -185.08571) (xy 90.137284 -185.157685)
			(xy 90.153309 -185.231783) (xy 90.161368 -185.307164) (xy 90.161872 -185.34507) (xy 91.277951 -185.34507)
			(xy 91.281986 -185.269366) (xy 91.294045 -185.194521) (xy 91.313991 -185.12138) (xy 91.341598 -185.050775)
			(xy 91.376554 -184.983504) (xy 91.418462 -184.920329) (xy 91.466848 -184.861967) (xy 91.521164 -184.809079)
			(xy 91.580793 -184.762264) (xy 91.645061 -184.722052) (xy 91.713238 -184.6889) (xy 91.784554 -184.663182)
			(xy 91.858199 -184.64519) (xy 91.933339 -184.635128) (xy 92.009123 -184.633109) (xy 92.084693 -184.639158)
			(xy 92.159191 -184.653205) (xy 92.231774 -184.675091) (xy 92.30162 -184.704568) (xy 92.367937 -184.741303)
			(xy 92.429973 -184.784878) (xy 92.487026 -184.8348) (xy 92.53845 -184.890504) (xy 92.583661 -184.951359)
			(xy 92.622148 -185.016674) (xy 92.653474 -185.08571) (xy 92.677284 -185.157685) (xy 92.693309 -185.231783)
			(xy 92.701368 -185.307164) (xy 92.701872 -185.34507) (xy 92.701368 -185.382976) (xy 92.693309 -185.458357)
			(xy 92.677284 -185.532455) (xy 92.653474 -185.60443) (xy 92.622148 -185.673466) (xy 92.583661 -185.738781)
			(xy 92.53845 -185.799636) (xy 92.487026 -185.85534) (xy 92.429973 -185.905262) (xy 92.367937 -185.948837)
			(xy 92.30162 -185.985572) (xy 92.231774 -186.015049) (xy 92.159191 -186.036935) (xy 92.084693 -186.050982)
			(xy 92.009123 -186.057031) (xy 91.933339 -186.055012) (xy 91.858199 -186.04495) (xy 91.784554 -186.026958)
			(xy 91.713238 -186.00124) (xy 91.645061 -185.968088) (xy 91.580793 -185.927876) (xy 91.521164 -185.881061)
			(xy 91.466848 -185.828173) (xy 91.418462 -185.769811) (xy 91.376554 -185.706636) (xy 91.341598 -185.639365)
			(xy 91.313991 -185.56876) (xy 91.294045 -185.495619) (xy 91.281986 -185.420774) (xy 91.277951 -185.34507)
			(xy 90.161872 -185.34507) (xy 90.161368 -185.382976) (xy 90.153309 -185.458357) (xy 90.137284 -185.532455)
			(xy 90.113474 -185.60443) (xy 90.082148 -185.673466) (xy 90.043661 -185.738781) (xy 89.99845 -185.799636)
			(xy 89.947026 -185.85534) (xy 89.889973 -185.905262) (xy 89.827937 -185.948837) (xy 89.76162 -185.985572)
			(xy 89.691774 -186.015049) (xy 89.619191 -186.036935) (xy 89.544693 -186.050982) (xy 89.469123 -186.057031)
			(xy 89.393339 -186.055012) (xy 89.318199 -186.04495) (xy 89.244554 -186.026958) (xy 89.173238 -186.00124)
			(xy 89.105061 -185.968088) (xy 89.040793 -185.927876) (xy 88.981164 -185.881061) (xy 88.926848 -185.828173)
			(xy 88.878462 -185.769811) (xy 88.836554 -185.706636) (xy 88.801598 -185.639365) (xy 88.773991 -185.56876)
			(xy 88.754045 -185.495619) (xy 88.741986 -185.420774) (xy 88.737951 -185.34507) (xy 87.621872 -185.34507)
			(xy 87.621368 -185.382976) (xy 87.613309 -185.458357) (xy 87.597284 -185.532455) (xy 87.573474 -185.60443)
			(xy 87.542148 -185.673466) (xy 87.503661 -185.738781) (xy 87.45845 -185.799636) (xy 87.407026 -185.85534)
			(xy 87.349973 -185.905262) (xy 87.287937 -185.948837) (xy 87.22162 -185.985572) (xy 87.151774 -186.015049)
			(xy 87.079191 -186.036935) (xy 87.004693 -186.050982) (xy 86.929123 -186.057031) (xy 86.853339 -186.055012)
			(xy 86.778199 -186.04495) (xy 86.704554 -186.026958) (xy 86.633238 -186.00124) (xy 86.565061 -185.968088)
			(xy 86.500793 -185.927876) (xy 86.441164 -185.881061) (xy 86.386848 -185.828173) (xy 86.338462 -185.769811)
			(xy 86.296554 -185.706636) (xy 86.261598 -185.639365) (xy 86.233991 -185.56876) (xy 86.214045 -185.495619)
			(xy 86.201986 -185.420774) (xy 86.197951 -185.34507) (xy 43.057175 -185.34507) (xy 43.055945 -185.348372)
			(xy 43.328336 -185.348372) (xy 44.751752 -185.348372) (xy 44.751752 -186.06008) (xy 45.867831 -186.06008)
			(xy 45.871866 -185.984376) (xy 45.883925 -185.909531) (xy 45.903871 -185.83639) (xy 45.931478 -185.765785)
			(xy 45.966434 -185.698514) (xy 46.008342 -185.635339) (xy 46.056728 -185.576977) (xy 46.111044 -185.524089)
			(xy 46.170673 -185.477274) (xy 46.234941 -185.437062) (xy 46.303118 -185.40391) (xy 46.374434 -185.378192)
			(xy 46.448079 -185.3602) (xy 46.523219 -185.350138) (xy 46.599003 -185.348119) (xy 46.674573 -185.354168)
			(xy 46.749071 -185.368215) (xy 46.821654 -185.390101) (xy 46.8915 -185.419578) (xy 46.957817 -185.456313)
			(xy 47.019853 -185.499888) (xy 47.076906 -185.54981) (xy 47.12833 -185.605514) (xy 47.173541 -185.666369)
			(xy 47.212028 -185.731684) (xy 47.243354 -185.80072) (xy 47.267164 -185.872695) (xy 47.283189 -185.946793)
			(xy 47.291248 -186.022174) (xy 47.291752 -186.06008) (xy 48.407831 -186.06008) (xy 48.411866 -185.984376)
			(xy 48.423925 -185.909531) (xy 48.443871 -185.83639) (xy 48.471478 -185.765785) (xy 48.506434 -185.698514)
			(xy 48.548342 -185.635339) (xy 48.596728 -185.576977) (xy 48.651044 -185.524089) (xy 48.710673 -185.477274)
			(xy 48.774941 -185.437062) (xy 48.843118 -185.40391) (xy 48.914434 -185.378192) (xy 48.988079 -185.3602)
			(xy 49.063219 -185.350138) (xy 49.139003 -185.348119) (xy 49.214573 -185.354168) (xy 49.289071 -185.368215)
			(xy 49.361654 -185.390101) (xy 49.4315 -185.419578) (xy 49.497817 -185.456313) (xy 49.559853 -185.499888)
			(xy 49.616906 -185.54981) (xy 49.66833 -185.605514) (xy 49.713541 -185.666369) (xy 49.752028 -185.731684)
			(xy 49.783354 -185.80072) (xy 49.807164 -185.872695) (xy 49.823189 -185.946793) (xy 49.831248 -186.022174)
			(xy 49.831752 -186.06008) (xy 50.947831 -186.06008) (xy 50.951866 -185.984376) (xy 50.963925 -185.909531)
			(xy 50.983871 -185.83639) (xy 51.011478 -185.765785) (xy 51.046434 -185.698514) (xy 51.088342 -185.635339)
			(xy 51.136728 -185.576977) (xy 51.191044 -185.524089) (xy 51.250673 -185.477274) (xy 51.314941 -185.437062)
			(xy 51.383118 -185.40391) (xy 51.454434 -185.378192) (xy 51.528079 -185.3602) (xy 51.603219 -185.350138)
			(xy 51.679003 -185.348119) (xy 51.754573 -185.354168) (xy 51.829071 -185.368215) (xy 51.901654 -185.390101)
			(xy 51.9715 -185.419578) (xy 52.037817 -185.456313) (xy 52.099853 -185.499888) (xy 52.156906 -185.54981)
			(xy 52.20833 -185.605514) (xy 52.253541 -185.666369) (xy 52.292028 -185.731684) (xy 52.323354 -185.80072)
			(xy 52.347164 -185.872695) (xy 52.363189 -185.946793) (xy 52.371248 -186.022174) (xy 52.371752 -186.06008)
			(xy 53.487831 -186.06008) (xy 53.491866 -185.984376) (xy 53.503925 -185.909531) (xy 53.523871 -185.83639)
			(xy 53.551478 -185.765785) (xy 53.586434 -185.698514) (xy 53.628342 -185.635339) (xy 53.676728 -185.576977)
			(xy 53.731044 -185.524089) (xy 53.790673 -185.477274) (xy 53.854941 -185.437062) (xy 53.923118 -185.40391)
			(xy 53.994434 -185.378192) (xy 54.068079 -185.3602) (xy 54.143219 -185.350138) (xy 54.219003 -185.348119)
			(xy 54.294573 -185.354168) (xy 54.369071 -185.368215) (xy 54.441654 -185.390101) (xy 54.5115 -185.419578)
			(xy 54.577817 -185.456313) (xy 54.639853 -185.499888) (xy 54.696906 -185.54981) (xy 54.74833 -185.605514)
			(xy 54.793541 -185.666369) (xy 54.832028 -185.731684) (xy 54.863354 -185.80072) (xy 54.887164 -185.872695)
			(xy 54.903189 -185.946793) (xy 54.911248 -186.022174) (xy 54.911752 -186.06008) (xy 56.027831 -186.06008)
			(xy 56.031866 -185.984376) (xy 56.043925 -185.909531) (xy 56.063871 -185.83639) (xy 56.091478 -185.765785)
			(xy 56.126434 -185.698514) (xy 56.168342 -185.635339) (xy 56.216728 -185.576977) (xy 56.271044 -185.524089)
			(xy 56.330673 -185.477274) (xy 56.394941 -185.437062) (xy 56.463118 -185.40391) (xy 56.534434 -185.378192)
			(xy 56.608079 -185.3602) (xy 56.683219 -185.350138) (xy 56.759003 -185.348119) (xy 56.834573 -185.354168)
			(xy 56.909071 -185.368215) (xy 56.981654 -185.390101) (xy 57.0515 -185.419578) (xy 57.117817 -185.456313)
			(xy 57.179853 -185.499888) (xy 57.236906 -185.54981) (xy 57.28833 -185.605514) (xy 57.333541 -185.666369)
			(xy 57.372028 -185.731684) (xy 57.403354 -185.80072) (xy 57.427164 -185.872695) (xy 57.443189 -185.946793)
			(xy 57.451248 -186.022174) (xy 57.451752 -186.06008) (xy 58.567831 -186.06008) (xy 58.571866 -185.984376)
			(xy 58.583925 -185.909531) (xy 58.603871 -185.83639) (xy 58.631478 -185.765785) (xy 58.666434 -185.698514)
			(xy 58.708342 -185.635339) (xy 58.756728 -185.576977) (xy 58.811044 -185.524089) (xy 58.870673 -185.477274)
			(xy 58.934941 -185.437062) (xy 59.003118 -185.40391) (xy 59.074434 -185.378192) (xy 59.148079 -185.3602)
			(xy 59.223219 -185.350138) (xy 59.299003 -185.348119) (xy 59.374573 -185.354168) (xy 59.449071 -185.368215)
			(xy 59.521654 -185.390101) (xy 59.5915 -185.419578) (xy 59.657817 -185.456313) (xy 59.719853 -185.499888)
			(xy 59.776906 -185.54981) (xy 59.82833 -185.605514) (xy 59.873541 -185.666369) (xy 59.912028 -185.731684)
			(xy 59.943354 -185.80072) (xy 59.967164 -185.872695) (xy 59.983189 -185.946793) (xy 59.991248 -186.022174)
			(xy 59.991752 -186.06008) (xy 61.107831 -186.06008) (xy 61.111866 -185.984376) (xy 61.123925 -185.909531)
			(xy 61.143871 -185.83639) (xy 61.171478 -185.765785) (xy 61.206434 -185.698514) (xy 61.248342 -185.635339)
			(xy 61.296728 -185.576977) (xy 61.351044 -185.524089) (xy 61.410673 -185.477274) (xy 61.474941 -185.437062)
			(xy 61.543118 -185.40391) (xy 61.614434 -185.378192) (xy 61.688079 -185.3602) (xy 61.763219 -185.350138)
			(xy 61.839003 -185.348119) (xy 61.914573 -185.354168) (xy 61.989071 -185.368215) (xy 62.061654 -185.390101)
			(xy 62.1315 -185.419578) (xy 62.197817 -185.456313) (xy 62.259853 -185.499888) (xy 62.316906 -185.54981)
			(xy 62.36833 -185.605514) (xy 62.413541 -185.666369) (xy 62.452028 -185.731684) (xy 62.483354 -185.80072)
			(xy 62.507164 -185.872695) (xy 62.523189 -185.946793) (xy 62.531248 -186.022174) (xy 62.531752 -186.06008)
			(xy 62.531248 -186.097986) (xy 62.523189 -186.173367) (xy 62.507164 -186.247465) (xy 62.483354 -186.31944)
			(xy 62.452028 -186.388476) (xy 62.413541 -186.453791) (xy 62.36833 -186.514646) (xy 62.316906 -186.57035)
			(xy 62.265798 -186.61507) (xy 84.927951 -186.61507) (xy 84.931986 -186.539366) (xy 84.944045 -186.464521)
			(xy 84.963991 -186.39138) (xy 84.991598 -186.320775) (xy 85.026554 -186.253504) (xy 85.068462 -186.190329)
			(xy 85.116848 -186.131967) (xy 85.171164 -186.079079) (xy 85.230793 -186.032264) (xy 85.295061 -185.992052)
			(xy 85.363238 -185.9589) (xy 85.434554 -185.933182) (xy 85.508199 -185.91519) (xy 85.583339 -185.905128)
			(xy 85.659123 -185.903109) (xy 85.734693 -185.909158) (xy 85.809191 -185.923205) (xy 85.881774 -185.945091)
			(xy 85.95162 -185.974568) (xy 86.017937 -186.011303) (xy 86.079973 -186.054878) (xy 86.137026 -186.1048)
			(xy 86.18845 -186.160504) (xy 86.233661 -186.221359) (xy 86.272148 -186.286674) (xy 86.303474 -186.35571)
			(xy 86.327284 -186.427685) (xy 86.343309 -186.501783) (xy 86.351368 -186.577164) (xy 86.351872 -186.61507)
			(xy 87.467951 -186.61507) (xy 87.471986 -186.539366) (xy 87.484045 -186.464521) (xy 87.503991 -186.39138)
			(xy 87.531598 -186.320775) (xy 87.566554 -186.253504) (xy 87.608462 -186.190329) (xy 87.656848 -186.131967)
			(xy 87.711164 -186.079079) (xy 87.770793 -186.032264) (xy 87.835061 -185.992052) (xy 87.903238 -185.9589)
			(xy 87.974554 -185.933182) (xy 88.048199 -185.91519) (xy 88.123339 -185.905128) (xy 88.199123 -185.903109)
			(xy 88.274693 -185.909158) (xy 88.349191 -185.923205) (xy 88.421774 -185.945091) (xy 88.49162 -185.974568)
			(xy 88.557937 -186.011303) (xy 88.619973 -186.054878) (xy 88.677026 -186.1048) (xy 88.72845 -186.160504)
			(xy 88.773661 -186.221359) (xy 88.812148 -186.286674) (xy 88.843474 -186.35571) (xy 88.867284 -186.427685)
			(xy 88.883309 -186.501783) (xy 88.891368 -186.577164) (xy 88.891872 -186.61507) (xy 90.007951 -186.61507)
			(xy 90.011986 -186.539366) (xy 90.024045 -186.464521) (xy 90.043991 -186.39138) (xy 90.071598 -186.320775)
			(xy 90.106554 -186.253504) (xy 90.148462 -186.190329) (xy 90.196848 -186.131967) (xy 90.251164 -186.079079)
			(xy 90.310793 -186.032264) (xy 90.375061 -185.992052) (xy 90.443238 -185.9589) (xy 90.514554 -185.933182)
			(xy 90.588199 -185.91519) (xy 90.663339 -185.905128) (xy 90.739123 -185.903109) (xy 90.814693 -185.909158)
			(xy 90.889191 -185.923205) (xy 90.961774 -185.945091) (xy 91.03162 -185.974568) (xy 91.097937 -186.011303)
			(xy 91.159973 -186.054878) (xy 91.165918 -186.06008) (xy 93.15476 -186.06008) (xy 93.158776 -185.94381)
			(xy 93.170803 -185.828095) (xy 93.190785 -185.713485) (xy 93.218627 -185.600526) (xy 93.254196 -185.489758)
			(xy 93.297322 -185.381707) (xy 93.347799 -185.276889) (xy 93.405388 -185.175804) (xy 93.469814 -185.078932)
			(xy 93.540769 -184.986736) (xy 93.617916 -184.899655) (xy 93.700887 -184.818104) (xy 93.789287 -184.742472)
			(xy 93.882694 -184.673118) (xy 93.980663 -184.610375) (xy 94.082727 -184.554539) (xy 94.188401 -184.505878)
			(xy 94.29718 -184.464624) (xy 94.408545 -184.430973) (xy 94.521968 -184.405085) (xy 94.636905 -184.387084)
			(xy 94.752811 -184.377055) (xy 94.869133 -184.375047) (xy 94.985316 -184.381069) (xy 95.100807 -184.395092)
			(xy 95.215055 -184.41705) (xy 95.327516 -184.446837) (xy 95.437654 -184.484312) (xy 95.544944 -184.529297)
			(xy 95.648875 -184.581576) (xy 95.748951 -184.640901) (xy 95.844697 -184.706989) (xy 95.935654 -184.779525)
			(xy 96.02139 -184.858164) (xy 96.101497 -184.94253) (xy 96.175593 -185.032222) (xy 96.243323 -185.126812)
			(xy 96.304367 -185.22585) (xy 96.358432 -185.328863) (xy 96.405262 -185.43536) (xy 96.444633 -185.544835)
			(xy 96.476357 -185.656765) (xy 96.500283 -185.770617) (xy 96.516297 -185.885849) (xy 96.524324 -186.001911)
			(xy 96.524826 -186.06008) (xy 96.524324 -186.118249) (xy 96.516297 -186.234311) (xy 96.500283 -186.349543)
			(xy 96.476357 -186.463395) (xy 96.444633 -186.575325) (xy 96.405262 -186.6848) (xy 96.358432 -186.791297)
			(xy 96.304367 -186.89431) (xy 96.243323 -186.993348) (xy 96.175593 -187.087938) (xy 96.101497 -187.17763)
			(xy 96.02139 -187.261996) (xy 95.935654 -187.340635) (xy 95.844697 -187.413171) (xy 95.748951 -187.479259)
			(xy 95.648875 -187.538584) (xy 95.544944 -187.590863) (xy 95.437654 -187.635848) (xy 95.327516 -187.673323)
			(xy 95.215055 -187.70311) (xy 95.100807 -187.725068) (xy 94.985316 -187.739091) (xy 94.869133 -187.745113)
			(xy 94.752811 -187.743105) (xy 94.636905 -187.733076) (xy 94.521968 -187.715075) (xy 94.408545 -187.689187)
			(xy 94.29718 -187.655536) (xy 94.188401 -187.614282) (xy 94.082727 -187.565621) (xy 93.980663 -187.509785)
			(xy 93.882694 -187.447042) (xy 93.789287 -187.377688) (xy 93.700887 -187.302056) (xy 93.617916 -187.220505)
			(xy 93.540769 -187.133424) (xy 93.469814 -187.041228) (xy 93.405388 -186.944356) (xy 93.347799 -186.843271)
			(xy 93.297322 -186.738453) (xy 93.254196 -186.630402) (xy 93.218627 -186.519634) (xy 93.190785 -186.406675)
			(xy 93.170803 -186.292065) (xy 93.158776 -186.17635) (xy 93.15476 -186.06008) (xy 91.165918 -186.06008)
			(xy 91.217026 -186.1048) (xy 91.26845 -186.160504) (xy 91.313661 -186.221359) (xy 91.352148 -186.286674)
			(xy 91.383474 -186.35571) (xy 91.407284 -186.427685) (xy 91.423309 -186.501783) (xy 91.431368 -186.577164)
			(xy 91.431872 -186.61507) (xy 91.431368 -186.652976) (xy 91.423309 -186.728357) (xy 91.407284 -186.802455)
			(xy 91.383474 -186.87443) (xy 91.352148 -186.943466) (xy 91.313661 -187.008781) (xy 91.26845 -187.069636)
			(xy 91.217026 -187.12534) (xy 91.159973 -187.175262) (xy 91.097937 -187.218837) (xy 91.03162 -187.255572)
			(xy 90.961774 -187.285049) (xy 90.889191 -187.306935) (xy 90.814693 -187.320982) (xy 90.739123 -187.327031)
			(xy 90.663339 -187.325012) (xy 90.588199 -187.31495) (xy 90.514554 -187.296958) (xy 90.443238 -187.27124)
			(xy 90.375061 -187.238088) (xy 90.310793 -187.197876) (xy 90.251164 -187.151061) (xy 90.196848 -187.098173)
			(xy 90.148462 -187.039811) (xy 90.106554 -186.976636) (xy 90.071598 -186.909365) (xy 90.043991 -186.83876)
			(xy 90.024045 -186.765619) (xy 90.011986 -186.690774) (xy 90.007951 -186.61507) (xy 88.891872 -186.61507)
			(xy 88.891368 -186.652976) (xy 88.883309 -186.728357) (xy 88.867284 -186.802455) (xy 88.843474 -186.87443)
			(xy 88.812148 -186.943466) (xy 88.773661 -187.008781) (xy 88.72845 -187.069636) (xy 88.677026 -187.12534)
			(xy 88.619973 -187.175262) (xy 88.557937 -187.218837) (xy 88.49162 -187.255572) (xy 88.421774 -187.285049)
			(xy 88.349191 -187.306935) (xy 88.274693 -187.320982) (xy 88.199123 -187.327031) (xy 88.123339 -187.325012)
			(xy 88.048199 -187.31495) (xy 87.974554 -187.296958) (xy 87.903238 -187.27124) (xy 87.835061 -187.238088)
			(xy 87.770793 -187.197876) (xy 87.711164 -187.151061) (xy 87.656848 -187.098173) (xy 87.608462 -187.039811)
			(xy 87.566554 -186.976636) (xy 87.531598 -186.909365) (xy 87.503991 -186.83876) (xy 87.484045 -186.765619)
			(xy 87.471986 -186.690774) (xy 87.467951 -186.61507) (xy 86.351872 -186.61507) (xy 86.351368 -186.652976)
			(xy 86.343309 -186.728357) (xy 86.327284 -186.802455) (xy 86.303474 -186.87443) (xy 86.272148 -186.943466)
			(xy 86.233661 -187.008781) (xy 86.18845 -187.069636) (xy 86.137026 -187.12534) (xy 86.079973 -187.175262)
			(xy 86.017937 -187.218837) (xy 85.95162 -187.255572) (xy 85.881774 -187.285049) (xy 85.809191 -187.306935)
			(xy 85.734693 -187.320982) (xy 85.659123 -187.327031) (xy 85.583339 -187.325012) (xy 85.508199 -187.31495)
			(xy 85.434554 -187.296958) (xy 85.363238 -187.27124) (xy 85.295061 -187.238088) (xy 85.230793 -187.197876)
			(xy 85.171164 -187.151061) (xy 85.116848 -187.098173) (xy 85.068462 -187.039811) (xy 85.026554 -186.976636)
			(xy 84.991598 -186.909365) (xy 84.963991 -186.83876) (xy 84.944045 -186.765619) (xy 84.931986 -186.690774)
			(xy 84.927951 -186.61507) (xy 62.265798 -186.61507) (xy 62.259853 -186.620272) (xy 62.197817 -186.663847)
			(xy 62.1315 -186.700582) (xy 62.061654 -186.730059) (xy 61.989071 -186.751945) (xy 61.914573 -186.765992)
			(xy 61.839003 -186.772041) (xy 61.763219 -186.770022) (xy 61.688079 -186.75996) (xy 61.614434 -186.741968)
			(xy 61.543118 -186.71625) (xy 61.474941 -186.683098) (xy 61.410673 -186.642886) (xy 61.351044 -186.596071)
			(xy 61.296728 -186.543183) (xy 61.248342 -186.484821) (xy 61.206434 -186.421646) (xy 61.171478 -186.354375)
			(xy 61.143871 -186.28377) (xy 61.123925 -186.210629) (xy 61.111866 -186.135784) (xy 61.107831 -186.06008)
			(xy 59.991752 -186.06008) (xy 59.991248 -186.097986) (xy 59.983189 -186.173367) (xy 59.967164 -186.247465)
			(xy 59.943354 -186.31944) (xy 59.912028 -186.388476) (xy 59.873541 -186.453791) (xy 59.82833 -186.514646)
			(xy 59.776906 -186.57035) (xy 59.719853 -186.620272) (xy 59.657817 -186.663847) (xy 59.5915 -186.700582)
			(xy 59.521654 -186.730059) (xy 59.449071 -186.751945) (xy 59.374573 -186.765992) (xy 59.299003 -186.772041)
			(xy 59.223219 -186.770022) (xy 59.148079 -186.75996) (xy 59.074434 -186.741968) (xy 59.003118 -186.71625)
			(xy 58.934941 -186.683098) (xy 58.870673 -186.642886) (xy 58.811044 -186.596071) (xy 58.756728 -186.543183)
			(xy 58.708342 -186.484821) (xy 58.666434 -186.421646) (xy 58.631478 -186.354375) (xy 58.603871 -186.28377)
			(xy 58.583925 -186.210629) (xy 58.571866 -186.135784) (xy 58.567831 -186.06008) (xy 57.451752 -186.06008)
			(xy 57.451248 -186.097986) (xy 57.443189 -186.173367) (xy 57.427164 -186.247465) (xy 57.403354 -186.31944)
			(xy 57.372028 -186.388476) (xy 57.333541 -186.453791) (xy 57.28833 -186.514646) (xy 57.236906 -186.57035)
			(xy 57.179853 -186.620272) (xy 57.117817 -186.663847) (xy 57.0515 -186.700582) (xy 56.981654 -186.730059)
			(xy 56.909071 -186.751945) (xy 56.834573 -186.765992) (xy 56.759003 -186.772041) (xy 56.683219 -186.770022)
			(xy 56.608079 -186.75996) (xy 56.534434 -186.741968) (xy 56.463118 -186.71625) (xy 56.394941 -186.683098)
			(xy 56.330673 -186.642886) (xy 56.271044 -186.596071) (xy 56.216728 -186.543183) (xy 56.168342 -186.484821)
			(xy 56.126434 -186.421646) (xy 56.091478 -186.354375) (xy 56.063871 -186.28377) (xy 56.043925 -186.210629)
			(xy 56.031866 -186.135784) (xy 56.027831 -186.06008) (xy 54.911752 -186.06008) (xy 54.911248 -186.097986)
			(xy 54.903189 -186.173367) (xy 54.887164 -186.247465) (xy 54.863354 -186.31944) (xy 54.832028 -186.388476)
			(xy 54.793541 -186.453791) (xy 54.74833 -186.514646) (xy 54.696906 -186.57035) (xy 54.639853 -186.620272)
			(xy 54.577817 -186.663847) (xy 54.5115 -186.700582) (xy 54.441654 -186.730059) (xy 54.369071 -186.751945)
			(xy 54.294573 -186.765992) (xy 54.219003 -186.772041) (xy 54.143219 -186.770022) (xy 54.068079 -186.75996)
			(xy 53.994434 -186.741968) (xy 53.923118 -186.71625) (xy 53.854941 -186.683098) (xy 53.790673 -186.642886)
			(xy 53.731044 -186.596071) (xy 53.676728 -186.543183) (xy 53.628342 -186.484821) (xy 53.586434 -186.421646)
			(xy 53.551478 -186.354375) (xy 53.523871 -186.28377) (xy 53.503925 -186.210629) (xy 53.491866 -186.135784)
			(xy 53.487831 -186.06008) (xy 52.371752 -186.06008) (xy 52.371248 -186.097986) (xy 52.363189 -186.173367)
			(xy 52.347164 -186.247465) (xy 52.323354 -186.31944) (xy 52.292028 -186.388476) (xy 52.253541 -186.453791)
			(xy 52.20833 -186.514646) (xy 52.156906 -186.57035) (xy 52.099853 -186.620272) (xy 52.037817 -186.663847)
			(xy 51.9715 -186.700582) (xy 51.901654 -186.730059) (xy 51.829071 -186.751945) (xy 51.754573 -186.765992)
			(xy 51.679003 -186.772041) (xy 51.603219 -186.770022) (xy 51.528079 -186.75996) (xy 51.454434 -186.741968)
			(xy 51.383118 -186.71625) (xy 51.314941 -186.683098) (xy 51.250673 -186.642886) (xy 51.191044 -186.596071)
			(xy 51.136728 -186.543183) (xy 51.088342 -186.484821) (xy 51.046434 -186.421646) (xy 51.011478 -186.354375)
			(xy 50.983871 -186.28377) (xy 50.963925 -186.210629) (xy 50.951866 -186.135784) (xy 50.947831 -186.06008)
			(xy 49.831752 -186.06008) (xy 49.831248 -186.097986) (xy 49.823189 -186.173367) (xy 49.807164 -186.247465)
			(xy 49.783354 -186.31944) (xy 49.752028 -186.388476) (xy 49.713541 -186.453791) (xy 49.66833 -186.514646)
			(xy 49.616906 -186.57035) (xy 49.559853 -186.620272) (xy 49.497817 -186.663847) (xy 49.4315 -186.700582)
			(xy 49.361654 -186.730059) (xy 49.289071 -186.751945) (xy 49.214573 -186.765992) (xy 49.139003 -186.772041)
			(xy 49.063219 -186.770022) (xy 48.988079 -186.75996) (xy 48.914434 -186.741968) (xy 48.843118 -186.71625)
			(xy 48.774941 -186.683098) (xy 48.710673 -186.642886) (xy 48.651044 -186.596071) (xy 48.596728 -186.543183)
			(xy 48.548342 -186.484821) (xy 48.506434 -186.421646) (xy 48.471478 -186.354375) (xy 48.443871 -186.28377)
			(xy 48.423925 -186.210629) (xy 48.411866 -186.135784) (xy 48.407831 -186.06008) (xy 47.291752 -186.06008)
			(xy 47.291248 -186.097986) (xy 47.283189 -186.173367) (xy 47.267164 -186.247465) (xy 47.243354 -186.31944)
			(xy 47.212028 -186.388476) (xy 47.173541 -186.453791) (xy 47.12833 -186.514646) (xy 47.076906 -186.57035)
			(xy 47.019853 -186.620272) (xy 46.957817 -186.663847) (xy 46.8915 -186.700582) (xy 46.821654 -186.730059)
			(xy 46.749071 -186.751945) (xy 46.674573 -186.765992) (xy 46.599003 -186.772041) (xy 46.523219 -186.770022)
			(xy 46.448079 -186.75996) (xy 46.374434 -186.741968) (xy 46.303118 -186.71625) (xy 46.234941 -186.683098)
			(xy 46.170673 -186.642886) (xy 46.111044 -186.596071) (xy 46.056728 -186.543183) (xy 46.008342 -186.484821)
			(xy 45.966434 -186.421646) (xy 45.931478 -186.354375) (xy 45.903871 -186.28377) (xy 45.883925 -186.210629)
			(xy 45.871866 -186.135784) (xy 45.867831 -186.06008) (xy 44.751752 -186.06008) (xy 44.751752 -186.771788)
			(xy 43.328336 -186.771788) (xy 43.328336 -185.348372) (xy 43.055945 -185.348372) (xy 43.054014 -185.353555)
			(xy 43.005523 -185.460294) (xy 42.949712 -185.563395) (xy 42.886853 -185.662356) (xy 42.817252 -185.756696)
			(xy 42.741246 -185.845958) (xy 42.659204 -185.929706) (xy 42.571527 -186.007535) (xy 42.47864 -186.079064)
			(xy 42.380994 -186.143948) (xy 42.279065 -186.20187) (xy 42.173347 -186.252549) (xy 42.064355 -186.295738)
			(xy 41.952619 -186.331228) (xy 41.838681 -186.358845) (xy 41.723096 -186.378457) (xy 41.606425 -186.389967)
			(xy 41.489236 -186.393319) (xy 41.372098 -186.388497) (xy 41.25558 -186.375525) (xy 41.14025 -186.354466)
			(xy 41.026668 -186.325421) (xy 40.915385 -186.288533) (xy 40.806943 -186.24398) (xy 40.70187 -186.19198)
			(xy 40.600675 -186.132784) (xy 40.50385 -186.066681) (xy 40.411868 -185.993992) (xy 40.325173 -185.91507)
			(xy 40.244189 -185.830299) (xy 40.169308 -185.740091) (xy 40.100895 -185.644885) (xy 40.039282 -185.545143)
			(xy 39.984769 -185.441351) (xy 39.937621 -185.334012) (xy 39.898066 -185.223649) (xy 39.866298 -185.110798)
			(xy 39.842471 -184.996008) (xy 39.826699 -184.879836) (xy 39.819061 -184.762848) (xy 39.818818 -184.704228)
			(xy 39.51732 -184.704228) (xy 39.51732 -186.354974) (xy 39.517857 -186.371592) (xy 39.526446 -186.4037)
			(xy 39.543045 -186.432494) (xy 39.554404 -186.444636) (xy 42.980864 -189.870842) (xy 42.980864 -190.603632)
			(xy 43.494452 -191.11722) (xy 43.494452 -191.253618) (xy 83.836254 -191.253618) (xy 83.840325 -191.197996)
			(xy 83.852451 -191.143559) (xy 83.872374 -191.091468) (xy 83.89967 -191.042833) (xy 83.933756 -190.99869)
			(xy 83.973905 -190.959981) (xy 84.019263 -190.92753) (xy 84.068863 -190.902029) (xy 84.121647 -190.884022)
			(xy 84.17649 -190.873892) (xy 84.232224 -190.871855) (xy 84.287661 -190.877955) (xy 84.341618 -190.892061)
			(xy 84.392947 -190.913873) (xy 84.440553 -190.942927) (xy 84.483421 -190.978602) (xy 84.520638 -191.020139)
			(xy 84.551411 -191.066652) (xy 84.575083 -191.117149) (xy 84.591151 -191.170556) (xy 84.599271 -191.225732)
			(xy 84.599279 -191.226186) (xy 85.72703 -191.226186) (xy 85.731101 -191.170564) (xy 85.743227 -191.116127)
			(xy 85.76315 -191.064036) (xy 85.790446 -191.015401) (xy 85.824532 -190.971258) (xy 85.864681 -190.932549)
			(xy 85.910039 -190.900098) (xy 85.959639 -190.874597) (xy 86.012423 -190.85659) (xy 86.067266 -190.84646)
			(xy 86.123 -190.844423) (xy 86.178437 -190.850523) (xy 86.232394 -190.864629) (xy 86.283723 -190.886441)
			(xy 86.331329 -190.915495) (xy 86.374197 -190.95117) (xy 86.381648 -190.959486) (xy 87.021668 -190.959486)
			(xy 87.025739 -190.903864) (xy 87.037865 -190.849427) (xy 87.057788 -190.797336) (xy 87.085084 -190.748701)
			(xy 87.11917 -190.704558) (xy 87.159319 -190.665849) (xy 87.204677 -190.633398) (xy 87.254277 -190.607897)
			(xy 87.307061 -190.58989) (xy 87.361904 -190.57976) (xy 87.417638 -190.577723) (xy 87.473075 -190.583823)
			(xy 87.527032 -190.597929) (xy 87.578361 -190.619741) (xy 87.625967 -190.648795) (xy 87.668835 -190.68447)
			(xy 87.706052 -190.726007) (xy 87.736825 -190.77252) (xy 87.760497 -190.823017) (xy 87.776565 -190.876424)
			(xy 87.784685 -190.9316) (xy 87.785194 -190.959486) (xy 87.784685 -190.987372) (xy 87.776565 -191.042548)
			(xy 87.760497 -191.095955) (xy 87.736825 -191.146452) (xy 87.706052 -191.192965) (xy 87.693582 -191.206882)
			(xy 91.71254 -191.206882) (xy 91.716611 -191.15126) (xy 91.728737 -191.096823) (xy 91.74866 -191.044732)
			(xy 91.775956 -190.996097) (xy 91.810042 -190.951954) (xy 91.850191 -190.913245) (xy 91.895549 -190.880794)
			(xy 91.945149 -190.855293) (xy 91.997933 -190.837286) (xy 92.052776 -190.827156) (xy 92.10851 -190.825119)
			(xy 92.163947 -190.831219) (xy 92.217904 -190.845325) (xy 92.269233 -190.867137) (xy 92.316839 -190.896191)
			(xy 92.359707 -190.931866) (xy 92.396924 -190.973403) (xy 92.427697 -191.019916) (xy 92.451369 -191.070413)
			(xy 92.467437 -191.12382) (xy 92.475557 -191.178996) (xy 92.476066 -191.206882) (xy 92.475557 -191.234768)
			(xy 92.467437 -191.289944) (xy 92.451369 -191.343351) (xy 92.427697 -191.393848) (xy 92.396924 -191.440361)
			(xy 92.359707 -191.481898) (xy 92.316839 -191.517573) (xy 92.269233 -191.546627) (xy 92.217904 -191.568439)
			(xy 92.163947 -191.582545) (xy 92.10851 -191.588645) (xy 92.052776 -191.586608) (xy 91.997933 -191.576478)
			(xy 91.945149 -191.558471) (xy 91.895549 -191.53297) (xy 91.850191 -191.500519) (xy 91.810042 -191.46181)
			(xy 91.775956 -191.417667) (xy 91.74866 -191.369032) (xy 91.728737 -191.316941) (xy 91.716611 -191.262504)
			(xy 91.71254 -191.206882) (xy 87.693582 -191.206882) (xy 87.668835 -191.234502) (xy 87.625967 -191.270177)
			(xy 87.578361 -191.299231) (xy 87.527032 -191.321043) (xy 87.473075 -191.335149) (xy 87.417638 -191.341249)
			(xy 87.361904 -191.339212) (xy 87.307061 -191.329082) (xy 87.254277 -191.311075) (xy 87.204677 -191.285574)
			(xy 87.159319 -191.253123) (xy 87.11917 -191.214414) (xy 87.085084 -191.170271) (xy 87.057788 -191.121636)
			(xy 87.037865 -191.069545) (xy 87.025739 -191.015108) (xy 87.021668 -190.959486) (xy 86.381648 -190.959486)
			(xy 86.411414 -190.992707) (xy 86.442187 -191.03922) (xy 86.465859 -191.089717) (xy 86.481927 -191.143124)
			(xy 86.490047 -191.1983) (xy 86.490556 -191.226186) (xy 86.490047 -191.254072) (xy 86.481927 -191.309248)
			(xy 86.465859 -191.362655) (xy 86.442187 -191.413152) (xy 86.411414 -191.459665) (xy 86.374197 -191.501202)
			(xy 86.331329 -191.536877) (xy 86.283723 -191.565931) (xy 86.232394 -191.587743) (xy 86.178437 -191.601849)
			(xy 86.123 -191.607949) (xy 86.067266 -191.605912) (xy 86.012423 -191.595782) (xy 85.959639 -191.577775)
			(xy 85.910039 -191.552274) (xy 85.864681 -191.519823) (xy 85.824532 -191.481114) (xy 85.790446 -191.436971)
			(xy 85.76315 -191.388336) (xy 85.743227 -191.336245) (xy 85.731101 -191.281808) (xy 85.72703 -191.226186)
			(xy 84.599279 -191.226186) (xy 84.59978 -191.253618) (xy 84.599271 -191.281504) (xy 84.591151 -191.33668)
			(xy 84.575083 -191.390087) (xy 84.551411 -191.440584) (xy 84.520638 -191.487097) (xy 84.483421 -191.528634)
			(xy 84.440553 -191.564309) (xy 84.392947 -191.593363) (xy 84.341618 -191.615175) (xy 84.287661 -191.629281)
			(xy 84.232224 -191.635381) (xy 84.17649 -191.633344) (xy 84.121647 -191.623214) (xy 84.068863 -191.605207)
			(xy 84.019263 -191.579706) (xy 83.973905 -191.547255) (xy 83.933756 -191.508546) (xy 83.89967 -191.464403)
			(xy 83.872374 -191.415768) (xy 83.852451 -191.363677) (xy 83.840325 -191.30924) (xy 83.836254 -191.253618)
			(xy 43.494452 -191.253618) (xy 43.494452 -191.705992) (xy 95.288098 -191.705992) (xy 95.292169 -191.65037)
			(xy 95.304295 -191.595933) (xy 95.324218 -191.543842) (xy 95.351514 -191.495207) (xy 95.3856 -191.451064)
			(xy 95.425749 -191.412355) (xy 95.471107 -191.379904) (xy 95.520707 -191.354403) (xy 95.573491 -191.336396)
			(xy 95.628334 -191.326266) (xy 95.684068 -191.324229) (xy 95.739505 -191.330329) (xy 95.793462 -191.344435)
			(xy 95.844791 -191.366247) (xy 95.892397 -191.395301) (xy 95.935265 -191.430976) (xy 95.972482 -191.472513)
			(xy 96.003255 -191.519026) (xy 96.026927 -191.569523) (xy 96.042995 -191.62293) (xy 96.051115 -191.678106)
			(xy 96.051624 -191.705992) (xy 96.051115 -191.733878) (xy 96.042995 -191.789054) (xy 96.026927 -191.842461)
			(xy 96.003255 -191.892958) (xy 95.972482 -191.939471) (xy 95.935265 -191.981008) (xy 95.892397 -192.016683)
			(xy 95.844791 -192.045737) (xy 95.793462 -192.067549) (xy 95.739505 -192.081655) (xy 95.684068 -192.087755)
			(xy 95.628334 -192.085718) (xy 95.573491 -192.075588) (xy 95.520707 -192.057581) (xy 95.471107 -192.03208)
			(xy 95.425749 -191.999629) (xy 95.3856 -191.96092) (xy 95.351514 -191.916777) (xy 95.324218 -191.868142)
			(xy 95.304295 -191.816051) (xy 95.292169 -191.761614) (xy 95.288098 -191.705992) (xy 43.494452 -191.705992)
			(xy 43.494452 -192.53708) (xy 82.809078 -192.53708) (xy 82.813149 -192.481458) (xy 82.825275 -192.427021)
			(xy 82.845198 -192.37493) (xy 82.872494 -192.326295) (xy 82.90658 -192.282152) (xy 82.946729 -192.243443)
			(xy 82.992087 -192.210992) (xy 83.041687 -192.185491) (xy 83.094471 -192.167484) (xy 83.149314 -192.157354)
			(xy 83.205048 -192.155317) (xy 83.260485 -192.161417) (xy 83.314442 -192.175523) (xy 83.365771 -192.197335)
			(xy 83.413377 -192.226389) (xy 83.456245 -192.262064) (xy 83.493462 -192.303601) (xy 83.524235 -192.350114)
			(xy 83.547907 -192.400611) (xy 83.563975 -192.454018) (xy 83.572095 -192.509194) (xy 83.572604 -192.53708)
			(xy 83.572095 -192.564966) (xy 83.563975 -192.620142) (xy 83.547907 -192.673549) (xy 83.544249 -192.681352)
			(xy 84.456522 -192.681352) (xy 84.460593 -192.62573) (xy 84.472719 -192.571293) (xy 84.492642 -192.519202)
			(xy 84.519938 -192.470567) (xy 84.554024 -192.426424) (xy 84.594173 -192.387715) (xy 84.639531 -192.355264)
			(xy 84.689131 -192.329763) (xy 84.741915 -192.311756) (xy 84.796758 -192.301626) (xy 84.852492 -192.299589)
			(xy 84.907929 -192.305689) (xy 84.961886 -192.319795) (xy 85.013215 -192.341607) (xy 85.060821 -192.370661)
			(xy 85.103689 -192.406336) (xy 85.140906 -192.447873) (xy 85.171679 -192.494386) (xy 85.195351 -192.544883)
			(xy 85.211419 -192.59829) (xy 85.219539 -192.653466) (xy 85.220048 -192.681352) (xy 85.219539 -192.709238)
			(xy 85.211419 -192.764414) (xy 85.195351 -192.817821) (xy 85.171679 -192.868318) (xy 85.140906 -192.914831)
			(xy 85.103689 -192.956368) (xy 85.060821 -192.992043) (xy 85.013215 -193.021097) (xy 84.961886 -193.042909)
			(xy 84.907929 -193.057015) (xy 84.852492 -193.063115) (xy 84.796758 -193.061078) (xy 84.741915 -193.050948)
			(xy 84.689131 -193.032941) (xy 84.639531 -193.00744) (xy 84.594173 -192.974989) (xy 84.554024 -192.93628)
			(xy 84.519938 -192.892137) (xy 84.492642 -192.843502) (xy 84.472719 -192.791411) (xy 84.460593 -192.736974)
			(xy 84.456522 -192.681352) (xy 83.544249 -192.681352) (xy 83.524235 -192.724046) (xy 83.493462 -192.770559)
			(xy 83.456245 -192.812096) (xy 83.413377 -192.847771) (xy 83.365771 -192.876825) (xy 83.314442 -192.898637)
			(xy 83.260485 -192.912743) (xy 83.205048 -192.918843) (xy 83.149314 -192.916806) (xy 83.094471 -192.906676)
			(xy 83.041687 -192.888669) (xy 82.992087 -192.863168) (xy 82.946729 -192.830717) (xy 82.90658 -192.792008)
			(xy 82.872494 -192.747865) (xy 82.845198 -192.69923) (xy 82.825275 -192.647139) (xy 82.813149 -192.592702)
			(xy 82.809078 -192.53708) (xy 43.494452 -192.53708) (xy 43.494452 -193.724022) (xy 83.269326 -193.724022)
			(xy 83.273397 -193.6684) (xy 83.285523 -193.613963) (xy 83.305446 -193.561872) (xy 83.332742 -193.513237)
			(xy 83.366828 -193.469094) (xy 83.406977 -193.430385) (xy 83.452335 -193.397934) (xy 83.501935 -193.372433)
			(xy 83.554719 -193.354426) (xy 83.609562 -193.344296) (xy 83.665296 -193.342259) (xy 83.720733 -193.348359)
			(xy 83.77469 -193.362465) (xy 83.826019 -193.384277) (xy 83.873625 -193.413331) (xy 83.916493 -193.449006)
			(xy 83.95371 -193.490543) (xy 83.984483 -193.537056) (xy 84.008155 -193.587553) (xy 84.024223 -193.64096)
			(xy 84.032343 -193.696136) (xy 84.032852 -193.724022) (xy 84.032343 -193.751908) (xy 84.024223 -193.807084)
			(xy 84.008155 -193.860491) (xy 83.984483 -193.910988) (xy 83.95371 -193.957501) (xy 83.916493 -193.999038)
			(xy 83.873625 -194.034713) (xy 83.826019 -194.063767) (xy 83.77469 -194.085579) (xy 83.720733 -194.099685)
			(xy 83.665296 -194.105785) (xy 83.609562 -194.103748) (xy 83.554719 -194.093618) (xy 83.501935 -194.075611)
			(xy 83.452335 -194.05011) (xy 83.406977 -194.017659) (xy 83.366828 -193.97895) (xy 83.332742 -193.934807)
			(xy 83.305446 -193.886172) (xy 83.285523 -193.834081) (xy 83.273397 -193.779644) (xy 83.269326 -193.724022)
			(xy 43.494452 -193.724022) (xy 43.494452 -194.194938) (xy 43.494978 -194.211578) (xy 43.503655 -194.243709)
			(xy 43.520356 -194.272498) (xy 43.53179 -194.2846) (xy 43.73753 -194.49034) (xy 43.73753 -195.903596)
			(xy 51.402996 -195.903596) (xy 53.055012 -195.903596) (xy 53.055012 -197.555612) (xy 51.402996 -197.555612)
			(xy 51.402996 -195.903596) (xy 43.73753 -195.903596) (xy 43.73753 -196.064378) (xy 43.031749 -196.770159)
			(xy 47.903374 -196.770159) (xy 47.903374 -196.689049) (xy 47.911324 -196.60833) (xy 47.927147 -196.528779)
			(xy 47.950692 -196.451163) (xy 47.981731 -196.376227) (xy 48.019966 -196.304695) (xy 48.065028 -196.237255)
			(xy 48.116483 -196.174556) (xy 48.173836 -196.117203) (xy 48.236535 -196.065748) (xy 48.303975 -196.020686)
			(xy 48.375507 -195.982451) (xy 48.450443 -195.951412) (xy 48.528059 -195.927867) (xy 48.60761 -195.912044)
			(xy 48.688329 -195.904094) (xy 48.769439 -195.904094) (xy 48.850158 -195.912044) (xy 48.929709 -195.927867)
			(xy 49.007325 -195.951412) (xy 49.082261 -195.982451) (xy 49.153793 -196.020686) (xy 49.221233 -196.065748)
			(xy 49.283932 -196.117203) (xy 49.341285 -196.174556) (xy 49.39274 -196.237255) (xy 49.437802 -196.304695)
			(xy 49.476037 -196.376227) (xy 49.507076 -196.451163) (xy 49.530621 -196.528779) (xy 49.546444 -196.60833)
			(xy 49.554394 -196.689049) (xy 49.554892 -196.729604) (xy 49.554394 -196.770159) (xy 49.546444 -196.850878)
			(xy 49.530621 -196.930429) (xy 49.507076 -197.008045) (xy 49.476037 -197.082981) (xy 49.437802 -197.154513)
			(xy 49.39274 -197.221953) (xy 49.341285 -197.284652) (xy 49.283932 -197.342005) (xy 49.221233 -197.39346)
			(xy 49.153793 -197.438522) (xy 49.082261 -197.476757) (xy 49.007325 -197.507796) (xy 48.929709 -197.531341)
			(xy 48.850158 -197.547164) (xy 48.769439 -197.555114) (xy 48.688329 -197.555114) (xy 48.60761 -197.547164)
			(xy 48.528059 -197.531341) (xy 48.450443 -197.507796) (xy 48.375507 -197.476757) (xy 48.303975 -197.438522)
			(xy 48.236535 -197.39346) (xy 48.173836 -197.342005) (xy 48.116483 -197.284652) (xy 48.065028 -197.221953)
			(xy 48.019966 -197.154513) (xy 47.981731 -197.082981) (xy 47.950692 -197.008045) (xy 47.927147 -196.930429)
			(xy 47.911324 -196.850878) (xy 47.903374 -196.770159) (xy 43.031749 -196.770159) (xy 42.416984 -197.384924)
			(xy 42.416984 -199.635872) (xy 68.862448 -199.635872) (xy 68.862448 -198.637144) (xy 68.863141 -198.601078)
			(xy 68.873462 -198.529687) (xy 68.883022 -198.494904) (xy 68.887848 -198.477378) (xy 68.887848 -198.103236)
			(xy 69.854064 -198.103236) (xy 69.854064 -198.477378) (xy 69.85889 -198.494904) (xy 69.868427 -198.529692)
			(xy 69.878757 -198.60108) (xy 69.879464 -198.637144) (xy 69.879464 -198.791322) (xy 70.150228 -198.791322)
			(xy 70.150228 -197.792594) (xy 70.150771 -197.75986) (xy 70.159201 -197.694936) (xy 70.175894 -197.631631)
			(xy 70.200575 -197.570992) (xy 70.232836 -197.514024) (xy 70.252082 -197.48754) (xy 70.277228 -197.453758)
			(xy 70.277228 -197.43674) (xy 70.292722 -197.43674) (xy 70.328536 -197.40626) (xy 70.353713 -197.385407)
			(xy 70.408445 -197.349656) (xy 70.46731 -197.321217) (xy 70.529335 -197.300562) (xy 70.593497 -197.288031)
			(xy 70.658736 -197.283831) (xy 70.723975 -197.288031) (xy 70.788137 -197.300562) (xy 70.850162 -197.321217)
			(xy 70.909027 -197.349656) (xy 70.963759 -197.385407) (xy 70.988936 -197.40626) (xy 71.02475 -197.43674)
			(xy 71.040244 -197.43674) (xy 71.040244 -197.453758) (xy 71.06539 -197.48754) (xy 71.08156 -197.509724)
			(xy 71.109562 -197.556944) (xy 71.12127 -197.581774) (xy 71.128419 -197.59629) (xy 71.148807 -197.621404)
			(xy 71.174851 -197.640589) (xy 71.20488 -197.652616) (xy 71.236967 -197.656713) (xy 71.269054 -197.652616)
			(xy 71.299083 -197.640589) (xy 71.325127 -197.621404) (xy 71.345515 -197.59629) (xy 71.352664 -197.581774)
			(xy 71.364376 -197.556946) (xy 71.392376 -197.509725) (xy 71.408544 -197.48754) (xy 71.433944 -197.453758)
			(xy 71.433944 -197.43674) (xy 71.449184 -197.43674) (xy 71.484998 -197.40626) (xy 71.510175 -197.385407)
			(xy 71.564907 -197.349656) (xy 71.623772 -197.321217) (xy 71.685797 -197.300562) (xy 71.749959 -197.288031)
			(xy 71.815198 -197.283831) (xy 71.880437 -197.288031) (xy 71.944599 -197.300562) (xy 72.006624 -197.321217)
			(xy 72.065489 -197.349656) (xy 72.120221 -197.385407) (xy 72.145398 -197.40626) (xy 72.181212 -197.43674)
			(xy 72.196452 -197.43674) (xy 72.196452 -197.453758) (xy 72.221852 -197.48754) (xy 72.241066 -197.514039)
			(xy 72.273297 -197.571008) (xy 72.297941 -197.631647) (xy 72.314587 -197.694949) (xy 72.322961 -197.759866)
			(xy 72.323452 -197.792594) (xy 72.323452 -197.81012) (xy 86.39887 -197.81012) (xy 86.402874 -197.610022)
			(xy 86.414881 -197.410244) (xy 86.434872 -197.211107) (xy 86.462814 -197.012929) (xy 86.498662 -196.816027)
			(xy 86.54236 -196.620718) (xy 86.593837 -196.427313) (xy 86.653011 -196.236123) (xy 86.719787 -196.047453)
			(xy 86.794059 -195.861606) (xy 86.875706 -195.678879) (xy 86.964599 -195.499566) (xy 87.060595 -195.323952)
			(xy 87.16354 -195.15232) (xy 87.27327 -194.984944) (xy 87.389608 -194.822093) (xy 87.512369 -194.664026)
			(xy 87.641356 -194.510998) (xy 87.776363 -194.363253) (xy 87.917172 -194.221027) (xy 88.063559 -194.08455)
			(xy 88.215289 -193.954038) (xy 88.37212 -193.829702) (xy 88.533799 -193.71174) (xy 88.700069 -193.600341)
			(xy 88.870662 -193.495684) (xy 89.045306 -193.397936) (xy 89.223722 -193.307253) (xy 89.405622 -193.223782)
			(xy 89.590717 -193.147655) (xy 89.778709 -193.078995) (xy 89.969298 -193.017911) (xy 90.162178 -192.964501)
			(xy 90.35704 -192.918852) (xy 90.553573 -192.881035) (xy 90.751462 -192.851111) (xy 90.950389 -192.829129)
			(xy 91.150037 -192.815124) (xy 91.350085 -192.809118) (xy 91.550213 -192.81112) (xy 91.750101 -192.821128)
			(xy 91.949428 -192.839125) (xy 92.147876 -192.865083) (xy 92.345126 -192.89896) (xy 92.540863 -192.940702)
			(xy 92.734773 -192.990241) (xy 92.926546 -193.047499) (xy 93.115875 -193.112384) (xy 93.302455 -193.184792)
			(xy 93.48599 -193.264608) (xy 93.666184 -193.351702) (xy 93.842749 -193.445936) (xy 94.015402 -193.547159)
			(xy 94.183867 -193.655209) (xy 94.347875 -193.769912) (xy 94.507162 -193.891086) (xy 94.661473 -194.018535)
			(xy 94.810561 -194.152056) (xy 94.954188 -194.291436) (xy 95.092124 -194.43645) (xy 95.224147 -194.586867)
			(xy 95.350046 -194.742445) (xy 95.46962 -194.902937) (xy 95.534931 -194.99834) (xy 96.87255 -194.99834)
			(xy 96.876621 -194.942718) (xy 96.888747 -194.888281) (xy 96.90867 -194.83619) (xy 96.935966 -194.787555)
			(xy 96.970052 -194.743412) (xy 97.010201 -194.704703) (xy 97.055559 -194.672252) (xy 97.105159 -194.646751)
			(xy 97.157943 -194.628744) (xy 97.212786 -194.618614) (xy 97.26852 -194.616577) (xy 97.323957 -194.622677)
			(xy 97.377914 -194.636783) (xy 97.429243 -194.658595) (xy 97.476849 -194.687649) (xy 97.519717 -194.723324)
			(xy 97.556934 -194.764861) (xy 97.587707 -194.811374) (xy 97.611379 -194.861871) (xy 97.627447 -194.915278)
			(xy 97.635567 -194.970454) (xy 97.636076 -194.99834) (xy 97.635567 -195.026226) (xy 97.627447 -195.081402)
			(xy 97.611379 -195.134809) (xy 97.587707 -195.185306) (xy 97.556934 -195.231819) (xy 97.519717 -195.273356)
			(xy 97.476849 -195.309031) (xy 97.429243 -195.338085) (xy 97.377914 -195.359897) (xy 97.323957 -195.374003)
			(xy 97.26852 -195.380103) (xy 97.212786 -195.378066) (xy 97.157943 -195.367936) (xy 97.105159 -195.349929)
			(xy 97.055559 -195.324428) (xy 97.010201 -195.291977) (xy 96.970052 -195.253268) (xy 96.935966 -195.209125)
			(xy 96.90867 -195.16049) (xy 96.888747 -195.108399) (xy 96.876621 -195.053962) (xy 96.87255 -194.99834)
			(xy 95.534931 -194.99834) (xy 95.582676 -195.068083) (xy 95.689035 -195.237621) (xy 95.788526 -195.411279)
			(xy 95.880989 -195.588778) (xy 95.966276 -195.769834) (xy 96.044251 -195.954158) (xy 96.114788 -196.141454)
			(xy 96.177776 -196.331422) (xy 96.233113 -196.523758) (xy 96.271822 -196.681852) (xy 97.862642 -196.681852)
			(xy 97.866713 -196.62623) (xy 97.878839 -196.571793) (xy 97.898762 -196.519702) (xy 97.926058 -196.471067)
			(xy 97.960144 -196.426924) (xy 98.000293 -196.388215) (xy 98.045651 -196.355764) (xy 98.095251 -196.330263)
			(xy 98.148035 -196.312256) (xy 98.202878 -196.302126) (xy 98.258612 -196.300089) (xy 98.314049 -196.306189)
			(xy 98.368006 -196.320295) (xy 98.419335 -196.342107) (xy 98.466941 -196.371161) (xy 98.509809 -196.406836)
			(xy 98.547026 -196.448373) (xy 98.577799 -196.494886) (xy 98.601471 -196.545383) (xy 98.617539 -196.59879)
			(xy 98.625659 -196.653966) (xy 98.626168 -196.681852) (xy 98.625659 -196.709738) (xy 98.617539 -196.764914)
			(xy 98.601471 -196.818321) (xy 98.577799 -196.868818) (xy 98.547026 -196.915331) (xy 98.509809 -196.956868)
			(xy 98.466941 -196.992543) (xy 98.419335 -197.021597) (xy 98.368006 -197.043409) (xy 98.314049 -197.057515)
			(xy 98.258612 -197.063615) (xy 98.202878 -197.061578) (xy 98.148035 -197.051448) (xy 98.095251 -197.033441)
			(xy 98.045651 -197.00794) (xy 98.000293 -196.975489) (xy 97.960144 -196.93678) (xy 97.926058 -196.892637)
			(xy 97.898762 -196.844002) (xy 97.878839 -196.791911) (xy 97.866713 -196.737474) (xy 97.862642 -196.681852)
			(xy 96.271822 -196.681852) (xy 96.28071 -196.718154) (xy 96.320491 -196.914299) (xy 96.352393 -197.111878)
			(xy 96.376364 -197.310575) (xy 96.392366 -197.510073) (xy 96.400373 -197.710051) (xy 96.400874 -197.81012)
			(xy 96.400373 -197.910189) (xy 96.392366 -198.110167) (xy 96.376364 -198.309665) (xy 96.352393 -198.508362)
			(xy 96.320491 -198.705941) (xy 96.28071 -198.902086) (xy 96.233113 -199.096482) (xy 96.177776 -199.288818)
			(xy 96.114788 -199.478786) (xy 96.044251 -199.666082) (xy 95.966276 -199.850406) (xy 95.880989 -200.031462)
			(xy 95.788526 -200.208961) (xy 95.689035 -200.382619) (xy 95.582676 -200.552157) (xy 95.46962 -200.717303)
			(xy 95.350046 -200.877795) (xy 95.224147 -201.033373) (xy 95.092124 -201.18379) (xy 94.954188 -201.328804)
			(xy 94.810561 -201.468184) (xy 94.661473 -201.601705) (xy 94.507162 -201.729154) (xy 94.347875 -201.850328)
			(xy 94.183867 -201.965031) (xy 94.015402 -202.073081) (xy 93.842749 -202.174304) (xy 93.666184 -202.268538)
			(xy 93.48599 -202.355632) (xy 93.302455 -202.435448) (xy 93.115875 -202.507856) (xy 92.926546 -202.572741)
			(xy 92.734773 -202.629999) (xy 92.540863 -202.679538) (xy 92.345126 -202.72128) (xy 92.147876 -202.755157)
			(xy 91.949428 -202.781115) (xy 91.750101 -202.799112) (xy 91.550213 -202.80912) (xy 91.350085 -202.811122)
			(xy 91.150037 -202.805116) (xy 90.950389 -202.791111) (xy 90.751462 -202.769129) (xy 90.553573 -202.739205)
			(xy 90.35704 -202.701388) (xy 90.162178 -202.655739) (xy 89.969298 -202.602329) (xy 89.778709 -202.541245)
			(xy 89.590717 -202.472585) (xy 89.405622 -202.396458) (xy 89.223722 -202.312987) (xy 89.045306 -202.222304)
			(xy 88.870662 -202.124556) (xy 88.700069 -202.019899) (xy 88.533799 -201.9085) (xy 88.37212 -201.790538)
			(xy 88.215289 -201.666202) (xy 88.063559 -201.53569) (xy 87.917172 -201.399213) (xy 87.776363 -201.256987)
			(xy 87.641356 -201.109242) (xy 87.512369 -200.956214) (xy 87.389608 -200.798147) (xy 87.27327 -200.635296)
			(xy 87.16354 -200.46792) (xy 87.060595 -200.296288) (xy 86.964599 -200.120674) (xy 86.875706 -199.941361)
			(xy 86.794059 -199.758634) (xy 86.719787 -199.572787) (xy 86.653011 -199.384117) (xy 86.593837 -199.192927)
			(xy 86.54236 -198.999522) (xy 86.498662 -198.804213) (xy 86.462814 -198.607311) (xy 86.434872 -198.409133)
			(xy 86.414881 -198.209996) (xy 86.402874 -198.010218) (xy 86.39887 -197.81012) (xy 72.323452 -197.81012)
			(xy 72.323452 -198.791322) (xy 72.322938 -198.823863) (xy 72.314639 -198.888415) (xy 72.298168 -198.951379)
			(xy 72.273794 -199.011725) (xy 72.241915 -199.068466) (xy 72.203054 -199.120673) (xy 72.157846 -199.167492)
			(xy 72.107031 -199.208157) (xy 72.05144 -199.242002) (xy 71.991984 -199.268473) (xy 71.929635 -199.287138)
			(xy 71.865414 -199.297691) (xy 71.80037 -199.299958) (xy 71.73557 -199.293904) (xy 71.672072 -199.279627)
			(xy 71.610917 -199.257361) (xy 71.553104 -199.22747) (xy 71.49958 -199.190443) (xy 71.451221 -199.146887)
			(xy 71.429626 -199.122538) (xy 71.415024 -199.106226) (xy 71.381241 -199.078386) (xy 71.343185 -199.05675)
			(xy 71.301983 -199.041961) (xy 71.258855 -199.034455) (xy 71.215079 -199.034455) (xy 71.171951 -199.041961)
			(xy 71.130749 -199.05675) (xy 71.092693 -199.078386) (xy 71.05891 -199.106226) (xy 71.044308 -199.122538)
			(xy 71.022725 -199.14691) (xy 70.974358 -199.190488) (xy 70.920823 -199.227535) (xy 70.862997 -199.257443)
			(xy 70.801826 -199.279725) (xy 70.738311 -199.294014) (xy 70.673491 -199.300078) (xy 70.608427 -199.297816)
			(xy 70.544185 -199.287267) (xy 70.481815 -199.268602) (xy 70.422338 -199.242127) (xy 70.366728 -199.208276)
			(xy 70.315895 -199.167602) (xy 70.27067 -199.120771) (xy 70.231795 -199.06855) (xy 70.199904 -199.011792)
			(xy 70.175521 -198.951428) (xy 70.159043 -198.888445) (xy 70.150742 -198.823874) (xy 70.150228 -198.791322)
			(xy 69.879464 -198.791322) (xy 69.879464 -199.635872) (xy 69.878962 -199.667833) (xy 69.870951 -199.731251)
			(xy 69.855054 -199.793165) (xy 69.831522 -199.852598) (xy 69.800728 -199.908613) (xy 69.763155 -199.960328)
			(xy 69.719398 -200.006925) (xy 69.670145 -200.04767) (xy 69.616174 -200.081921) (xy 69.558335 -200.109138)
			(xy 69.497542 -200.128891) (xy 69.434752 -200.140869) (xy 69.370956 -200.144883) (xy 69.30716 -200.140869)
			(xy 69.24437 -200.128891) (xy 69.183577 -200.109138) (xy 69.125738 -200.081921) (xy 69.071767 -200.04767)
			(xy 69.022514 -200.006925) (xy 68.978757 -199.960328) (xy 68.941184 -199.908613) (xy 68.91039 -199.852598)
			(xy 68.886858 -199.793165) (xy 68.870961 -199.731251) (xy 68.86295 -199.667833) (xy 68.862448 -199.635872)
			(xy 42.416984 -199.635872) (xy 42.416984 -199.725534) (xy 41.67505 -200.467468) (xy 40.648128 -201.494644)
			(xy 38.167056 -201.494644) (xy 37.535104 -200.862692) (xy 36.560252 -200.862692) (xy 36.536869 -200.864701)
			(xy 36.491369 -200.876186) (xy 36.448747 -200.895821) (xy 36.41045 -200.922941) (xy 36.377778 -200.956626)
			(xy 36.351838 -200.995731) (xy 36.333511 -201.038932) (xy 36.323419 -201.084761) (xy 36.321904 -201.131663)
			(xy 36.329018 -201.178048) (xy 36.34452 -201.222341) (xy 36.355782 -201.24293) (xy 36.377055 -201.2811)
			(xy 36.413242 -201.360645) (xy 36.441891 -201.443205) (xy 36.462757 -201.528066) (xy 36.475659 -201.614498)
			(xy 36.480486 -201.701754) (xy 36.477196 -201.789081) (xy 36.465817 -201.875727) (xy 36.446449 -201.960943)
			(xy 36.419257 -202.043994) (xy 36.384477 -202.124164) (xy 36.342408 -202.200761) (xy 36.293414 -202.273125)
			(xy 36.237917 -202.34063) (xy 36.176396 -202.402695) (xy 36.109382 -202.458784) (xy 36.037452 -202.508413)
			(xy 35.961229 -202.551155) (xy 35.881368 -202.586639) (xy 35.798559 -202.614561) (xy 35.713517 -202.634679)
			(xy 35.626975 -202.64682) (xy 35.53968 -202.650878) (xy 35.452385 -202.64682) (xy 35.365843 -202.634679)
			(xy 35.280801 -202.614561) (xy 35.197992 -202.586639) (xy 35.118131 -202.551155) (xy 35.041908 -202.508413)
			(xy 34.969978 -202.458784) (xy 34.902964 -202.402695) (xy 34.841443 -202.34063) (xy 34.785946 -202.273125)
			(xy 34.736952 -202.200761) (xy 34.694883 -202.124164) (xy 34.660103 -202.043994) (xy 34.632911 -201.960943)
			(xy 34.613543 -201.875727) (xy 34.602164 -201.789081) (xy 34.598874 -201.701754) (xy 34.603701 -201.614498)
			(xy 34.616603 -201.528066) (xy 34.637469 -201.443205) (xy 34.666118 -201.360645) (xy 34.702305 -201.2811)
			(xy 34.723578 -201.24293) (xy 34.734785 -201.222313) (xy 34.750274 -201.178022) (xy 34.75738 -201.131643)
			(xy 34.755863 -201.084747) (xy 34.745774 -201.038924) (xy 34.727454 -200.995727) (xy 34.701526 -200.956622)
			(xy 34.668867 -200.922932) (xy 34.630586 -200.895802) (xy 34.587979 -200.87615) (xy 34.542492 -200.864642)
			(xy 34.519108 -200.862692) (xy 34.228532 -200.862692) (xy 33.966404 -200.600564) (xy 33.25876 -200.600564)
			(xy 31.738316 -202.121008) (xy 30.982666 -202.876912) (xy 29.667708 -202.876912) (xy 29.614876 -202.929744)
			(xy 29.614876 -203.212192) (xy 29.615344 -203.234304) (xy 29.622984 -203.277863) (xy 29.638052 -203.319442)
			(xy 29.660092 -203.357782) (xy 29.688439 -203.391727) (xy 29.722236 -203.420249) (xy 29.760462 -203.442488)
			(xy 29.801961 -203.457772) (xy 29.84548 -203.465638) (xy 29.889703 -203.465849) (xy 29.933295 -203.458398)
			(xy 29.974938 -203.443511) (xy 29.994352 -203.432918) (xy 30.032526 -203.411747) (xy 30.112061 -203.375762)
			(xy 30.194589 -203.347303) (xy 30.2794 -203.326616) (xy 30.365763 -203.31388) (xy 30.452935 -203.309203)
			(xy 30.540165 -203.312626) (xy 30.626703 -203.324119) (xy 30.711802 -203.343584) (xy 30.794731 -203.370853)
			(xy 30.874776 -203.405691) (xy 30.951246 -203.447798) (xy 31.023485 -203.496812) (xy 31.09087 -203.552311)
			(xy 31.15282 -203.613817) (xy 31.208804 -203.6808) (xy 31.258337 -203.752683) (xy 31.300995 -203.828848)
			(xy 31.336409 -203.90864) (xy 31.364275 -203.99137) (xy 31.384353 -204.076327) (xy 31.39647 -204.162779)
			(xy 31.400522 -204.249982) (xy 31.398502 -204.293486) (xy 34.599874 -204.293486) (xy 34.599874 -204.206586)
			(xy 34.607892 -204.120057) (xy 34.62386 -204.034637) (xy 34.647641 -203.951055) (xy 34.679033 -203.870023)
			(xy 34.717767 -203.792234) (xy 34.763514 -203.71835) (xy 34.815883 -203.649003) (xy 34.874427 -203.584783)
			(xy 34.938647 -203.526239) (xy 35.007994 -203.47387) (xy 35.081878 -203.428123) (xy 35.159667 -203.389389)
			(xy 35.240699 -203.357997) (xy 35.324281 -203.334216) (xy 35.409701 -203.318248) (xy 35.49623 -203.31023)
			(xy 35.58313 -203.31023) (xy 35.669659 -203.318248) (xy 35.755079 -203.334216) (xy 35.838661 -203.357997)
			(xy 35.919693 -203.389389) (xy 35.997482 -203.428123) (xy 36.071366 -203.47387) (xy 36.140713 -203.526239)
			(xy 36.204933 -203.584783) (xy 36.263477 -203.649003) (xy 36.315846 -203.71835) (xy 36.361593 -203.792234)
			(xy 36.400327 -203.870023) (xy 36.431719 -203.951055) (xy 36.4555 -204.034637) (xy 36.471468 -204.120057)
			(xy 36.479486 -204.206586) (xy 36.479988 -204.250036) (xy 36.479486 -204.293486) (xy 36.471468 -204.380015)
			(xy 36.4555 -204.465435) (xy 36.431719 -204.549017) (xy 36.400327 -204.630049) (xy 36.361593 -204.707838)
			(xy 36.315846 -204.781722) (xy 36.263477 -204.851069) (xy 36.204933 -204.915289) (xy 36.140713 -204.973833)
			(xy 36.071366 -205.026202) (xy 35.997482 -205.071949) (xy 35.919693 -205.110683) (xy 35.838661 -205.142075)
			(xy 35.755079 -205.165856) (xy 35.669659 -205.181824) (xy 35.58313 -205.189842) (xy 35.49623 -205.189842)
			(xy 35.409701 -205.181824) (xy 35.324281 -205.165856) (xy 35.240699 -205.142075) (xy 35.159667 -205.110683)
			(xy 35.081878 -205.071949) (xy 35.007994 -205.026202) (xy 34.938647 -204.973833) (xy 34.874427 -204.915289)
			(xy 34.815883 -204.851069) (xy 34.763514 -204.781722) (xy 34.717767 -204.707838) (xy 34.679033 -204.630049)
			(xy 34.647641 -204.549017) (xy 34.62386 -204.465435) (xy 34.607892 -204.380015) (xy 34.599874 -204.293486)
			(xy 31.398502 -204.293486) (xy 31.396473 -204.337185) (xy 31.384359 -204.423638) (xy 31.364285 -204.508596)
			(xy 31.336422 -204.591327) (xy 31.301011 -204.67112) (xy 31.258356 -204.747287) (xy 31.208825 -204.819172)
			(xy 31.152845 -204.886157) (xy 31.090896 -204.947665) (xy 31.023514 -205.003166) (xy 30.951277 -205.052183)
			(xy 30.874808 -205.094293) (xy 30.794764 -205.129134) (xy 30.711836 -205.156406) (xy 30.626738 -205.175875)
			(xy 30.540201 -205.187371) (xy 30.452971 -205.190798) (xy 30.365799 -205.186124) (xy 30.279435 -205.17339)
			(xy 30.194624 -205.152707) (xy 30.112094 -205.124251) (xy 30.032558 -205.088269) (xy 29.994352 -205.067154)
			(xy 29.974901 -205.056653) (xy 29.93327 -205.0418) (xy 29.889698 -205.034376) (xy 29.845499 -205.034603)
			(xy 29.802005 -205.042474) (xy 29.76053 -205.057753) (xy 29.722324 -205.079978) (xy 29.68854 -205.108478)
			(xy 29.660197 -205.142395) (xy 29.63815 -205.180704) (xy 29.623065 -205.22225) (xy 29.615396 -205.26578)
			(xy 29.614876 -205.28788) (xy 29.614876 -205.752192) (xy 29.615344 -205.774304) (xy 29.622984 -205.817863)
			(xy 29.638052 -205.859442) (xy 29.660092 -205.897782) (xy 29.688439 -205.931727) (xy 29.722236 -205.960249)
			(xy 29.760462 -205.982488) (xy 29.801961 -205.997772) (xy 29.84548 -206.005638) (xy 29.889703 -206.005849)
			(xy 29.933295 -205.998398) (xy 29.974938 -205.983511) (xy 29.994352 -205.972918) (xy 30.032526 -205.951747)
			(xy 30.112061 -205.915762) (xy 30.194589 -205.887303) (xy 30.2794 -205.866616) (xy 30.365763 -205.85388)
			(xy 30.452935 -205.849203) (xy 30.540165 -205.852626) (xy 30.626703 -205.864119) (xy 30.711802 -205.883584)
			(xy 30.794731 -205.910853) (xy 30.874776 -205.945691) (xy 30.951246 -205.987798) (xy 31.023485 -206.036812)
			(xy 31.09087 -206.092311) (xy 31.15282 -206.153817) (xy 31.208804 -206.2208) (xy 31.258337 -206.292683)
			(xy 31.300995 -206.368848) (xy 31.336409 -206.44864) (xy 31.364275 -206.53137) (xy 31.384353 -206.616327)
			(xy 31.39647 -206.702779) (xy 31.400522 -206.789982) (xy 31.398502 -206.833486) (xy 34.599874 -206.833486)
			(xy 34.599874 -206.746586) (xy 34.607892 -206.660057) (xy 34.62386 -206.574637) (xy 34.647641 -206.491055)
			(xy 34.679033 -206.410023) (xy 34.717767 -206.332234) (xy 34.763514 -206.25835) (xy 34.815883 -206.189003)
			(xy 34.874427 -206.124783) (xy 34.938647 -206.066239) (xy 35.007994 -206.01387) (xy 35.081878 -205.968123)
			(xy 35.159667 -205.929389) (xy 35.240699 -205.897997) (xy 35.324281 -205.874216) (xy 35.409701 -205.858248)
			(xy 35.49623 -205.85023) (xy 35.58313 -205.85023) (xy 35.669659 -205.858248) (xy 35.755079 -205.874216)
			(xy 35.838661 -205.897997) (xy 35.919693 -205.929389) (xy 35.997482 -205.968123) (xy 36.071366 -206.01387)
			(xy 36.140713 -206.066239) (xy 36.204933 -206.124783) (xy 36.263477 -206.189003) (xy 36.315846 -206.25835)
			(xy 36.35924 -206.328433) (xy 64.461877 -206.328433) (xy 64.461877 -206.265167) (xy 64.470135 -206.202443)
			(xy 64.486509 -206.141333) (xy 64.51072 -206.082884) (xy 64.542352 -206.028094) (xy 64.580866 -205.977902)
			(xy 64.625601 -205.933167) (xy 64.675793 -205.894653) (xy 64.730582 -205.863021) (xy 64.789032 -205.83881)
			(xy 64.850141 -205.822435) (xy 64.912865 -205.814177) (xy 64.944498 -205.81366) (xy 66.26733 -205.81366)
			(xy 66.275712 -205.812644) (xy 66.304515 -205.80915) (xy 66.362531 -205.808276) (xy 66.420235 -205.814353)
			(xy 66.476796 -205.827295) (xy 66.531401 -205.846914) (xy 66.583265 -205.872929) (xy 66.60769 -205.88859)
			(xy 66.639694 -205.909672) (xy 66.842386 -205.909672) (xy 66.87439 -205.88859) (xy 66.898176 -205.873307)
			(xy 66.94861 -205.847753) (xy 67.001684 -205.828268) (xy 67.056673 -205.81512) (xy 67.112821 -205.808488)
			(xy 67.14109 -205.808072) (xy 68.792344 -205.808072) (xy 68.93941 -205.955138) (xy 68.961488 -205.977869)
			(xy 69.000036 -206.028167) (xy 69.031678 -206.083073) (xy 69.05587 -206.141644) (xy 69.072196 -206.202875)
			(xy 69.080377 -206.265715) (xy 69.080272 -206.329085) (xy 69.071883 -206.391898) (xy 69.055353 -206.453075)
			(xy 69.030967 -206.511565) (xy 68.999144 -206.566366) (xy 68.960429 -206.616535) (xy 68.915487 -206.661212)
			(xy 68.86509 -206.69963) (xy 68.810103 -206.73113) (xy 68.751469 -206.755169) (xy 68.690196 -206.771337)
			(xy 68.627335 -206.779355) (xy 68.563965 -206.779086) (xy 68.532502 -206.775304) (xy 68.52412 -206.774288)
			(xy 67.14109 -206.774288) (xy 67.112823 -206.77385) (xy 67.05668 -206.7672) (xy 67.001695 -206.75405)
			(xy 66.948618 -206.734579) (xy 66.898174 -206.709053) (xy 66.87439 -206.69377) (xy 66.842386 -206.672688)
			(xy 66.695066 -206.672688) (xy 66.678385 -206.673217) (xy 66.646165 -206.681868) (xy 66.617285 -206.69857)
			(xy 66.60515 -206.710026) (xy 66.535554 -206.779876) (xy 64.944498 -206.779876) (xy 64.912865 -206.779423)
			(xy 64.850141 -206.771165) (xy 64.789032 -206.75479) (xy 64.730582 -206.730579) (xy 64.675793 -206.698947)
			(xy 64.625601 -206.660433) (xy 64.580866 -206.615698) (xy 64.542352 -206.565506) (xy 64.51072 -206.510716)
			(xy 64.486509 -206.452267) (xy 64.470135 -206.391157) (xy 64.461877 -206.328433) (xy 36.35924 -206.328433)
			(xy 36.361593 -206.332234) (xy 36.400327 -206.410023) (xy 36.431719 -206.491055) (xy 36.4555 -206.574637)
			(xy 36.471468 -206.660057) (xy 36.479486 -206.746586) (xy 36.479988 -206.790036) (xy 36.479486 -206.833486)
			(xy 36.471468 -206.920015) (xy 36.4555 -207.005435) (xy 36.431719 -207.089017) (xy 36.400327 -207.170049)
			(xy 36.361593 -207.247838) (xy 36.315846 -207.321722) (xy 36.263477 -207.391069) (xy 36.204933 -207.455289)
			(xy 36.140713 -207.513833) (xy 36.071366 -207.566202) (xy 35.997482 -207.611949) (xy 35.919693 -207.650683)
			(xy 35.838661 -207.682075) (xy 35.755079 -207.705856) (xy 35.669659 -207.721824) (xy 35.58313 -207.729842)
			(xy 35.49623 -207.729842) (xy 35.409701 -207.721824) (xy 35.324281 -207.705856) (xy 35.240699 -207.682075)
			(xy 35.159667 -207.650683) (xy 35.081878 -207.611949) (xy 35.007994 -207.566202) (xy 34.938647 -207.513833)
			(xy 34.874427 -207.455289) (xy 34.815883 -207.391069) (xy 34.763514 -207.321722) (xy 34.717767 -207.247838)
			(xy 34.679033 -207.170049) (xy 34.647641 -207.089017) (xy 34.62386 -207.005435) (xy 34.607892 -206.920015)
			(xy 34.599874 -206.833486) (xy 31.398502 -206.833486) (xy 31.396473 -206.877185) (xy 31.384359 -206.963638)
			(xy 31.364285 -207.048596) (xy 31.336422 -207.131327) (xy 31.301011 -207.21112) (xy 31.258356 -207.287287)
			(xy 31.208825 -207.359172) (xy 31.152845 -207.426157) (xy 31.090896 -207.487665) (xy 31.023514 -207.543166)
			(xy 30.951277 -207.592183) (xy 30.874808 -207.634293) (xy 30.794764 -207.669134) (xy 30.711836 -207.696406)
			(xy 30.626738 -207.715875) (xy 30.540201 -207.727371) (xy 30.452971 -207.730798) (xy 30.365799 -207.726124)
			(xy 30.279435 -207.71339) (xy 30.194624 -207.692707) (xy 30.112094 -207.664251) (xy 30.032558 -207.628269)
			(xy 29.994352 -207.607154) (xy 29.974901 -207.596653) (xy 29.93327 -207.5818) (xy 29.889698 -207.574376)
			(xy 29.845499 -207.574603) (xy 29.802005 -207.582474) (xy 29.76053 -207.597753) (xy 29.722324 -207.619978)
			(xy 29.68854 -207.648478) (xy 29.660197 -207.682395) (xy 29.63815 -207.720704) (xy 29.623065 -207.76225)
			(xy 29.615396 -207.80578) (xy 29.614876 -207.82788) (xy 29.614876 -208.292192) (xy 29.615344 -208.314304)
			(xy 29.622984 -208.357863) (xy 29.638052 -208.399442) (xy 29.660092 -208.437782) (xy 29.688439 -208.471727)
			(xy 29.722236 -208.500249) (xy 29.760462 -208.522488) (xy 29.801961 -208.537772) (xy 29.84548 -208.545638)
			(xy 29.889703 -208.545849) (xy 29.933295 -208.538398) (xy 29.974938 -208.523511) (xy 29.994352 -208.512918)
			(xy 30.032526 -208.491747) (xy 30.112061 -208.455762) (xy 30.194589 -208.427303) (xy 30.2794 -208.406616)
			(xy 30.365763 -208.39388) (xy 30.452935 -208.389203) (xy 30.540165 -208.392626) (xy 30.626703 -208.404119)
			(xy 30.711802 -208.423584) (xy 30.794731 -208.450853) (xy 30.874776 -208.485691) (xy 30.951246 -208.527798)
			(xy 31.023485 -208.576812) (xy 31.09087 -208.632311) (xy 31.15282 -208.693817) (xy 31.208804 -208.7608)
			(xy 31.258337 -208.832683) (xy 31.300995 -208.908848) (xy 31.336409 -208.98864) (xy 31.364275 -209.07137)
			(xy 31.384353 -209.156327) (xy 31.39647 -209.242779) (xy 31.400522 -209.329982) (xy 31.398502 -209.373486)
			(xy 34.599874 -209.373486) (xy 34.599874 -209.286586) (xy 34.607892 -209.200057) (xy 34.62386 -209.114637)
			(xy 34.647641 -209.031055) (xy 34.679033 -208.950023) (xy 34.717767 -208.872234) (xy 34.763514 -208.79835)
			(xy 34.815883 -208.729003) (xy 34.874427 -208.664783) (xy 34.938647 -208.606239) (xy 35.007994 -208.55387)
			(xy 35.081878 -208.508123) (xy 35.159667 -208.469389) (xy 35.240699 -208.437997) (xy 35.324281 -208.414216)
			(xy 35.409701 -208.398248) (xy 35.49623 -208.39023) (xy 35.58313 -208.39023) (xy 35.669659 -208.398248)
			(xy 35.755079 -208.414216) (xy 35.838661 -208.437997) (xy 35.919693 -208.469389) (xy 35.997482 -208.508123)
			(xy 36.071366 -208.55387) (xy 36.140713 -208.606239) (xy 36.204933 -208.664783) (xy 36.263477 -208.729003)
			(xy 36.315846 -208.79835) (xy 36.361593 -208.872234) (xy 36.400327 -208.950023) (xy 36.408868 -208.97207)
			(xy 39.100938 -208.97207) (xy 39.104829 -208.917724) (xy 39.116415 -208.864486) (xy 39.13546 -208.813438)
			(xy 39.161576 -208.76562) (xy 39.194232 -208.722006) (xy 39.232762 -208.683483) (xy 39.276383 -208.650836)
			(xy 39.324206 -208.624729) (xy 39.375257 -208.605694) (xy 39.428498 -208.594119) (xy 39.482844 -208.590238)
			(xy 39.53719 -208.594131) (xy 39.590428 -208.605719) (xy 39.641475 -208.624766) (xy 39.689292 -208.650884)
			(xy 39.711376 -208.666842) (xy 39.730388 -208.680438) (xy 39.772271 -208.70117) (xy 39.817239 -208.713896)
			(xy 39.863776 -208.718186) (xy 39.910313 -208.713896) (xy 39.955281 -208.70117) (xy 39.997164 -208.680438)
			(xy 40.016176 -208.666842) (xy 40.038218 -208.650813) (xy 40.086048 -208.624682) (xy 40.13711 -208.605624)
			(xy 40.190365 -208.594028) (xy 40.244728 -208.590129) (xy 40.299093 -208.594007) (xy 40.352352 -208.605584)
			(xy 40.403422 -208.624622) (xy 40.451261 -208.650735) (xy 40.494898 -208.683391) (xy 40.533442 -208.721925)
			(xy 40.56611 -208.765553) (xy 40.592236 -208.813386) (xy 40.611288 -208.86445) (xy 40.622878 -208.917706)
			(xy 40.626771 -208.97207) (xy 40.987631 -208.97207) (xy 40.991522 -208.917723) (xy 41.003109 -208.864482)
			(xy 41.022154 -208.813433) (xy 41.048271 -208.765614) (xy 41.080928 -208.721999) (xy 41.11946 -208.683475)
			(xy 41.163082 -208.650828) (xy 41.210907 -208.624721) (xy 41.26196 -208.605686) (xy 41.315203 -208.594111)
			(xy 41.369551 -208.590231) (xy 41.423898 -208.594125) (xy 41.477138 -208.605715) (xy 41.528186 -208.624763)
			(xy 41.576004 -208.650883) (xy 41.598088 -208.666842) (xy 41.6171 -208.680438) (xy 41.658983 -208.70117)
			(xy 41.703951 -208.713896) (xy 41.750488 -208.718186) (xy 41.797025 -208.713896) (xy 41.841993 -208.70117)
			(xy 41.883876 -208.680438) (xy 41.902888 -208.666842) (xy 41.92493 -208.650814) (xy 41.972759 -208.624684)
			(xy 42.02382 -208.605629) (xy 42.077074 -208.594034) (xy 42.131435 -208.590136) (xy 42.185798 -208.594015)
			(xy 42.239055 -208.605592) (xy 42.290123 -208.624631) (xy 42.337961 -208.650743) (xy 42.381596 -208.683399)
			(xy 42.420139 -208.721932) (xy 42.452805 -208.765559) (xy 42.47893 -208.813391) (xy 42.497981 -208.864453)
			(xy 42.509571 -208.917708) (xy 42.513464 -208.97207) (xy 43.228606 -208.97207) (xy 43.232498 -208.917717)
			(xy 43.244086 -208.864471) (xy 43.263134 -208.813417) (xy 43.289255 -208.765593) (xy 43.321916 -208.721974)
			(xy 43.360454 -208.683448) (xy 43.404082 -208.650798) (xy 43.451912 -208.62469) (xy 43.502972 -208.605656)
			(xy 43.556221 -208.594083) (xy 43.610575 -208.590206) (xy 43.664928 -208.594104) (xy 43.718172 -208.605698)
			(xy 43.769224 -208.624753) (xy 43.817045 -208.650879) (xy 43.83913 -208.666842) (xy 43.858142 -208.680438)
			(xy 43.900025 -208.70117) (xy 43.944993 -208.713896) (xy 43.99153 -208.718186) (xy 44.038067 -208.713896)
			(xy 44.083035 -208.70117) (xy 44.124918 -208.680438) (xy 44.14393 -208.666842) (xy 44.165971 -208.650817)
			(xy 44.213797 -208.624695) (xy 44.264854 -208.605645) (xy 44.318103 -208.594055) (xy 44.372459 -208.590161)
			(xy 44.426816 -208.594043) (xy 44.480067 -208.605622) (xy 44.531128 -208.624661) (xy 44.57896 -208.650773)
			(xy 44.622589 -208.683427) (xy 44.661127 -208.721957) (xy 44.693789 -208.76558) (xy 44.71991 -208.813407)
			(xy 44.738958 -208.864465) (xy 44.750547 -208.917714) (xy 44.754439 -208.97207) (xy 45.132615 -208.97207)
			(xy 45.136507 -208.917719) (xy 45.148094 -208.864476) (xy 45.167142 -208.813423) (xy 45.193261 -208.765601)
			(xy 45.225921 -208.721984) (xy 45.264456 -208.683458) (xy 45.308082 -208.650809) (xy 45.35591 -208.624702)
			(xy 45.406968 -208.605667) (xy 45.460214 -208.594093) (xy 45.514566 -208.590215) (xy 45.568916 -208.594112)
			(xy 45.622159 -208.605705) (xy 45.67321 -208.624757) (xy 45.721029 -208.650881) (xy 45.743114 -208.666842)
			(xy 45.762126 -208.680438) (xy 45.804009 -208.70117) (xy 45.848977 -208.713896) (xy 45.895514 -208.718186)
			(xy 45.942051 -208.713896) (xy 45.987019 -208.70117) (xy 46.028902 -208.680438) (xy 46.047914 -208.666842)
			(xy 46.069955 -208.650816) (xy 46.117782 -208.624691) (xy 46.168841 -208.605639) (xy 46.222092 -208.594047)
			(xy 46.27645 -208.590152) (xy 46.330809 -208.594033) (xy 46.384063 -208.60561) (xy 46.435126 -208.624649)
			(xy 46.482961 -208.650762) (xy 46.526592 -208.683416) (xy 46.565132 -208.721948) (xy 46.597795 -208.765572)
			(xy 46.623918 -208.813401) (xy 46.642967 -208.86446) (xy 46.654556 -208.917712) (xy 46.658448 -208.97207)
			(xy 46.654564 -209.026429) (xy 46.642984 -209.079682) (xy 46.623942 -209.130745) (xy 46.597828 -209.178578)
			(xy 46.565171 -209.222207) (xy 46.554749 -209.23263) (xy 64.500013 -209.23263) (xy 64.500013 -209.16937)
			(xy 64.50827 -209.10665) (xy 64.524643 -209.045545) (xy 64.548852 -208.9871) (xy 64.580482 -208.932314)
			(xy 64.618993 -208.882126) (xy 64.663725 -208.837394) (xy 64.713913 -208.798883) (xy 64.768698 -208.767253)
			(xy 64.827143 -208.743044) (xy 64.888248 -208.726671) (xy 64.950968 -208.718413) (xy 64.982598 -208.717896)
			(xy 66.22669 -208.717896) (xy 66.235072 -208.71688) (xy 66.263896 -208.713352) (xy 66.321961 -208.712427)
			(xy 66.379716 -208.71848) (xy 66.436328 -208.731423) (xy 66.490976 -208.751069) (xy 66.54287 -208.777134)
			(xy 66.567304 -208.792826) (xy 66.599054 -208.813908) (xy 66.656204 -208.813908) (xy 66.656204 -208.869026)
			(xy 66.676084 -208.891334) (xy 66.710728 -208.940021) (xy 66.739101 -208.992611) (xy 66.760769 -209.048299)
			(xy 66.7754 -209.106235) (xy 66.782771 -209.165534) (xy 66.782769 -209.225289) (xy 66.775395 -209.284588)
			(xy 66.760761 -209.342523) (xy 66.739091 -209.398211) (xy 66.710716 -209.450799) (xy 66.676069 -209.499485)
			(xy 66.656204 -209.521806) (xy 66.656204 -209.576924) (xy 66.602102 -209.576924) (xy 66.494914 -209.684112)
			(xy 64.982598 -209.684112) (xy 64.950968 -209.683587) (xy 64.888248 -209.675329) (xy 64.827143 -209.658956)
			(xy 64.768698 -209.634747) (xy 64.713913 -209.603117) (xy 64.663725 -209.564606) (xy 64.618993 -209.519874)
			(xy 64.580482 -209.469686) (xy 64.548852 -209.4149) (xy 64.524643 -209.356455) (xy 64.50827 -209.29535)
			(xy 64.500013 -209.23263) (xy 46.554749 -209.23263) (xy 46.526637 -209.260745) (xy 46.483011 -209.293406)
			(xy 46.435181 -209.319526) (xy 46.38412 -209.338573) (xy 46.330869 -209.350159) (xy 46.27651 -209.354048)
			(xy 46.222151 -209.350162) (xy 46.168899 -209.338578) (xy 46.117837 -209.319534) (xy 46.070005 -209.293417)
			(xy 46.047914 -209.277458) (xy 46.028902 -209.263862) (xy 45.987019 -209.24313) (xy 45.942051 -209.230404)
			(xy 45.895514 -209.226114) (xy 45.848977 -209.230404) (xy 45.804009 -209.24313) (xy 45.762126 -209.263862)
			(xy 45.743114 -209.277458) (xy 45.720979 -209.293352) (xy 45.673155 -209.319468) (xy 45.622101 -209.338512)
			(xy 45.568857 -209.350097) (xy 45.514506 -209.353985) (xy 45.460155 -209.350098) (xy 45.40691 -209.338516)
			(xy 45.355856 -209.319473) (xy 45.308031 -209.293358) (xy 45.264411 -209.260703) (xy 45.225882 -209.222171)
			(xy 45.193229 -209.178548) (xy 45.167117 -209.130722) (xy 45.148078 -209.079667) (xy 45.136498 -209.026421)
			(xy 45.132615 -208.97207) (xy 44.754439 -208.97207) (xy 44.750555 -209.026427) (xy 44.738975 -209.079678)
			(xy 44.719935 -209.130738) (xy 44.693821 -209.17857) (xy 44.661166 -209.222198) (xy 44.622635 -209.260734)
			(xy 44.579011 -209.293395) (xy 44.531183 -209.319514) (xy 44.480125 -209.338561) (xy 44.426875 -209.350148)
			(xy 44.372519 -209.354039) (xy 44.318162 -209.350154) (xy 44.264912 -209.338572) (xy 44.213852 -209.31953)
			(xy 44.166021 -209.293415) (xy 44.14393 -209.277458) (xy 44.124918 -209.263862) (xy 44.083035 -209.24313)
			(xy 44.038067 -209.230404) (xy 43.99153 -209.226114) (xy 43.944993 -209.230404) (xy 43.900025 -209.24313)
			(xy 43.858142 -209.263862) (xy 43.83913 -209.277458) (xy 43.816994 -209.293353) (xy 43.76917 -209.319472)
			(xy 43.718114 -209.338519) (xy 43.664868 -209.350105) (xy 43.610515 -209.353994) (xy 43.556162 -209.350109)
			(xy 43.502915 -209.338527) (xy 43.451858 -209.319485) (xy 43.404031 -209.293369) (xy 43.360408 -209.260713)
			(xy 43.321877 -209.222181) (xy 43.289223 -209.178556) (xy 43.263109 -209.130729) (xy 43.244069 -209.079671)
			(xy 43.232489 -209.026424) (xy 43.228606 -208.97207) (xy 42.513464 -208.97207) (xy 42.50958 -209.026433)
			(xy 42.497998 -209.079689) (xy 42.478955 -209.130755) (xy 42.452838 -209.178591) (xy 42.420178 -209.222222)
			(xy 42.381641 -209.260762) (xy 42.338012 -209.293424) (xy 42.290178 -209.319545) (xy 42.239113 -209.338591)
			(xy 42.185857 -209.350176) (xy 42.131495 -209.354064) (xy 42.077133 -209.350175) (xy 42.023878 -209.338588)
			(xy 41.972813 -209.31954) (xy 41.92498 -209.293419) (xy 41.902888 -209.277458) (xy 41.883876 -209.263862)
			(xy 41.841993 -209.24313) (xy 41.797025 -209.230404) (xy 41.750488 -209.226114) (xy 41.703951 -209.230404)
			(xy 41.658983 -209.24313) (xy 41.6171 -209.263862) (xy 41.598088 -209.277458) (xy 41.575953 -209.293349)
			(xy 41.528132 -209.319462) (xy 41.47708 -209.338502) (xy 41.423839 -209.350083) (xy 41.369491 -209.353969)
			(xy 41.315144 -209.350081) (xy 41.261903 -209.338497) (xy 41.210853 -209.319454) (xy 41.163032 -209.29334)
			(xy 41.119415 -209.260685) (xy 41.080889 -209.222156) (xy 41.048239 -209.178535) (xy 41.022129 -209.130712)
			(xy 41.003092 -209.07966) (xy 40.991514 -209.026418) (xy 40.987631 -208.97207) (xy 40.626771 -208.97207)
			(xy 40.622887 -209.026434) (xy 40.611305 -209.079692) (xy 40.592261 -209.13076) (xy 40.566142 -209.178597)
			(xy 40.533482 -209.222229) (xy 40.494943 -209.26077) (xy 40.451312 -209.293433) (xy 40.403476 -209.319553)
			(xy 40.35241 -209.3386) (xy 40.299152 -209.350184) (xy 40.244788 -209.354071) (xy 40.190425 -209.350181)
			(xy 40.137168 -209.338593) (xy 40.086103 -209.319543) (xy 40.038268 -209.29342) (xy 40.016176 -209.277458)
			(xy 39.997164 -209.263862) (xy 39.955281 -209.24313) (xy 39.910313 -209.230404) (xy 39.863776 -209.226114)
			(xy 39.817239 -209.230404) (xy 39.772271 -209.24313) (xy 39.730388 -209.263862) (xy 39.711376 -209.277458)
			(xy 39.689242 -209.293348) (xy 39.641421 -209.319459) (xy 39.590371 -209.338498) (xy 39.53713 -209.350077)
			(xy 39.482784 -209.353962) (xy 39.428439 -209.350073) (xy 39.3752 -209.338489) (xy 39.324151 -209.319446)
			(xy 39.276332 -209.293332) (xy 39.232717 -209.260678) (xy 39.194193 -209.222149) (xy 39.161544 -209.178529)
			(xy 39.135435 -209.130708) (xy 39.116398 -209.079657) (xy 39.104821 -209.026416) (xy 39.100938 -208.97207)
			(xy 36.408868 -208.97207) (xy 36.431719 -209.031055) (xy 36.4555 -209.114637) (xy 36.471468 -209.200057)
			(xy 36.479486 -209.286586) (xy 36.479988 -209.330036) (xy 36.479486 -209.373486) (xy 36.471468 -209.460015)
			(xy 36.4555 -209.545435) (xy 36.431719 -209.629017) (xy 36.400327 -209.710049) (xy 36.361593 -209.787838)
			(xy 36.315846 -209.861722) (xy 36.263477 -209.931069) (xy 36.204933 -209.995289) (xy 36.140713 -210.053833)
			(xy 36.079698 -210.09991) (xy 69.997584 -210.09991) (xy 70.001572 -209.84729) (xy 70.013533 -209.594922)
			(xy 70.033455 -209.343058) (xy 70.061319 -209.091948) (xy 70.097095 -208.841842) (xy 70.140749 -208.592991)
			(xy 70.192238 -208.345642) (xy 70.251509 -208.100041) (xy 70.318504 -207.856434) (xy 70.393155 -207.615064)
			(xy 70.47539 -207.37617) (xy 70.565124 -207.139992) (xy 70.66227 -206.906764) (xy 70.76673 -206.676718)
			(xy 70.878401 -206.450086) (xy 70.99717 -206.227091) (xy 71.122919 -206.007957) (xy 71.255524 -205.792902)
			(xy 71.394851 -205.58214) (xy 71.540763 -205.375882) (xy 71.693113 -205.174333) (xy 71.851749 -204.977693)
			(xy 72.016514 -204.78616) (xy 72.187244 -204.599923) (xy 72.363768 -204.419169) (xy 72.54591 -204.244078)
			(xy 72.733488 -204.074824) (xy 72.926316 -203.911575) (xy 73.124201 -203.754496) (xy 73.326947 -203.603741)
			(xy 73.534351 -203.459463) (xy 73.746206 -203.321803) (xy 73.962301 -203.1909) (xy 74.182421 -203.066884)
			(xy 74.406346 -202.949879) (xy 74.633853 -202.840001) (xy 74.864715 -202.73736) (xy 75.098703 -202.642058)
			(xy 75.335582 -202.554191) (xy 75.575118 -202.473844) (xy 75.81707 -202.4011) (xy 76.061198 -202.33603)
			(xy 76.307259 -202.2787) (xy 76.555007 -202.229166) (xy 76.804195 -202.187477) (xy 77.054575 -202.153676)
			(xy 77.305897 -202.127795) (xy 77.557911 -202.109862) (xy 77.810365 -202.099893) (xy 78.063009 -202.097899)
			(xy 78.315589 -202.103881) (xy 78.567855 -202.117834) (xy 78.819554 -202.139744) (xy 79.070437 -202.169588)
			(xy 79.320252 -202.207338) (xy 79.568751 -202.252955) (xy 79.815686 -202.306394) (xy 80.060811 -202.367602)
			(xy 80.303881 -202.436517) (xy 80.544655 -202.513072) (xy 80.782892 -202.597189) (xy 81.018355 -202.688786)
			(xy 81.250809 -202.78777) (xy 81.480023 -202.894042) (xy 81.705767 -203.007498) (xy 81.927817 -203.128023)
			(xy 82.145951 -203.255499) (xy 82.359953 -203.389797) (xy 82.569609 -203.530783) (xy 82.774709 -203.678318)
			(xy 82.975049 -203.832254) (xy 83.17043 -203.992438) (xy 83.360657 -204.15871) (xy 83.54554 -204.330905)
			(xy 83.724896 -204.508849) (xy 83.898544 -204.692368) (xy 84.066312 -204.881276) (xy 84.228033 -205.075387)
			(xy 84.383546 -205.274506) (xy 84.532695 -205.478435) (xy 84.675332 -205.686971) (xy 84.811315 -205.899906)
			(xy 84.940508 -206.117028) (xy 85.062783 -206.33812) (xy 85.178017 -206.562961) (xy 85.286096 -206.791329)
			(xy 85.386911 -207.022994) (xy 85.480363 -207.257727) (xy 85.566358 -207.495292) (xy 85.644811 -207.735454)
			(xy 85.715643 -207.977973) (xy 85.778784 -208.222608) (xy 85.834171 -208.469113) (xy 85.881748 -208.717244)
			(xy 85.921468 -208.966754) (xy 85.953292 -209.217393) (xy 85.977188 -209.468911) (xy 85.993132 -209.721059)
			(xy 86.001107 -209.973584) (xy 86.001606 -210.09991) (xy 86.001107 -210.226236) (xy 85.993132 -210.478761)
			(xy 85.977188 -210.730909) (xy 85.953292 -210.982427) (xy 85.921468 -211.233066) (xy 85.881748 -211.482576)
			(xy 85.834171 -211.730707) (xy 85.778784 -211.977212) (xy 85.715643 -212.221847) (xy 85.644811 -212.464366)
			(xy 85.566358 -212.704528) (xy 85.480363 -212.942093) (xy 85.386911 -213.176826) (xy 85.286096 -213.408491)
			(xy 85.178017 -213.636859) (xy 85.062783 -213.8617) (xy 84.940508 -214.082792) (xy 84.811315 -214.299914)
			(xy 84.675332 -214.512849) (xy 84.532695 -214.721385) (xy 84.383546 -214.925314) (xy 84.228033 -215.124433)
			(xy 84.066312 -215.318544) (xy 83.898544 -215.507452) (xy 83.724896 -215.690971) (xy 83.54554 -215.868915)
			(xy 83.360657 -216.04111) (xy 83.17043 -216.207382) (xy 82.975049 -216.367566) (xy 82.774709 -216.521502)
			(xy 82.569609 -216.669037) (xy 82.359953 -216.810023) (xy 82.145951 -216.944321) (xy 81.927817 -217.071797)
			(xy 81.705767 -217.192322) (xy 81.480023 -217.305778) (xy 81.250809 -217.41205) (xy 81.018355 -217.511034)
			(xy 80.782892 -217.602631) (xy 80.544655 -217.686748) (xy 80.303881 -217.763303) (xy 80.060811 -217.832218)
			(xy 79.815686 -217.893426) (xy 79.568751 -217.946865) (xy 79.320252 -217.992482) (xy 79.070437 -218.030232)
			(xy 78.819554 -218.060076) (xy 78.567855 -218.081986) (xy 78.315589 -218.095939) (xy 78.063009 -218.101921)
			(xy 77.810365 -218.099927) (xy 77.557911 -218.089958) (xy 77.305897 -218.072025) (xy 77.054575 -218.046144)
			(xy 76.804195 -218.012343) (xy 76.555007 -217.970654) (xy 76.307259 -217.92112) (xy 76.061198 -217.86379)
			(xy 75.81707 -217.79872) (xy 75.575118 -217.725976) (xy 75.335582 -217.645629) (xy 75.098703 -217.557762)
			(xy 74.864715 -217.46246) (xy 74.633853 -217.359819) (xy 74.406346 -217.249941) (xy 74.182421 -217.132936)
			(xy 73.962301 -217.00892) (xy 73.746206 -216.878017) (xy 73.534351 -216.740357) (xy 73.326947 -216.596079)
			(xy 73.124201 -216.445324) (xy 72.926316 -216.288245) (xy 72.733488 -216.124996) (xy 72.54591 -215.955742)
			(xy 72.363768 -215.780651) (xy 72.187244 -215.599897) (xy 72.016514 -215.41366) (xy 71.851749 -215.222127)
			(xy 71.693113 -215.025487) (xy 71.540763 -214.823938) (xy 71.394851 -214.61768) (xy 71.255524 -214.406918)
			(xy 71.122919 -214.191863) (xy 70.99717 -213.972729) (xy 70.878401 -213.749734) (xy 70.76673 -213.523102)
			(xy 70.66227 -213.293056) (xy 70.565124 -213.059828) (xy 70.47539 -212.82365) (xy 70.393155 -212.584756)
			(xy 70.318504 -212.343386) (xy 70.251509 -212.099779) (xy 70.192238 -211.854178) (xy 70.140749 -211.606829)
			(xy 70.097095 -211.357978) (xy 70.061319 -211.107872) (xy 70.033455 -210.856762) (xy 70.013533 -210.604898)
			(xy 70.001572 -210.35253) (xy 69.997584 -210.09991) (xy 36.079698 -210.09991) (xy 36.071366 -210.106202)
			(xy 35.997482 -210.151949) (xy 35.919693 -210.190683) (xy 35.838661 -210.222075) (xy 35.755079 -210.245856)
			(xy 35.669659 -210.261824) (xy 35.58313 -210.269842) (xy 35.49623 -210.269842) (xy 35.409701 -210.261824)
			(xy 35.324281 -210.245856) (xy 35.240699 -210.222075) (xy 35.159667 -210.190683) (xy 35.081878 -210.151949)
			(xy 35.007994 -210.106202) (xy 34.938647 -210.053833) (xy 34.874427 -209.995289) (xy 34.815883 -209.931069)
			(xy 34.763514 -209.861722) (xy 34.717767 -209.787838) (xy 34.679033 -209.710049) (xy 34.647641 -209.629017)
			(xy 34.62386 -209.545435) (xy 34.607892 -209.460015) (xy 34.599874 -209.373486) (xy 31.398502 -209.373486)
			(xy 31.396473 -209.417185) (xy 31.384359 -209.503638) (xy 31.364285 -209.588596) (xy 31.336422 -209.671327)
			(xy 31.301011 -209.75112) (xy 31.258356 -209.827287) (xy 31.208825 -209.899172) (xy 31.152845 -209.966157)
			(xy 31.090896 -210.027665) (xy 31.023514 -210.083166) (xy 30.951277 -210.132183) (xy 30.874808 -210.174293)
			(xy 30.794764 -210.209134) (xy 30.711836 -210.236406) (xy 30.626738 -210.255875) (xy 30.540201 -210.267371)
			(xy 30.452971 -210.270798) (xy 30.365799 -210.266124) (xy 30.279435 -210.25339) (xy 30.194624 -210.232707)
			(xy 30.112094 -210.204251) (xy 30.032558 -210.168269) (xy 29.994352 -210.147154) (xy 29.974901 -210.136653)
			(xy 29.93327 -210.1218) (xy 29.889698 -210.114376) (xy 29.845499 -210.114603) (xy 29.802005 -210.122474)
			(xy 29.76053 -210.137753) (xy 29.722324 -210.159978) (xy 29.68854 -210.188478) (xy 29.660197 -210.222395)
			(xy 29.63815 -210.260704) (xy 29.623065 -210.30225) (xy 29.615396 -210.34578) (xy 29.614876 -210.36788)
			(xy 29.614876 -210.832192) (xy 29.615344 -210.854304) (xy 29.618642 -210.873108) (xy 39.100887 -210.873108)
			(xy 39.104773 -210.818755) (xy 39.116355 -210.765508) (xy 39.135398 -210.714452) (xy 39.161512 -210.666625)
			(xy 39.194168 -210.623001) (xy 39.2327 -210.58447) (xy 39.276323 -210.551814) (xy 39.324149 -210.525699)
			(xy 39.375206 -210.506656) (xy 39.428453 -210.495073) (xy 39.482806 -210.491187) (xy 39.537159 -210.495075)
			(xy 39.590406 -210.506659) (xy 39.641462 -210.525704) (xy 39.689287 -210.55182) (xy 39.711376 -210.567778)
			(xy 39.730388 -210.581374) (xy 39.772271 -210.602106) (xy 39.817239 -210.614832) (xy 39.863776 -210.619122)
			(xy 39.910313 -210.614832) (xy 39.955281 -210.602106) (xy 39.997164 -210.581374) (xy 40.016176 -210.567778)
			(xy 40.038278 -210.551835) (xy 40.086104 -210.525712) (xy 40.137162 -210.506662) (xy 40.19041 -210.495073)
			(xy 40.244767 -210.49118) (xy 40.299124 -210.495063) (xy 40.352375 -210.506643) (xy 40.403435 -210.525685)
			(xy 40.451266 -210.551799) (xy 40.494893 -210.584455) (xy 40.533429 -210.622988) (xy 40.566088 -210.666613)
			(xy 40.592205 -210.714442) (xy 40.61125 -210.765502) (xy 40.622833 -210.818752) (xy 40.62672 -210.873108)
			(xy 40.987579 -210.873108) (xy 40.991466 -210.818753) (xy 41.003049 -210.765505) (xy 41.022092 -210.714447)
			(xy 41.048208 -210.666619) (xy 41.080865 -210.622994) (xy 41.119398 -210.584462) (xy 41.163022 -210.551805)
			(xy 41.210851 -210.52569) (xy 41.261909 -210.506647) (xy 41.315158 -210.495065) (xy 41.369513 -210.491179)
			(xy 41.423868 -210.495069) (xy 41.477115 -210.506655) (xy 41.528172 -210.525701) (xy 41.575999 -210.551819)
			(xy 41.598088 -210.567778) (xy 41.6171 -210.581374) (xy 41.658983 -210.602106) (xy 41.703951 -210.614832)
			(xy 41.750488 -210.619122) (xy 41.797025 -210.614832) (xy 41.841993 -210.602106) (xy 41.883876 -210.581374)
			(xy 41.902888 -210.567778) (xy 41.92499 -210.551836) (xy 41.972815 -210.525715) (xy 42.023871 -210.506667)
			(xy 42.077119 -210.495079) (xy 42.131474 -210.491187) (xy 42.185829 -210.495071) (xy 42.239078 -210.506652)
			(xy 42.290137 -210.525693) (xy 42.337966 -210.551807) (xy 42.381591 -210.584463) (xy 42.420125 -210.622995)
			(xy 42.452783 -210.666619) (xy 42.478899 -210.714447) (xy 42.497943 -210.765505) (xy 42.509526 -210.818753)
			(xy 42.513413 -210.873108) (xy 43.228554 -210.873108) (xy 43.232441 -210.818748) (xy 43.244026 -210.765494)
			(xy 43.263072 -210.71443) (xy 43.289191 -210.666598) (xy 43.321853 -210.62297) (xy 43.360391 -210.584434)
			(xy 43.404022 -210.551776) (xy 43.451856 -210.52566) (xy 43.502921 -210.506618) (xy 43.556176 -210.495037)
			(xy 43.610537 -210.491154) (xy 43.664897 -210.495048) (xy 43.71815 -210.506638) (xy 43.769211 -210.52569)
			(xy 43.81704 -210.551816) (xy 43.83913 -210.567778) (xy 43.858142 -210.581374) (xy 43.900025 -210.602106)
			(xy 43.944993 -210.614832) (xy 43.99153 -210.619122) (xy 44.038067 -210.614832) (xy 44.083035 -210.602106)
			(xy 44.124918 -210.581374) (xy 44.14393 -210.567778) (xy 44.166031 -210.551839) (xy 44.213853 -210.525725)
			(xy 44.264906 -210.506683) (xy 44.318148 -210.4951) (xy 44.372497 -210.491213) (xy 44.426847 -210.4951)
			(xy 44.48009 -210.506682) (xy 44.531142 -210.525723) (xy 44.578965 -210.551837) (xy 44.622585 -210.58449)
			(xy 44.661113 -210.62302) (xy 44.693766 -210.66664) (xy 44.719879 -210.714463) (xy 44.73892 -210.765516)
			(xy 44.750501 -210.818759) (xy 44.754387 -210.873108) (xy 45.132564 -210.873108) (xy 45.136451 -210.81875)
			(xy 45.148034 -210.765498) (xy 45.167079 -210.714437) (xy 45.193197 -210.666606) (xy 45.225857 -210.622979)
			(xy 45.264394 -210.584445) (xy 45.308022 -210.551787) (xy 45.355854 -210.525671) (xy 45.406916 -210.506629)
			(xy 45.460169 -210.495048) (xy 45.514528 -210.491164) (xy 45.568886 -210.495056) (xy 45.622137 -210.506645)
			(xy 45.673196 -210.525694) (xy 45.721024 -210.551817) (xy 45.743114 -210.567778) (xy 45.762126 -210.581374)
			(xy 45.804009 -210.602106) (xy 45.848977 -210.614832) (xy 45.895514 -210.619122) (xy 45.942051 -210.614832)
			(xy 45.987019 -210.602106) (xy 46.028902 -210.581374) (xy 46.047914 -210.567778) (xy 46.070015 -210.551838)
			(xy 46.117839 -210.525721) (xy 46.168892 -210.506677) (xy 46.222137 -210.495092) (xy 46.276488 -210.491203)
			(xy 46.33084 -210.495089) (xy 46.384085 -210.50667) (xy 46.43514 -210.525712) (xy 46.482965 -210.551825)
			(xy 46.526587 -210.58448) (xy 46.565118 -210.62301) (xy 46.597773 -210.666632) (xy 46.623887 -210.714457)
			(xy 46.642929 -210.765512) (xy 46.654511 -210.818757) (xy 46.658397 -210.873108) (xy 46.654508 -210.92746)
			(xy 46.642924 -210.980704) (xy 46.62388 -211.031758) (xy 46.597764 -211.079582) (xy 46.565107 -211.123203)
			(xy 46.526575 -211.161731) (xy 46.482951 -211.194384) (xy 46.435125 -211.220495) (xy 46.384069 -211.239534)
			(xy 46.330823 -211.251114) (xy 46.276472 -211.254997) (xy 46.22212 -211.251105) (xy 46.168876 -211.239518)
			(xy 46.117823 -211.220472) (xy 46.070001 -211.194353) (xy 46.047914 -211.178394) (xy 46.028902 -211.164798)
			(xy 45.987019 -211.144066) (xy 45.942051 -211.13134) (xy 45.895514 -211.12705) (xy 45.848977 -211.13134)
			(xy 45.804009 -211.144066) (xy 45.762126 -211.164798) (xy 45.743114 -211.178394) (xy 45.721039 -211.194374)
			(xy 45.673211 -211.220499) (xy 45.622153 -211.239551) (xy 45.568902 -211.251142) (xy 45.514544 -211.255036)
			(xy 45.460186 -211.251154) (xy 45.406932 -211.239576) (xy 45.355869 -211.220536) (xy 45.308036 -211.194422)
			(xy 45.264406 -211.161766) (xy 45.225868 -211.123234) (xy 45.193207 -211.079608) (xy 45.167086 -211.031779)
			(xy 45.148039 -210.980718) (xy 45.136453 -210.927467) (xy 45.132564 -210.873108) (xy 44.754387 -210.873108)
			(xy 44.750499 -210.927458) (xy 44.738915 -210.9807) (xy 44.719872 -211.031752) (xy 44.693757 -211.079574)
			(xy 44.661102 -211.123193) (xy 44.622572 -211.161721) (xy 44.578951 -211.194372) (xy 44.531127 -211.220484)
			(xy 44.480073 -211.239523) (xy 44.42683 -211.251103) (xy 44.372481 -211.254987) (xy 44.318132 -211.251097)
			(xy 44.264889 -211.239512) (xy 44.213838 -211.220468) (xy 44.166016 -211.194351) (xy 44.14393 -211.178394)
			(xy 44.124918 -211.164798) (xy 44.083035 -211.144066) (xy 44.038067 -211.13134) (xy 43.99153 -211.12705)
			(xy 43.944993 -211.13134) (xy 43.900025 -211.144066) (xy 43.858142 -211.164798) (xy 43.83913 -211.178394)
			(xy 43.817054 -211.194375) (xy 43.769226 -211.220503) (xy 43.718166 -211.239557) (xy 43.664914 -211.25115)
			(xy 43.610554 -211.255046) (xy 43.556192 -211.251165) (xy 43.502937 -211.239587) (xy 43.451872 -211.220547)
			(xy 43.404036 -211.194433) (xy 43.360404 -211.161777) (xy 43.321864 -211.123243) (xy 43.2892 -211.079616)
			(xy 43.263079 -211.031785) (xy 43.24403 -210.980722) (xy 43.232444 -210.927469) (xy 43.228554 -210.873108)
			(xy 42.513413 -210.873108) (xy 42.509524 -210.927463) (xy 42.497938 -210.980711) (xy 42.478892 -211.031768)
			(xy 42.452774 -211.079595) (xy 42.420114 -211.123218) (xy 42.381579 -211.161748) (xy 42.337952 -211.194402)
			(xy 42.290121 -211.220514) (xy 42.239062 -211.239553) (xy 42.185812 -211.251131) (xy 42.131457 -211.255013)
			(xy 42.077102 -211.251119) (xy 42.023855 -211.239528) (xy 41.9728 -211.220478) (xy 41.924975 -211.194355)
			(xy 41.902888 -211.178394) (xy 41.883876 -211.164798) (xy 41.841993 -211.144066) (xy 41.797025 -211.13134)
			(xy 41.750488 -211.12705) (xy 41.703951 -211.13134) (xy 41.658983 -211.144066) (xy 41.6171 -211.164798)
			(xy 41.598088 -211.178394) (xy 41.576013 -211.194372) (xy 41.528188 -211.220492) (xy 41.477132 -211.239541)
			(xy 41.423884 -211.251129) (xy 41.36953 -211.255021) (xy 41.315174 -211.251137) (xy 41.261925 -211.239557)
			(xy 41.210866 -211.220517) (xy 41.163037 -211.194404) (xy 41.11941 -211.161749) (xy 41.080876 -211.123218)
			(xy 41.048217 -211.079595) (xy 41.022099 -211.031768) (xy 41.003053 -210.980711) (xy 40.991468 -210.927463)
			(xy 40.987579 -210.873108) (xy 40.62672 -210.873108) (xy 40.622831 -210.927465) (xy 40.611245 -210.980715)
			(xy 40.592198 -211.031773) (xy 40.566079 -211.079601) (xy 40.533418 -211.123225) (xy 40.494881 -211.161756)
			(xy 40.451252 -211.19441) (xy 40.40342 -211.220522) (xy 40.352358 -211.239561) (xy 40.299107 -211.251139)
			(xy 40.24475 -211.25502) (xy 40.190394 -211.251125) (xy 40.137145 -211.239533) (xy 40.086089 -211.220481)
			(xy 40.038264 -211.194356) (xy 40.016176 -211.178394) (xy 39.997164 -211.164798) (xy 39.955281 -211.144066)
			(xy 39.910313 -211.13134) (xy 39.863776 -211.12705) (xy 39.817239 -211.13134) (xy 39.772271 -211.144066)
			(xy 39.730388 -211.164798) (xy 39.711376 -211.178394) (xy 39.689302 -211.194371) (xy 39.641477 -211.220489)
			(xy 39.590422 -211.239536) (xy 39.537176 -211.251123) (xy 39.482823 -211.255013) (xy 39.428469 -211.251129)
			(xy 39.375222 -211.239549) (xy 39.324165 -211.220508) (xy 39.276337 -211.194395) (xy 39.232712 -211.161741)
			(xy 39.194179 -211.123211) (xy 39.161521 -211.079589) (xy 39.135405 -211.031764) (xy 39.11636 -210.980708)
			(xy 39.104775 -210.927462) (xy 39.100887 -210.873108) (xy 29.618642 -210.873108) (xy 29.622984 -210.897863)
			(xy 29.638052 -210.939442) (xy 29.660092 -210.977782) (xy 29.688439 -211.011727) (xy 29.722236 -211.040249)
			(xy 29.760462 -211.062488) (xy 29.801961 -211.077772) (xy 29.84548 -211.085638) (xy 29.889703 -211.085849)
			(xy 29.933295 -211.078398) (xy 29.974938 -211.063511) (xy 29.994352 -211.052918) (xy 30.032526 -211.031747)
			(xy 30.112061 -210.995762) (xy 30.194589 -210.967303) (xy 30.2794 -210.946616) (xy 30.365763 -210.93388)
			(xy 30.452935 -210.929203) (xy 30.540165 -210.932626) (xy 30.626703 -210.944119) (xy 30.711802 -210.963584)
			(xy 30.794731 -210.990853) (xy 30.874776 -211.025691) (xy 30.951246 -211.067798) (xy 31.023485 -211.116812)
			(xy 31.09087 -211.172311) (xy 31.15282 -211.233817) (xy 31.208804 -211.3008) (xy 31.258337 -211.372683)
			(xy 31.300995 -211.448848) (xy 31.336409 -211.52864) (xy 31.364275 -211.61137) (xy 31.384353 -211.696327)
			(xy 31.39647 -211.782779) (xy 31.400522 -211.869982) (xy 31.398502 -211.913486) (xy 34.599874 -211.913486)
			(xy 34.599874 -211.826586) (xy 34.607892 -211.740057) (xy 34.62386 -211.654637) (xy 34.647641 -211.571055)
			(xy 34.679033 -211.490023) (xy 34.717767 -211.412234) (xy 34.763514 -211.33835) (xy 34.815883 -211.269003)
			(xy 34.874427 -211.204783) (xy 34.938647 -211.146239) (xy 35.007994 -211.09387) (xy 35.081878 -211.048123)
			(xy 35.159667 -211.009389) (xy 35.240699 -210.977997) (xy 35.324281 -210.954216) (xy 35.409701 -210.938248)
			(xy 35.49623 -210.93023) (xy 35.58313 -210.93023) (xy 35.669659 -210.938248) (xy 35.755079 -210.954216)
			(xy 35.838661 -210.977997) (xy 35.919693 -211.009389) (xy 35.997482 -211.048123) (xy 36.071366 -211.09387)
			(xy 36.140713 -211.146239) (xy 36.204933 -211.204783) (xy 36.263477 -211.269003) (xy 36.315846 -211.33835)
			(xy 36.361593 -211.412234) (xy 36.400327 -211.490023) (xy 36.431719 -211.571055) (xy 36.4555 -211.654637)
			(xy 36.471468 -211.740057) (xy 36.479486 -211.826586) (xy 36.479988 -211.870036) (xy 36.479486 -211.913486)
			(xy 36.471468 -212.000015) (xy 36.4555 -212.085435) (xy 36.431719 -212.169017) (xy 36.400327 -212.250049)
			(xy 36.361593 -212.327838) (xy 36.315846 -212.401722) (xy 36.263477 -212.471069) (xy 36.204933 -212.535289)
			(xy 36.190781 -212.54819) (xy 39.100911 -212.54819) (xy 39.104799 -212.493841) (xy 39.116383 -212.440598)
			(xy 39.135427 -212.389545) (xy 39.161542 -212.341723) (xy 39.194198 -212.298103) (xy 39.232729 -212.259576)
			(xy 39.276351 -212.226924) (xy 39.324176 -212.200813) (xy 39.37523 -212.181774) (xy 39.428474 -212.170195)
			(xy 39.482824 -212.166311) (xy 39.537174 -212.170201) (xy 39.590416 -212.181787) (xy 39.641468 -212.200833)
			(xy 39.68929 -212.22695) (xy 39.711376 -212.242908) (xy 39.730388 -212.256504) (xy 39.772271 -212.277236)
			(xy 39.817239 -212.289962) (xy 39.863776 -212.294252) (xy 39.910313 -212.289962) (xy 39.955281 -212.277236)
			(xy 39.997164 -212.256504) (xy 40.016176 -212.242908) (xy 40.03825 -212.226924) (xy 40.086078 -212.200798)
			(xy 40.137138 -212.181744) (xy 40.190389 -212.170152) (xy 40.244749 -212.166256) (xy 40.299109 -212.170137)
			(xy 40.352364 -212.181715) (xy 40.403429 -212.200755) (xy 40.451264 -212.226869) (xy 40.494895 -212.259525)
			(xy 40.533435 -212.298058) (xy 40.566098 -212.341685) (xy 40.59222 -212.389516) (xy 40.611267 -212.440578)
			(xy 40.622854 -212.49383) (xy 40.626744 -212.54819) (xy 40.987603 -212.54819) (xy 40.991492 -212.493839)
			(xy 41.003077 -212.440594) (xy 41.022121 -212.38954) (xy 41.048238 -212.341717) (xy 41.080894 -212.298096)
			(xy 41.119427 -212.259568) (xy 41.163051 -212.226916) (xy 41.210877 -212.200804) (xy 41.261933 -212.181765)
			(xy 41.315179 -212.170187) (xy 41.369531 -212.166303) (xy 41.423882 -212.170195) (xy 41.477126 -212.181783)
			(xy 41.528179 -212.20083) (xy 41.576001 -212.226949) (xy 41.598088 -212.242908) (xy 41.6171 -212.256504)
			(xy 41.658983 -212.277236) (xy 41.703951 -212.289962) (xy 41.750488 -212.294252) (xy 41.797025 -212.289962)
			(xy 41.841993 -212.277236) (xy 41.883876 -212.256504) (xy 41.902888 -212.242908) (xy 41.924961 -212.226925)
			(xy 41.972789 -212.200801) (xy 42.023847 -212.181749) (xy 42.077098 -212.170158) (xy 42.131456 -212.166263)
			(xy 42.185814 -212.170145) (xy 42.239067 -212.181724) (xy 42.29013 -212.200764) (xy 42.337964 -212.226877)
			(xy 42.381594 -212.259533) (xy 42.420132 -212.298066) (xy 42.452793 -212.341691) (xy 42.478914 -212.38952)
			(xy 42.497961 -212.440581) (xy 42.509547 -212.493832) (xy 42.513437 -212.54819) (xy 43.228578 -212.54819)
			(xy 43.232468 -212.493833) (xy 43.244054 -212.440583) (xy 43.263101 -212.389524) (xy 43.289221 -212.341696)
			(xy 43.321883 -212.298072) (xy 43.36042 -212.25954) (xy 43.40405 -212.226886) (xy 43.451883 -212.200774)
			(xy 43.502945 -212.181736) (xy 43.556197 -212.170159) (xy 43.610555 -212.166278) (xy 43.664911 -212.170174)
			(xy 43.71816 -212.181767) (xy 43.769217 -212.20082) (xy 43.817042 -212.226945) (xy 43.83913 -212.242908)
			(xy 43.858142 -212.256504) (xy 43.900025 -212.277236) (xy 43.944993 -212.289962) (xy 43.99153 -212.294252)
			(xy 44.038067 -212.289962) (xy 44.083035 -212.277236) (xy 44.124918 -212.256504) (xy 44.14393 -212.242908)
			(xy 44.166002 -212.226929) (xy 44.213827 -212.200811) (xy 44.264881 -212.181765) (xy 44.318127 -212.170179)
			(xy 44.372479 -212.166289) (xy 44.426832 -212.170173) (xy 44.480079 -212.181754) (xy 44.531136 -212.200794)
			(xy 44.578963 -212.226907) (xy 44.622587 -212.25956) (xy 44.66112 -212.29809) (xy 44.693777 -212.341712)
			(xy 44.719894 -212.389537) (xy 44.738938 -212.440592) (xy 44.750523 -212.493838) (xy 44.754411 -212.54819)
			(xy 45.132588 -212.54819) (xy 45.136477 -212.493835) (xy 45.148063 -212.440587) (xy 45.167109 -212.38953)
			(xy 45.193227 -212.341704) (xy 45.225887 -212.298081) (xy 45.264423 -212.259551) (xy 45.30805 -212.226898)
			(xy 45.355881 -212.200786) (xy 45.40694 -212.181747) (xy 45.46019 -212.170169) (xy 45.514546 -212.166288)
			(xy 45.5689 -212.170182) (xy 45.622147 -212.181773) (xy 45.673202 -212.200824) (xy 45.721027 -212.226947)
			(xy 45.743114 -212.242908) (xy 45.762126 -212.256504) (xy 45.804009 -212.277236) (xy 45.848977 -212.289962)
			(xy 45.895514 -212.294252) (xy 45.942051 -212.289962) (xy 45.987019 -212.277236) (xy 46.028902 -212.256504)
			(xy 46.047914 -212.242908) (xy 46.069987 -212.226928) (xy 46.117812 -212.200807) (xy 46.168868 -212.181759)
			(xy 46.222116 -212.170171) (xy 46.27647 -212.166279) (xy 46.330825 -212.170163) (xy 46.384075 -212.181742)
			(xy 46.435134 -212.200782) (xy 46.482963 -212.226896) (xy 46.526589 -212.25955) (xy 46.565124 -212.298081)
			(xy 46.597783 -212.341704) (xy 46.623901 -212.389531) (xy 46.642947 -212.440588) (xy 46.654532 -212.493836)
			(xy 46.658421 -212.54819) (xy 46.654535 -212.602545) (xy 46.642952 -212.655794) (xy 46.623909 -212.706852)
			(xy 46.597794 -212.75468) (xy 46.565137 -212.798305) (xy 46.526604 -212.836837) (xy 46.482979 -212.869494)
			(xy 46.435151 -212.89561) (xy 46.384093 -212.914652) (xy 46.330844 -212.926235) (xy 46.27649 -212.930121)
			(xy 46.222135 -212.926232) (xy 46.168887 -212.914646) (xy 46.11783 -212.895601) (xy 46.070003 -212.869483)
			(xy 46.047914 -212.853524) (xy 46.028902 -212.839928) (xy 45.987019 -212.819196) (xy 45.942051 -212.80647)
			(xy 45.895514 -212.80218) (xy 45.848977 -212.80647) (xy 45.804009 -212.819196) (xy 45.762126 -212.839928)
			(xy 45.743114 -212.853524) (xy 45.72101 -212.869464) (xy 45.673185 -212.895584) (xy 45.622129 -212.914633)
			(xy 45.568881 -212.926221) (xy 45.514526 -212.930112) (xy 45.460171 -212.926228) (xy 45.406922 -212.914648)
			(xy 45.355863 -212.895606) (xy 45.308034 -212.869492) (xy 45.264408 -212.836836) (xy 45.225875 -212.798304)
			(xy 45.193217 -212.75468) (xy 45.167101 -212.706852) (xy 45.148057 -212.655794) (xy 45.136474 -212.602545)
			(xy 45.132588 -212.54819) (xy 44.754411 -212.54819) (xy 44.750525 -212.602543) (xy 44.738943 -212.65579)
			(xy 44.719902 -212.706846) (xy 44.693787 -212.754672) (xy 44.661132 -212.798295) (xy 44.622601 -212.836827)
			(xy 44.578979 -212.869483) (xy 44.531153 -212.895598) (xy 44.480097 -212.914641) (xy 44.426851 -212.926224)
			(xy 44.372499 -212.930111) (xy 44.318146 -212.926224) (xy 44.2649 -212.91464) (xy 44.213844 -212.895597)
			(xy 44.166019 -212.869481) (xy 44.14393 -212.853524) (xy 44.124918 -212.839928) (xy 44.083035 -212.819196)
			(xy 44.038067 -212.80647) (xy 43.99153 -212.80218) (xy 43.944993 -212.80647) (xy 43.900025 -212.819196)
			(xy 43.858142 -212.839928) (xy 43.83913 -212.853524) (xy 43.817026 -212.869465) (xy 43.769199 -212.895588)
			(xy 43.718142 -212.914639) (xy 43.664892 -212.926229) (xy 43.610536 -212.930122) (xy 43.556178 -212.926239)
			(xy 43.502926 -212.914659) (xy 43.451865 -212.895618) (xy 43.404034 -212.869503) (xy 43.360406 -212.836847)
			(xy 43.32187 -212.798314) (xy 43.289211 -212.754688) (xy 43.263093 -212.706858) (xy 43.244048 -212.655798)
			(xy 43.232465 -212.602548) (xy 43.228578 -212.54819) (xy 42.513437 -212.54819) (xy 42.50955 -212.602549)
			(xy 42.497966 -212.655801) (xy 42.478922 -212.706862) (xy 42.452804 -212.754693) (xy 42.420144 -212.79832)
			(xy 42.381608 -212.836855) (xy 42.33798 -212.869512) (xy 42.290148 -212.895628) (xy 42.239086 -212.914671)
			(xy 42.185833 -212.926252) (xy 42.131475 -212.930137) (xy 42.077117 -212.926245) (xy 42.023866 -212.914657)
			(xy 41.972806 -212.895607) (xy 41.924978 -212.869485) (xy 41.902888 -212.853524) (xy 41.883876 -212.839928)
			(xy 41.841993 -212.819196) (xy 41.797025 -212.80647) (xy 41.750488 -212.80218) (xy 41.703951 -212.80647)
			(xy 41.658983 -212.819196) (xy 41.6171 -212.839928) (xy 41.598088 -212.853524) (xy 41.575985 -212.869461)
			(xy 41.528161 -212.895578) (xy 41.477108 -212.914623) (xy 41.423863 -212.926207) (xy 41.369512 -212.930097)
			(xy 41.31516 -212.926211) (xy 41.261915 -212.914629) (xy 41.21086 -212.895588) (xy 41.163034 -212.869474)
			(xy 41.119412 -212.836819) (xy 41.080882 -212.798289) (xy 41.048227 -212.754667) (xy 41.022113 -212.706842)
			(xy 41.003071 -212.655787) (xy 40.99149 -212.602542) (xy 40.987603 -212.54819) (xy 40.626744 -212.54819)
			(xy 40.622857 -212.602551) (xy 40.611273 -212.655804) (xy 40.592227 -212.706867) (xy 40.566108 -212.754699)
			(xy 40.533448 -212.798327) (xy 40.49491 -212.836862) (xy 40.45128 -212.869521) (xy 40.403446 -212.895637)
			(xy 40.352382 -212.914679) (xy 40.299128 -212.92626) (xy 40.244768 -212.930144) (xy 40.190408 -212.926251)
			(xy 40.137156 -212.914661) (xy 40.086095 -212.89561) (xy 40.038266 -212.869486) (xy 40.016176 -212.853524)
			(xy 39.997164 -212.839928) (xy 39.955281 -212.819196) (xy 39.910313 -212.80647) (xy 39.863776 -212.80218)
			(xy 39.817239 -212.80647) (xy 39.772271 -212.819196) (xy 39.730388 -212.839928) (xy 39.711376 -212.853524)
			(xy 39.689273 -212.86946) (xy 39.64145 -212.895575) (xy 39.590398 -212.914618) (xy 39.537155 -212.926201)
			(xy 39.482805 -212.930089) (xy 39.428455 -212.926203) (xy 39.375211 -212.914621) (xy 39.324158 -212.895579)
			(xy 39.276335 -212.869466) (xy 39.232714 -212.836812) (xy 39.194185 -212.798282) (xy 39.161532 -212.754661)
			(xy 39.135419 -212.706837) (xy 39.116378 -212.655784) (xy 39.104797 -212.60254) (xy 39.100911 -212.54819)
			(xy 36.190781 -212.54819) (xy 36.140713 -212.593833) (xy 36.071366 -212.646202) (xy 35.997482 -212.691949)
			(xy 35.919693 -212.730683) (xy 35.838661 -212.762075) (xy 35.755079 -212.785856) (xy 35.669659 -212.801824)
			(xy 35.58313 -212.809842) (xy 35.49623 -212.809842) (xy 35.409701 -212.801824) (xy 35.324281 -212.785856)
			(xy 35.240699 -212.762075) (xy 35.159667 -212.730683) (xy 35.081878 -212.691949) (xy 35.007994 -212.646202)
			(xy 34.938647 -212.593833) (xy 34.874427 -212.535289) (xy 34.815883 -212.471069) (xy 34.763514 -212.401722)
			(xy 34.717767 -212.327838) (xy 34.679033 -212.250049) (xy 34.647641 -212.169017) (xy 34.62386 -212.085435)
			(xy 34.607892 -212.000015) (xy 34.599874 -211.913486) (xy 31.398502 -211.913486) (xy 31.396473 -211.957185)
			(xy 31.384359 -212.043638) (xy 31.364285 -212.128596) (xy 31.336422 -212.211327) (xy 31.301011 -212.29112)
			(xy 31.258356 -212.367287) (xy 31.208825 -212.439172) (xy 31.152845 -212.506157) (xy 31.090896 -212.567665)
			(xy 31.023514 -212.623166) (xy 30.951277 -212.672183) (xy 30.874808 -212.714293) (xy 30.794764 -212.749134)
			(xy 30.711836 -212.776406) (xy 30.626738 -212.795875) (xy 30.540201 -212.807371) (xy 30.452971 -212.810798)
			(xy 30.365799 -212.806124) (xy 30.279435 -212.79339) (xy 30.194624 -212.772707) (xy 30.112094 -212.744251)
			(xy 30.032558 -212.708269) (xy 29.994352 -212.687154) (xy 29.974901 -212.676653) (xy 29.93327 -212.6618)
			(xy 29.889698 -212.654376) (xy 29.845499 -212.654603) (xy 29.802005 -212.662474) (xy 29.76053 -212.677753)
			(xy 29.722324 -212.699978) (xy 29.68854 -212.728478) (xy 29.660197 -212.762395) (xy 29.63815 -212.800704)
			(xy 29.623065 -212.84225) (xy 29.615396 -212.88578) (xy 29.614876 -212.90788) (xy 29.614876 -213.372192)
			(xy 29.615344 -213.394304) (xy 29.622984 -213.437863) (xy 29.638052 -213.479442) (xy 29.660092 -213.517782)
			(xy 29.688439 -213.551727) (xy 29.722236 -213.580249) (xy 29.760462 -213.602488) (xy 29.801961 -213.617772)
			(xy 29.84548 -213.625638) (xy 29.889703 -213.625849) (xy 29.933295 -213.618398) (xy 29.974938 -213.603511)
			(xy 29.994352 -213.592918) (xy 30.033232 -213.571371) (xy 30.114286 -213.534864) (xy 30.198424 -213.50617)
			(xy 30.284894 -213.485545) (xy 30.372926 -213.473173) (xy 30.461732 -213.469165) (xy 30.550519 -213.473557)
			(xy 30.638496 -213.486308) (xy 30.724877 -213.507307) (xy 30.80889 -213.536364) (xy 30.889786 -213.57322)
			(xy 30.928564 -213.59495) (xy 30.947047 -213.605723) (xy 30.98313 -213.628718) (xy 31.0007 -213.640924)
			(xy 31.033106 -213.664227) (xy 31.094279 -213.715511) (xy 31.150884 -213.771796) (xy 31.202513 -213.832677)
			(xy 31.225998 -213.864952) (xy 31.250643 -213.900444) (xy 31.29406 -213.975158) (xy 31.330439 -214.053541)
			(xy 31.359474 -214.13493) (xy 31.380919 -214.21864) (xy 31.394594 -214.303964) (xy 31.400383 -214.390183)
			(xy 31.39881 -214.453486) (xy 34.599874 -214.453486) (xy 34.599874 -214.366586) (xy 34.607892 -214.280057)
			(xy 34.62386 -214.194637) (xy 34.647641 -214.111055) (xy 34.679033 -214.030023) (xy 34.717767 -213.952234)
			(xy 34.763514 -213.87835) (xy 34.815883 -213.809003) (xy 34.874427 -213.744783) (xy 34.938647 -213.686239)
			(xy 35.007994 -213.63387) (xy 35.081878 -213.588123) (xy 35.159667 -213.549389) (xy 35.240699 -213.517997)
			(xy 35.324281 -213.494216) (xy 35.409701 -213.478248) (xy 35.49623 -213.47023) (xy 35.58313 -213.47023)
			(xy 35.669659 -213.478248) (xy 35.755079 -213.494216) (xy 35.838661 -213.517997) (xy 35.919693 -213.549389)
			(xy 35.997482 -213.588123) (xy 36.071366 -213.63387) (xy 36.140713 -213.686239) (xy 36.204933 -213.744783)
			(xy 36.263477 -213.809003) (xy 36.315846 -213.87835) (xy 36.361593 -213.952234) (xy 36.400327 -214.030023)
			(xy 36.431719 -214.111055) (xy 36.4555 -214.194637) (xy 36.471468 -214.280057) (xy 36.479486 -214.366586)
			(xy 36.479988 -214.410036) (xy 36.479486 -214.453486) (xy 36.471468 -214.540015) (xy 36.467843 -214.559407)
			(xy 39.057349 -214.559407) (xy 39.061236 -214.505045) (xy 39.072821 -214.45179) (xy 39.091868 -214.400725)
			(xy 39.117988 -214.352892) (xy 39.150651 -214.309263) (xy 39.189191 -214.270727) (xy 39.232823 -214.238068)
			(xy 39.28066 -214.211952) (xy 39.331726 -214.19291) (xy 39.384982 -214.181331) (xy 39.439345 -214.177449)
			(xy 39.493706 -214.181343) (xy 39.54696 -214.192936) (xy 39.598022 -214.211989) (xy 39.645852 -214.238117)
			(xy 39.667942 -214.25408) (xy 39.686954 -214.267676) (xy 39.728837 -214.288408) (xy 39.773805 -214.301134)
			(xy 39.820342 -214.305424) (xy 39.866879 -214.301134) (xy 39.911847 -214.288408) (xy 39.95373 -214.267676)
			(xy 39.972742 -214.25408) (xy 39.99484 -214.23814) (xy 40.042662 -214.212027) (xy 40.093714 -214.192987)
			(xy 40.146955 -214.181405) (xy 40.201303 -214.177518) (xy 40.255651 -214.181406) (xy 40.308892 -214.192988)
			(xy 40.359943 -214.21203) (xy 40.407765 -214.238143) (xy 40.451383 -214.270796) (xy 40.48991 -214.309325)
			(xy 40.522562 -214.352944) (xy 40.548674 -214.400766) (xy 40.567715 -214.451818) (xy 40.579296 -214.505059)
			(xy 40.583182 -214.559407) (xy 40.944201 -214.559407) (xy 40.948088 -214.505057) (xy 40.959669 -214.451813)
			(xy 40.97871 -214.40076) (xy 41.004823 -214.352936) (xy 41.037476 -214.309314) (xy 41.076005 -214.270784)
			(xy 41.119625 -214.23813) (xy 41.167448 -214.212015) (xy 41.218501 -214.192973) (xy 41.271745 -214.181389)
			(xy 41.326095 -214.177501) (xy 41.380445 -214.181388) (xy 41.433688 -214.19297) (xy 41.484742 -214.212011)
			(xy 41.532566 -214.238124) (xy 41.554654 -214.25408) (xy 41.573666 -214.267676) (xy 41.615549 -214.288408)
			(xy 41.660517 -214.301134) (xy 41.707054 -214.305424) (xy 41.753591 -214.301134) (xy 41.798559 -214.288408)
			(xy 41.840442 -214.267676) (xy 41.859454 -214.25408) (xy 41.881555 -214.238132) (xy 41.929382 -214.212006)
			(xy 41.980442 -214.192953) (xy 42.033694 -214.18136) (xy 42.088053 -214.177466) (xy 42.142413 -214.181347)
			(xy 42.195668 -214.192926) (xy 42.246732 -214.211967) (xy 42.294566 -214.238082) (xy 42.338197 -214.270739)
			(xy 42.376735 -214.309273) (xy 42.409397 -214.3529) (xy 42.435517 -214.400732) (xy 42.454563 -214.451794)
			(xy 42.466147 -214.505047) (xy 42.470034 -214.559407) (xy 43.185176 -214.559407) (xy 43.189063 -214.505051)
			(xy 43.200646 -214.451802) (xy 43.21969 -214.400743) (xy 43.245806 -214.352915) (xy 43.278464 -214.30929)
			(xy 43.316998 -214.270757) (xy 43.360624 -214.2381) (xy 43.408454 -214.211985) (xy 43.459513 -214.192943)
			(xy 43.512763 -214.181361) (xy 43.567119 -214.177476) (xy 43.621474 -214.181367) (xy 43.674723 -214.192953)
			(xy 43.72578 -214.212001) (xy 43.773607 -214.23812) (xy 43.795696 -214.25408) (xy 43.814708 -214.267676)
			(xy 43.856591 -214.288408) (xy 43.901559 -214.301134) (xy 43.948096 -214.305424) (xy 43.994633 -214.301134)
			(xy 44.039601 -214.288408) (xy 44.081484 -214.267676) (xy 44.100496 -214.25408) (xy 44.122596 -214.238136)
			(xy 44.170421 -214.212016) (xy 44.221476 -214.192969) (xy 44.274723 -214.181382) (xy 44.329077 -214.177491)
			(xy 44.383431 -214.181375) (xy 44.436679 -214.192956) (xy 44.487737 -214.211997) (xy 44.535566 -214.238111)
			(xy 44.57919 -214.270766) (xy 44.617723 -214.309298) (xy 44.65038 -214.352921) (xy 44.676496 -214.400748)
			(xy 44.69554 -214.451805) (xy 44.707123 -214.505053) (xy 44.711009 -214.559407) (xy 45.089186 -214.559407)
			(xy 45.093072 -214.505054) (xy 45.104655 -214.451806) (xy 45.123698 -214.40075) (xy 45.149813 -214.352923)
			(xy 45.182469 -214.309299) (xy 45.221001 -214.270767) (xy 45.264624 -214.238112) (xy 45.312452 -214.211997)
			(xy 45.363509 -214.192954) (xy 45.416756 -214.181372) (xy 45.471109 -214.177486) (xy 45.525463 -214.181375)
			(xy 45.57871 -214.19296) (xy 45.629766 -214.212004) (xy 45.677591 -214.238122) (xy 45.69968 -214.25408)
			(xy 45.718692 -214.267676) (xy 45.760575 -214.288408) (xy 45.805543 -214.301134) (xy 45.85208 -214.305424)
			(xy 45.898617 -214.301134) (xy 45.943585 -214.288408) (xy 45.985468 -214.267676) (xy 46.00448 -214.25408)
			(xy 46.02658 -214.238135) (xy 46.074406 -214.212012) (xy 46.125463 -214.192963) (xy 46.178712 -214.181374)
			(xy 46.233068 -214.177481) (xy 46.287424 -214.181364) (xy 46.340675 -214.192944) (xy 46.391735 -214.211985)
			(xy 46.439566 -214.2381) (xy 46.483193 -214.270756) (xy 46.521728 -214.309288) (xy 46.554387 -214.352913)
			(xy 46.580504 -214.400742) (xy 46.599549 -214.451801) (xy 46.611132 -214.505051) (xy 46.615019 -214.559407)
			(xy 46.61113 -214.613763) (xy 46.599544 -214.667013) (xy 46.580498 -214.718071) (xy 46.554379 -214.765899)
			(xy 46.521719 -214.809523) (xy 46.483182 -214.848054) (xy 46.439554 -214.880708) (xy 46.391722 -214.906821)
			(xy 46.340661 -214.92586) (xy 46.28741 -214.937438) (xy 46.233053 -214.941319) (xy 46.178698 -214.937424)
			(xy 46.125449 -214.925833) (xy 46.074393 -214.906782) (xy 46.026568 -214.880658) (xy 46.00448 -214.864696)
			(xy 45.985468 -214.8511) (xy 45.943585 -214.830368) (xy 45.898617 -214.817642) (xy 45.85208 -214.813352)
			(xy 45.805543 -214.817642) (xy 45.760575 -214.830368) (xy 45.718692 -214.8511) (xy 45.69968 -214.864696)
			(xy 45.677604 -214.88067) (xy 45.629779 -214.90679) (xy 45.578723 -214.925836) (xy 45.525477 -214.937423)
			(xy 45.471124 -214.941314) (xy 45.41677 -214.93743) (xy 45.363522 -214.92585) (xy 45.312465 -214.906809)
			(xy 45.264637 -214.880696) (xy 45.221012 -214.848042) (xy 45.182478 -214.809512) (xy 45.149821 -214.76589)
			(xy 45.123704 -214.718064) (xy 45.104659 -214.667007) (xy 45.093074 -214.613761) (xy 45.089186 -214.559407)
			(xy 44.711009 -214.559407) (xy 44.707121 -214.613761) (xy 44.695536 -214.667008) (xy 44.676491 -214.718065)
			(xy 44.650373 -214.765891) (xy 44.617714 -214.809513) (xy 44.579179 -214.848043) (xy 44.535553 -214.880697)
			(xy 44.487724 -214.906809) (xy 44.436666 -214.925848) (xy 44.383417 -214.937427) (xy 44.329062 -214.941309)
			(xy 44.274709 -214.937416) (xy 44.221462 -214.925827) (xy 44.170407 -214.906778) (xy 44.122583 -214.880656)
			(xy 44.100496 -214.864696) (xy 44.081484 -214.8511) (xy 44.039601 -214.830368) (xy 43.994633 -214.817642)
			(xy 43.948096 -214.813352) (xy 43.901559 -214.817642) (xy 43.856591 -214.830368) (xy 43.814708 -214.8511)
			(xy 43.795696 -214.864696) (xy 43.773619 -214.880672) (xy 43.725793 -214.906793) (xy 43.674736 -214.925843)
			(xy 43.621488 -214.937431) (xy 43.567133 -214.941324) (xy 43.512777 -214.937441) (xy 43.459527 -214.925861)
			(xy 43.408467 -214.906821) (xy 43.360636 -214.880707) (xy 43.317009 -214.848053) (xy 43.278474 -214.809521)
			(xy 43.245814 -214.765897) (xy 43.219696 -214.71807) (xy 43.20065 -214.667012) (xy 43.189065 -214.613763)
			(xy 43.185176 -214.559407) (xy 42.470034 -214.559407) (xy 42.466145 -214.613767) (xy 42.454559 -214.66702)
			(xy 42.435511 -214.718081) (xy 42.409389 -214.765912) (xy 42.376726 -214.809538) (xy 42.338186 -214.848071)
			(xy 42.294554 -214.880726) (xy 42.246719 -214.906839) (xy 42.195654 -214.925878) (xy 42.142399 -214.937455)
			(xy 42.088039 -214.941334) (xy 42.033679 -214.937437) (xy 41.980428 -214.925843) (xy 41.929369 -214.906788)
			(xy 41.881542 -214.88066) (xy 41.859454 -214.864696) (xy 41.840442 -214.8511) (xy 41.798559 -214.830368)
			(xy 41.753591 -214.817642) (xy 41.707054 -214.813352) (xy 41.660517 -214.817642) (xy 41.615549 -214.830368)
			(xy 41.573666 -214.8511) (xy 41.554654 -214.864696) (xy 41.532578 -214.880668) (xy 41.484755 -214.906783)
			(xy 41.433702 -214.925826) (xy 41.380459 -214.93741) (xy 41.326109 -214.941299) (xy 41.271759 -214.937413)
			(xy 41.218515 -214.925831) (xy 41.167461 -214.906791) (xy 41.119637 -214.880678) (xy 41.076016 -214.848025)
			(xy 41.037486 -214.809496) (xy 41.004831 -214.765877) (xy 40.978716 -214.718053) (xy 40.959673 -214.667)
			(xy 40.94809 -214.613757) (xy 40.944201 -214.559407) (xy 40.583182 -214.559407) (xy 40.579294 -214.613755)
			(xy 40.567711 -214.666996) (xy 40.548668 -214.718047) (xy 40.522555 -214.765868) (xy 40.489901 -214.809486)
			(xy 40.451372 -214.848013) (xy 40.407753 -214.880665) (xy 40.35993 -214.906776) (xy 40.308878 -214.925816)
			(xy 40.255637 -214.937396) (xy 40.201289 -214.941282) (xy 40.146941 -214.937393) (xy 40.0937 -214.925809)
			(xy 40.042649 -214.906767) (xy 39.994828 -214.880652) (xy 39.972742 -214.864696) (xy 39.95373 -214.8511)
			(xy 39.911847 -214.830368) (xy 39.866879 -214.817642) (xy 39.820342 -214.813352) (xy 39.773805 -214.817642)
			(xy 39.728837 -214.830368) (xy 39.686954 -214.8511) (xy 39.667942 -214.864696) (xy 39.645864 -214.880676)
			(xy 39.598035 -214.906805) (xy 39.546974 -214.92586) (xy 39.493721 -214.937454) (xy 39.439359 -214.941351)
			(xy 39.384997 -214.937471) (xy 39.33174 -214.925894) (xy 39.280673 -214.906854) (xy 39.232835 -214.88074)
			(xy 39.189202 -214.848083) (xy 39.150661 -214.809548) (xy 39.117996 -214.76592) (xy 39.091874 -214.718088)
			(xy 39.072825 -214.667024) (xy 39.061238 -214.613769) (xy 39.057349 -214.559407) (xy 36.467843 -214.559407)
			(xy 36.4555 -214.625435) (xy 36.431719 -214.709017) (xy 36.400327 -214.790049) (xy 36.361593 -214.867838)
			(xy 36.315846 -214.941722) (xy 36.263477 -215.011069) (xy 36.204933 -215.075289) (xy 36.140713 -215.133833)
			(xy 36.071366 -215.186202) (xy 35.997482 -215.231949) (xy 35.919693 -215.270683) (xy 35.838661 -215.302075)
			(xy 35.755079 -215.325856) (xy 35.669659 -215.341824) (xy 35.58313 -215.349842) (xy 35.49623 -215.349842)
			(xy 35.409701 -215.341824) (xy 35.324281 -215.325856) (xy 35.240699 -215.302075) (xy 35.159667 -215.270683)
			(xy 35.081878 -215.231949) (xy 35.007994 -215.186202) (xy 34.938647 -215.133833) (xy 34.874427 -215.075289)
			(xy 34.815883 -215.011069) (xy 34.763514 -214.941722) (xy 34.717767 -214.867838) (xy 34.679033 -214.790049)
			(xy 34.647641 -214.709017) (xy 34.62386 -214.625435) (xy 34.607892 -214.540015) (xy 34.599874 -214.453486)
			(xy 31.39881 -214.453486) (xy 31.398237 -214.47657) (xy 31.388175 -214.562395) (xy 31.370281 -214.646936)
			(xy 31.344707 -214.729478) (xy 31.311668 -214.809325) (xy 31.271442 -214.885805) (xy 31.22437 -214.958272)
			(xy 31.170847 -215.026114) (xy 31.111326 -215.08876) (xy 31.046309 -215.145681) (xy 30.976344 -215.196397)
			(xy 30.902021 -215.24048) (xy 30.823967 -215.277558) (xy 30.74284 -215.307319) (xy 30.659325 -215.329511)
			(xy 30.574126 -215.343948) (xy 30.487963 -215.350508) (xy 30.40156 -215.349134) (xy 30.315648 -215.339839)
			(xy 30.230952 -215.322702) (xy 30.148184 -215.297866) (xy 30.068044 -215.265542) (xy 30.029404 -215.246204)
			(xy 29.996168 -215.228699) (xy 29.932316 -215.189119) (xy 29.87183 -215.144565) (xy 29.843222 -215.12022)
			(xy 29.826712 -215.105742) (xy 29.78785 -215.090502) (xy 29.773311 -215.085323) (xy 29.742705 -215.081396)
			(xy 29.712053 -215.084936) (xy 29.683148 -215.095736) (xy 29.657685 -215.113163) (xy 29.637153 -215.136196)
			(xy 29.622755 -215.163487) (xy 29.615335 -215.193438) (xy 29.614876 -215.208866) (xy 29.614876 -215.39327)
			(xy 29.638498 -215.42629) (xy 29.655806 -215.451325) (xy 29.68467 -215.50491) (xy 29.706573 -215.561697)
			(xy 29.721169 -215.620786) (xy 29.728226 -215.68124) (xy 29.727631 -215.742101) (xy 29.719396 -215.802406)
			(xy 29.70365 -215.861198) (xy 29.680642 -215.917546) (xy 29.650737 -215.970558) (xy 29.61441 -216.019392)
			(xy 29.572235 -216.063276) (xy 29.524881 -216.101513) (xy 29.473099 -216.133499) (xy 29.417708 -216.158725)
			(xy 29.359588 -216.176793) (xy 29.299657 -216.187416) (xy 29.238867 -216.190426) (xy 29.178181 -216.185775)
			(xy 29.118559 -216.173536) (xy 29.089604 -216.16416) (xy 29.068686 -216.157532) (xy 29.025336 -216.150745)
			(xy 28.981465 -216.151506) (xy 28.938378 -216.159793) (xy 28.897354 -216.175359) (xy 28.859614 -216.19774)
			(xy 28.826281 -216.226273) (xy 28.798344 -216.260107) (xy 28.776636 -216.298238) (xy 28.7618 -216.339531)
			(xy 28.754279 -216.382759) (xy 28.753816 -216.404698) (xy 28.753816 -216.993486) (xy 29.519874 -216.993486)
			(xy 29.519874 -216.906586) (xy 29.527892 -216.820057) (xy 29.54386 -216.734637) (xy 29.567641 -216.651055)
			(xy 29.599033 -216.570023) (xy 29.637767 -216.492234) (xy 29.683514 -216.41835) (xy 29.735883 -216.349003)
			(xy 29.794427 -216.284783) (xy 29.858647 -216.226239) (xy 29.927994 -216.17387) (xy 30.001878 -216.128123)
			(xy 30.079667 -216.089389) (xy 30.160699 -216.057997) (xy 30.244281 -216.034216) (xy 30.329701 -216.018248)
			(xy 30.41623 -216.01023) (xy 30.50313 -216.01023) (xy 30.589659 -216.018248) (xy 30.675079 -216.034216)
			(xy 30.758661 -216.057997) (xy 30.839693 -216.089389) (xy 30.917482 -216.128123) (xy 30.991366 -216.17387)
			(xy 31.060713 -216.226239) (xy 31.124933 -216.284783) (xy 31.183477 -216.349003) (xy 31.235846 -216.41835)
			(xy 31.281593 -216.492234) (xy 31.320327 -216.570023) (xy 31.351719 -216.651055) (xy 31.3755 -216.734637)
			(xy 31.391468 -216.820057) (xy 31.399486 -216.906586) (xy 31.399988 -216.950036) (xy 31.399486 -216.993486)
			(xy 34.599874 -216.993486) (xy 34.599874 -216.906586) (xy 34.607892 -216.820057) (xy 34.62386 -216.734637)
			(xy 34.647641 -216.651055) (xy 34.679033 -216.570023) (xy 34.717767 -216.492234) (xy 34.763514 -216.41835)
			(xy 34.815883 -216.349003) (xy 34.874427 -216.284783) (xy 34.938647 -216.226239) (xy 35.007994 -216.17387)
			(xy 35.081878 -216.128123) (xy 35.159667 -216.089389) (xy 35.240699 -216.057997) (xy 35.324281 -216.034216)
			(xy 35.409701 -216.018248) (xy 35.49623 -216.01023) (xy 35.58313 -216.01023) (xy 35.669659 -216.018248)
			(xy 35.755079 -216.034216) (xy 35.838661 -216.057997) (xy 35.919693 -216.089389) (xy 35.997482 -216.128123)
			(xy 36.071366 -216.17387) (xy 36.140713 -216.226239) (xy 36.204933 -216.284783) (xy 36.263477 -216.349003)
			(xy 36.315846 -216.41835) (xy 36.335377 -216.449894) (xy 39.057366 -216.449894) (xy 39.061255 -216.395535)
			(xy 39.072842 -216.342282) (xy 39.091889 -216.291221) (xy 39.11801 -216.24339) (xy 39.150673 -216.199764)
			(xy 39.189213 -216.161231) (xy 39.232844 -216.128576) (xy 39.280679 -216.102463) (xy 39.331743 -216.083424)
			(xy 39.384998 -216.071846) (xy 39.439358 -216.067966) (xy 39.493717 -216.071863) (xy 39.546968 -216.083456)
			(xy 39.598027 -216.102511) (xy 39.645854 -216.128638) (xy 39.667942 -216.144602) (xy 39.686954 -216.158198)
			(xy 39.728837 -216.17893) (xy 39.773805 -216.191656) (xy 39.820342 -216.195946) (xy 39.866879 -216.191656)
			(xy 39.911847 -216.17893) (xy 39.95373 -216.158198) (xy 39.972742 -216.144602) (xy 39.99482 -216.128632)
			(xy 40.042643 -216.102517) (xy 40.093696 -216.083473) (xy 40.14694 -216.071889) (xy 40.20129 -216.068001)
			(xy 40.25564 -216.071886) (xy 40.308884 -216.083468) (xy 40.359939 -216.102508) (xy 40.407763 -216.128621)
			(xy 40.451385 -216.161274) (xy 40.489915 -216.199803) (xy 40.52257 -216.243423) (xy 40.548685 -216.291247)
			(xy 40.567728 -216.3423) (xy 40.579311 -216.395544) (xy 40.583199 -216.449894) (xy 40.944219 -216.449894)
			(xy 40.948107 -216.395547) (xy 40.95969 -216.342306) (xy 40.978732 -216.291255) (xy 41.004845 -216.243434)
			(xy 41.037498 -216.199816) (xy 41.076026 -216.161289) (xy 41.119646 -216.128637) (xy 41.167468 -216.102526)
			(xy 41.218519 -216.083486) (xy 41.27176 -216.071905) (xy 41.326108 -216.068019) (xy 41.380455 -216.071907)
			(xy 41.433696 -216.08349) (xy 41.484747 -216.102532) (xy 41.532568 -216.128646) (xy 41.554654 -216.144602)
			(xy 41.573666 -216.158198) (xy 41.615549 -216.17893) (xy 41.660517 -216.191656) (xy 41.707054 -216.195946)
			(xy 41.753591 -216.191656) (xy 41.798559 -216.17893) (xy 41.840442 -216.158198) (xy 41.859454 -216.144602)
			(xy 41.881534 -216.128625) (xy 41.929363 -216.102495) (xy 41.980424 -216.083439) (xy 42.033678 -216.071845)
			(xy 42.08804 -216.067948) (xy 42.142403 -216.071828) (xy 42.19566 -216.083405) (xy 42.246727 -216.102445)
			(xy 42.294565 -216.12856) (xy 42.338199 -216.161217) (xy 42.37674 -216.199751) (xy 42.409405 -216.243379)
			(xy 42.435527 -216.291212) (xy 42.454576 -216.342276) (xy 42.466163 -216.395532) (xy 42.470052 -216.449894)
			(xy 43.185194 -216.449894) (xy 43.189082 -216.395541) (xy 43.200667 -216.342294) (xy 43.219711 -216.291239)
			(xy 43.245828 -216.243413) (xy 43.278486 -216.199791) (xy 43.31702 -216.161261) (xy 43.360645 -216.128608)
			(xy 43.408473 -216.102496) (xy 43.459531 -216.083456) (xy 43.512778 -216.071877) (xy 43.567132 -216.067994)
			(xy 43.621485 -216.071886) (xy 43.67473 -216.083474) (xy 43.725785 -216.102522) (xy 43.773609 -216.128642)
			(xy 43.795696 -216.144602) (xy 43.814708 -216.158198) (xy 43.856591 -216.17893) (xy 43.901559 -216.191656)
			(xy 43.948096 -216.195946) (xy 43.994633 -216.191656) (xy 44.039601 -216.17893) (xy 44.081484 -216.158198)
			(xy 44.100496 -216.144602) (xy 44.122575 -216.128628) (xy 44.170401 -216.102506) (xy 44.221459 -216.083456)
			(xy 44.274707 -216.071866) (xy 44.329064 -216.067973) (xy 44.383421 -216.071856) (xy 44.436672 -216.083435)
			(xy 44.487733 -216.102475) (xy 44.535564 -216.128589) (xy 44.579192 -216.161244) (xy 44.617728 -216.199776)
			(xy 44.650388 -216.2434) (xy 44.676507 -216.291229) (xy 44.695553 -216.342288) (xy 44.707138 -216.395537)
			(xy 44.711027 -216.449894) (xy 45.089203 -216.449894) (xy 45.093092 -216.395543) (xy 45.104676 -216.342299)
			(xy 45.123719 -216.291245) (xy 45.149835 -216.243421) (xy 45.182491 -216.199801) (xy 45.221022 -216.161272)
			(xy 45.264645 -216.128619) (xy 45.312471 -216.102507) (xy 45.363526 -216.083467) (xy 45.416771 -216.071888)
			(xy 45.471123 -216.068003) (xy 45.525473 -216.071894) (xy 45.578717 -216.08348) (xy 45.62977 -216.102526)
			(xy 45.677593 -216.128644) (xy 45.69968 -216.144602) (xy 45.718692 -216.158198) (xy 45.760575 -216.17893)
			(xy 45.805543 -216.191656) (xy 45.85208 -216.195946) (xy 45.898617 -216.191656) (xy 45.943585 -216.17893)
			(xy 45.985468 -216.158198) (xy 46.00448 -216.144602) (xy 46.026559 -216.128627) (xy 46.074387 -216.102502)
			(xy 46.125446 -216.083449) (xy 46.178696 -216.071858) (xy 46.233055 -216.067963) (xy 46.287414 -216.071845)
			(xy 46.340667 -216.083424) (xy 46.391731 -216.102464) (xy 46.439564 -216.128578) (xy 46.483194 -216.161234)
			(xy 46.521733 -216.199767) (xy 46.533678 -216.215722) (xy 66.59372 -216.215722) (xy 66.59372 -215.227916)
			(xy 66.594214 -215.196776) (xy 66.601811 -215.134961) (xy 66.616903 -215.074537) (xy 66.639266 -215.01641)
			(xy 66.668564 -214.961451) (xy 66.704358 -214.910485) (xy 66.746111 -214.864273) (xy 66.793198 -214.82351)
			(xy 66.844913 -214.788807) (xy 66.900482 -214.760682) (xy 66.95907 -214.739559) (xy 67.019801 -214.725752)
			(xy 67.081763 -214.71947) (xy 67.144029 -214.720807) (xy 67.205665 -214.729742) (xy 67.265747 -214.746141)
			(xy 67.323375 -214.769759) (xy 67.377686 -214.800242) (xy 67.427864 -214.837133) (xy 67.473159 -214.879878)
			(xy 67.493388 -214.903558) (xy 67.507442 -214.919955) (xy 67.540203 -214.948092) (xy 67.577251 -214.970284)
			(xy 67.617519 -214.98589) (xy 67.659845 -214.994461) (xy 67.703012 -214.995751) (xy 67.745774 -214.989722)
			(xy 67.786902 -214.976548) (xy 67.825208 -214.956608) (xy 67.859591 -214.930477) (xy 67.874642 -214.914988)
			(xy 67.896973 -214.891811) (xy 67.946494 -214.850701) (xy 68.000807 -214.816168) (xy 68.059044 -214.788766)
			(xy 68.120273 -214.768931) (xy 68.183516 -214.756983) (xy 68.24776 -214.75311) (xy 68.31198 -214.757377)
			(xy 68.375149 -214.769713) (xy 68.436255 -214.789922) (xy 68.494322 -214.817681) (xy 68.548423 -214.852546)
			(xy 68.59769 -214.89396) (xy 68.619878 -214.917274) (xy 68.635409 -214.933364) (xy 68.671043 -214.960379)
			(xy 68.710852 -214.980746) (xy 68.75361 -214.993836) (xy 68.797998 -214.999246) (xy 68.842648 -214.99681)
			(xy 68.886184 -214.986602) (xy 68.927263 -214.968937) (xy 68.96462 -214.94436) (xy 68.997103 -214.913628)
			(xy 69.010784 -214.895938) (xy 69.030341 -214.870247) (xy 69.074991 -214.823606) (xy 69.125188 -214.782994)
			(xy 69.180124 -214.749066) (xy 69.238914 -214.722368) (xy 69.300612 -214.703329) (xy 69.364224 -214.692257)
			(xy 69.428726 -214.68933) (xy 69.49308 -214.694594) (xy 69.556248 -214.707965) (xy 69.617215 -214.729228)
			(xy 69.674999 -214.75804) (xy 69.728669 -214.793938) (xy 69.77736 -214.836343) (xy 69.7992 -214.860124)
			(xy 69.815447 -214.877525) (xy 69.853195 -214.906525) (xy 69.89568 -214.927995) (xy 69.941418 -214.941184)
			(xy 69.988811 -214.945632) (xy 70.036204 -214.941184) (xy 70.081942 -214.927995) (xy 70.124427 -214.906525)
			(xy 70.162175 -214.877525) (xy 70.178422 -214.860124) (xy 70.200281 -214.836319) (xy 70.249025 -214.79388)
			(xy 70.302754 -214.75796) (xy 70.360602 -214.729138) (xy 70.421635 -214.707879) (xy 70.484871 -214.694526)
			(xy 70.549289 -214.689295) (xy 70.61385 -214.692268) (xy 70.677515 -214.703399) (xy 70.739255 -214.722508)
			(xy 70.798076 -214.749286) (xy 70.85303 -214.783303) (xy 70.90323 -214.82401) (xy 70.947867 -214.870749)
			(xy 70.986221 -214.922769) (xy 71.017673 -214.979229) (xy 71.041718 -215.03922) (xy 71.057966 -215.101774)
			(xy 71.066157 -215.165883) (xy 71.06666 -215.198198) (xy 71.06666 -216.215722) (xy 71.066128 -216.248457)
			(xy 71.057696 -216.313381) (xy 71.041 -216.376686) (xy 71.016317 -216.437325) (xy 70.984054 -216.494293)
			(xy 70.964806 -216.520776) (xy 70.93966 -216.554558) (xy 70.93966 -216.571576) (xy 70.924166 -216.571576)
			(xy 70.888352 -216.602056) (xy 70.863175 -216.622909) (xy 70.808443 -216.65866) (xy 70.749578 -216.687099)
			(xy 70.687553 -216.707754) (xy 70.623391 -216.720285) (xy 70.558152 -216.724485) (xy 70.492913 -216.720285)
			(xy 70.428751 -216.707754) (xy 70.366726 -216.687099) (xy 70.307861 -216.65866) (xy 70.253129 -216.622909)
			(xy 70.227952 -216.602056) (xy 70.192138 -216.571576) (xy 70.176644 -216.571576) (xy 70.176644 -216.554558)
			(xy 70.151498 -216.520776) (xy 70.137743 -216.501968) (xy 70.113318 -216.462284) (xy 70.10273 -216.441528)
			(xy 70.095372 -216.42761) (xy 70.075 -216.40362) (xy 70.049369 -216.385356) (xy 70.020043 -216.373932)
			(xy 69.988811 -216.370045) (xy 69.957579 -216.373932) (xy 69.928253 -216.385356) (xy 69.902622 -216.40362)
			(xy 69.88225 -216.42761) (xy 69.874892 -216.441528) (xy 69.864329 -216.462298) (xy 69.8399 -216.501983)
			(xy 69.826124 -216.520776) (xy 69.800724 -216.554558) (xy 69.800724 -216.571576) (xy 69.785484 -216.571576)
			(xy 69.74967 -216.602056) (xy 69.724493 -216.622909) (xy 69.669761 -216.65866) (xy 69.610896 -216.687099)
			(xy 69.548871 -216.707754) (xy 69.484709 -216.720285) (xy 69.41947 -216.724485) (xy 69.354231 -216.720285)
			(xy 69.290069 -216.707754) (xy 69.228044 -216.687099) (xy 69.169179 -216.65866) (xy 69.114447 -216.622909)
			(xy 69.08927 -216.602056) (xy 69.053456 -216.571576) (xy 69.038216 -216.571576) (xy 69.038216 -216.554558)
			(xy 69.012816 -216.520776) (xy 68.994177 -216.49514) (xy 68.962715 -216.440116) (xy 68.950078 -216.411048)
			(xy 68.94321 -216.395891) (xy 68.922957 -216.369505) (xy 68.896566 -216.349259) (xy 68.865835 -216.336531)
			(xy 68.832857 -216.33219) (xy 68.799879 -216.336531) (xy 68.769148 -216.349259) (xy 68.742757 -216.369505)
			(xy 68.722504 -216.395891) (xy 68.715636 -216.411048) (xy 68.702999 -216.440116) (xy 68.671538 -216.495141)
			(xy 68.652898 -216.520776) (xy 68.627752 -216.554558) (xy 68.627752 -216.571576) (xy 68.612258 -216.571576)
			(xy 68.576444 -216.602056) (xy 68.551267 -216.622909) (xy 68.496535 -216.65866) (xy 68.43767 -216.687099)
			(xy 68.375645 -216.707754) (xy 68.311483 -216.720285) (xy 68.246244 -216.724485) (xy 68.181005 -216.720285)
			(xy 68.116843 -216.707754) (xy 68.054818 -216.687099) (xy 67.995953 -216.65866) (xy 67.941221 -216.622909)
			(xy 67.916044 -216.602056) (xy 67.88023 -216.571576) (xy 67.864736 -216.571576) (xy 67.864736 -216.554558)
			(xy 67.83959 -216.520776) (xy 67.825064 -216.500945) (xy 67.799491 -216.458961) (xy 67.788536 -216.436956)
			(xy 67.781233 -216.422865) (xy 67.760865 -216.398539) (xy 67.735118 -216.38) (xy 67.705589 -216.368395)
			(xy 67.674109 -216.364446) (xy 67.642629 -216.368395) (xy 67.6131 -216.38) (xy 67.587353 -216.398539)
			(xy 67.566985 -216.422865) (xy 67.559682 -216.436956) (xy 67.54871 -216.458952) (xy 67.523139 -216.500935)
			(xy 67.508628 -216.520776) (xy 67.483228 -216.554558) (xy 67.483228 -216.571576) (xy 67.467988 -216.571576)
			(xy 67.432174 -216.602056) (xy 67.406997 -216.622909) (xy 67.352265 -216.65866) (xy 67.2934 -216.687099)
			(xy 67.231375 -216.707754) (xy 67.167213 -216.720285) (xy 67.101974 -216.724485) (xy 67.036735 -216.720285)
			(xy 66.972573 -216.707754) (xy 66.910548 -216.687099) (xy 66.851683 -216.65866) (xy 66.796951 -216.622909)
			(xy 66.771774 -216.602056) (xy 66.73596 -216.571576) (xy 66.72072 -216.571576) (xy 66.72072 -216.554558)
			(xy 66.69532 -216.520776) (xy 66.676064 -216.494306) (xy 66.64384 -216.437329) (xy 66.619206 -216.376683)
			(xy 66.602569 -216.313374) (xy 66.594205 -216.248452) (xy 66.59372 -216.215722) (xy 46.533678 -216.215722)
			(xy 46.554394 -216.243392) (xy 46.580515 -216.291223) (xy 46.599562 -216.342283) (xy 46.611148 -216.395535)
			(xy 46.615037 -216.449894) (xy 46.611149 -216.504253) (xy 46.599565 -216.557505) (xy 46.58052 -216.608566)
			(xy 46.554401 -216.656397) (xy 46.551728 -216.659968) (xy 51.342036 -216.659968) (xy 52.994052 -216.659968)
			(xy 52.994052 -218.311984) (xy 51.342036 -218.311984) (xy 51.342036 -216.659968) (xy 46.551728 -216.659968)
			(xy 46.521741 -216.700024) (xy 46.483204 -216.738559) (xy 46.439574 -216.771216) (xy 46.391742 -216.797331)
			(xy 46.340679 -216.816373) (xy 46.287426 -216.827953) (xy 46.233067 -216.831837) (xy 46.178708 -216.827944)
			(xy 46.125457 -216.816354) (xy 46.074398 -216.797303) (xy 46.026569 -216.77118) (xy 46.00448 -216.755218)
			(xy 45.985468 -216.741622) (xy 45.943585 -216.72089) (xy 45.898617 -216.708164) (xy 45.85208 -216.703874)
			(xy 45.805543 -216.708164) (xy 45.760575 -216.72089) (xy 45.718692 -216.741622) (xy 45.69968 -216.755218)
			(xy 45.677583 -216.771163) (xy 45.629759 -216.797279) (xy 45.578706 -216.816323) (xy 45.525462 -216.827908)
			(xy 45.471111 -216.831797) (xy 45.41676 -216.827911) (xy 45.363515 -216.816329) (xy 45.31246 -216.797288)
			(xy 45.264635 -216.771174) (xy 45.221013 -216.73852) (xy 45.182483 -216.69999) (xy 45.149828 -216.656369)
			(xy 45.123714 -216.608544) (xy 45.104672 -216.55749) (xy 45.09309 -216.504245) (xy 45.089203 -216.449894)
			(xy 44.711027 -216.449894) (xy 44.70714 -216.504251) (xy 44.695556 -216.557501) (xy 44.676512 -216.60856)
			(xy 44.650395 -216.65639) (xy 44.617736 -216.700015) (xy 44.579201 -216.738548) (xy 44.535574 -216.771205)
			(xy 44.487744 -216.79732) (xy 44.436683 -216.816361) (xy 44.383433 -216.827943) (xy 44.329076 -216.831827)
			(xy 44.274719 -216.827936) (xy 44.22147 -216.816348) (xy 44.170412 -216.797299) (xy 44.122585 -216.771178)
			(xy 44.100496 -216.755218) (xy 44.081484 -216.741622) (xy 44.039601 -216.72089) (xy 43.994633 -216.708164)
			(xy 43.948096 -216.703874) (xy 43.901559 -216.708164) (xy 43.856591 -216.72089) (xy 43.814708 -216.741622)
			(xy 43.795696 -216.755218) (xy 43.773599 -216.771164) (xy 43.725774 -216.797283) (xy 43.674719 -216.816329)
			(xy 43.621473 -216.827916) (xy 43.56712 -216.831806) (xy 43.512766 -216.827921) (xy 43.459519 -216.81634)
			(xy 43.408462 -216.797299) (xy 43.360635 -216.771185) (xy 43.317011 -216.738531) (xy 43.278478 -216.7)
			(xy 43.245822 -216.656377) (xy 43.219706 -216.60855) (xy 43.200663 -216.557494) (xy 43.189081 -216.504247)
			(xy 43.185194 -216.449894) (xy 42.470052 -216.449894) (xy 42.466165 -216.504256) (xy 42.454579 -216.557512)
			(xy 42.435532 -216.608577) (xy 42.409411 -216.65641) (xy 42.376748 -216.70004) (xy 42.338208 -216.738576)
			(xy 42.294575 -216.771234) (xy 42.246738 -216.79735) (xy 42.195672 -216.816391) (xy 42.142415 -216.827971)
			(xy 42.088052 -216.831852) (xy 42.03369 -216.827957) (xy 41.980436 -216.816364) (xy 41.929374 -216.79731)
			(xy 41.881544 -216.771182) (xy 41.859454 -216.755218) (xy 41.840442 -216.741622) (xy 41.798559 -216.72089)
			(xy 41.753591 -216.708164) (xy 41.707054 -216.703874) (xy 41.660517 -216.708164) (xy 41.615549 -216.72089)
			(xy 41.573666 -216.741622) (xy 41.554654 -216.755218) (xy 41.532558 -216.771161) (xy 41.484736 -216.797273)
			(xy 41.433685 -216.816313) (xy 41.380443 -216.827895) (xy 41.326096 -216.831781) (xy 41.271748 -216.827893)
			(xy 41.218507 -216.816311) (xy 41.167457 -216.797269) (xy 41.119636 -216.771156) (xy 41.076017 -216.738503)
			(xy 41.03749 -216.699975) (xy 41.004838 -216.656356) (xy 40.978727 -216.608534) (xy 40.959686 -216.557483)
			(xy 40.948105 -216.504242) (xy 40.944219 -216.449894) (xy 40.583199 -216.449894) (xy 40.579313 -216.504244)
			(xy 40.567731 -216.557488) (xy 40.54869 -216.608542) (xy 40.522577 -216.656367) (xy 40.489923 -216.699988)
			(xy 40.451394 -216.738518) (xy 40.407773 -216.771172) (xy 40.359949 -216.797287) (xy 40.308896 -216.816329)
			(xy 40.255652 -216.827912) (xy 40.201302 -216.831799) (xy 40.146952 -216.827912) (xy 40.093708 -216.81633)
			(xy 40.042654 -216.797288) (xy 39.99483 -216.771174) (xy 39.972742 -216.755218) (xy 39.95373 -216.741622)
			(xy 39.911847 -216.72089) (xy 39.866879 -216.708164) (xy 39.820342 -216.703874) (xy 39.773805 -216.708164)
			(xy 39.728837 -216.72089) (xy 39.686954 -216.741622) (xy 39.667942 -216.755218) (xy 39.645843 -216.771168)
			(xy 39.598016 -216.797294) (xy 39.546956 -216.816347) (xy 39.493705 -216.827939) (xy 39.439346 -216.831834)
			(xy 39.384986 -216.827952) (xy 39.331732 -216.816373) (xy 39.280668 -216.797332) (xy 39.232834 -216.771218)
			(xy 39.189203 -216.738561) (xy 39.150665 -216.700027) (xy 39.118004 -216.6564) (xy 39.091884 -216.608568)
			(xy 39.072838 -216.557506) (xy 39.061254 -216.504254) (xy 39.057366 -216.449894) (xy 36.335377 -216.449894)
			(xy 36.361593 -216.492234) (xy 36.400327 -216.570023) (xy 36.431719 -216.651055) (xy 36.4555 -216.734637)
			(xy 36.471468 -216.820057) (xy 36.479486 -216.906586) (xy 36.479988 -216.950036) (xy 36.479486 -216.993486)
			(xy 36.471468 -217.080015) (xy 36.4555 -217.165435) (xy 36.431719 -217.249017) (xy 36.400327 -217.330049)
			(xy 36.361593 -217.407838) (xy 36.315846 -217.481722) (xy 36.282007 -217.526531) (xy 47.842414 -217.526531)
			(xy 47.842414 -217.445421) (xy 47.850364 -217.364702) (xy 47.866187 -217.285151) (xy 47.889732 -217.207535)
			(xy 47.920771 -217.132599) (xy 47.959006 -217.061067) (xy 48.004068 -216.993627) (xy 48.055523 -216.930928)
			(xy 48.112876 -216.873575) (xy 48.175575 -216.82212) (xy 48.243015 -216.777058) (xy 48.314547 -216.738823)
			(xy 48.389483 -216.707784) (xy 48.467099 -216.684239) (xy 48.54665 -216.668416) (xy 48.627369 -216.660466)
			(xy 48.708479 -216.660466) (xy 48.789198 -216.668416) (xy 48.868749 -216.684239) (xy 48.946365 -216.707784)
			(xy 49.021301 -216.738823) (xy 49.092833 -216.777058) (xy 49.160273 -216.82212) (xy 49.222972 -216.873575)
			(xy 49.280325 -216.930928) (xy 49.33178 -216.993627) (xy 49.376842 -217.061067) (xy 49.415077 -217.132599)
			(xy 49.446116 -217.207535) (xy 49.469661 -217.285151) (xy 49.485484 -217.364702) (xy 49.493434 -217.445421)
			(xy 49.493932 -217.485976) (xy 49.493434 -217.526531) (xy 49.485484 -217.60725) (xy 49.469661 -217.686801)
			(xy 49.446116 -217.764417) (xy 49.415077 -217.839353) (xy 49.376842 -217.910885) (xy 49.33178 -217.978325)
			(xy 49.280325 -218.041024) (xy 49.222972 -218.098377) (xy 49.160273 -218.149832) (xy 49.092833 -218.194894)
			(xy 49.021301 -218.233129) (xy 48.946365 -218.264168) (xy 48.868749 -218.287713) (xy 48.789198 -218.303536)
			(xy 48.708479 -218.311486) (xy 48.627369 -218.311486) (xy 48.54665 -218.303536) (xy 48.467099 -218.287713)
			(xy 48.389483 -218.264168) (xy 48.314547 -218.233129) (xy 48.243015 -218.194894) (xy 48.175575 -218.149832)
			(xy 48.112876 -218.098377) (xy 48.055523 -218.041024) (xy 48.004068 -217.978325) (xy 47.959006 -217.910885)
			(xy 47.920771 -217.839353) (xy 47.889732 -217.764417) (xy 47.866187 -217.686801) (xy 47.850364 -217.60725)
			(xy 47.842414 -217.526531) (xy 36.282007 -217.526531) (xy 36.263477 -217.551069) (xy 36.204933 -217.615289)
			(xy 36.140713 -217.673833) (xy 36.071366 -217.726202) (xy 35.997482 -217.771949) (xy 35.919693 -217.810683)
			(xy 35.838661 -217.842075) (xy 35.755079 -217.865856) (xy 35.669659 -217.881824) (xy 35.58313 -217.889842)
			(xy 35.49623 -217.889842) (xy 35.409701 -217.881824) (xy 35.324281 -217.865856) (xy 35.240699 -217.842075)
			(xy 35.159667 -217.810683) (xy 35.081878 -217.771949) (xy 35.007994 -217.726202) (xy 34.938647 -217.673833)
			(xy 34.874427 -217.615289) (xy 34.815883 -217.551069) (xy 34.763514 -217.481722) (xy 34.717767 -217.407838)
			(xy 34.679033 -217.330049) (xy 34.647641 -217.249017) (xy 34.62386 -217.165435) (xy 34.607892 -217.080015)
			(xy 34.599874 -216.993486) (xy 31.399486 -216.993486) (xy 31.391468 -217.080015) (xy 31.3755 -217.165435)
			(xy 31.351719 -217.249017) (xy 31.320327 -217.330049) (xy 31.281593 -217.407838) (xy 31.235846 -217.481722)
			(xy 31.183477 -217.551069) (xy 31.124933 -217.615289) (xy 31.060713 -217.673833) (xy 30.991366 -217.726202)
			(xy 30.917482 -217.771949) (xy 30.839693 -217.810683) (xy 30.758661 -217.842075) (xy 30.675079 -217.865856)
			(xy 30.589659 -217.881824) (xy 30.50313 -217.889842) (xy 30.41623 -217.889842) (xy 30.329701 -217.881824)
			(xy 30.244281 -217.865856) (xy 30.160699 -217.842075) (xy 30.079667 -217.810683) (xy 30.001878 -217.771949)
			(xy 29.927994 -217.726202) (xy 29.858647 -217.673833) (xy 29.794427 -217.615289) (xy 29.735883 -217.551069)
			(xy 29.683514 -217.481722) (xy 29.637767 -217.407838) (xy 29.599033 -217.330049) (xy 29.567641 -217.249017)
			(xy 29.54386 -217.165435) (xy 29.527892 -217.080015) (xy 29.519874 -216.993486) (xy 28.753816 -216.993486)
			(xy 28.753816 -218.491128) (xy 39.057321 -218.491128) (xy 39.061206 -218.436761) (xy 39.072789 -218.383502)
			(xy 39.091835 -218.332433) (xy 39.117955 -218.284594) (xy 39.150617 -218.24096) (xy 39.189158 -218.202419)
			(xy 39.232791 -218.169756) (xy 39.28063 -218.143636) (xy 39.331698 -218.12459) (xy 39.384958 -218.113007)
			(xy 39.439324 -218.109121) (xy 39.49369 -218.113014) (xy 39.546948 -218.124604) (xy 39.598015 -218.143656)
			(xy 39.64585 -218.169783) (xy 39.667942 -218.185746) (xy 39.686954 -218.199342) (xy 39.728837 -218.220074)
			(xy 39.773805 -218.2328) (xy 39.820342 -218.23709) (xy 39.866879 -218.2328) (xy 39.911847 -218.220074)
			(xy 39.95373 -218.199342) (xy 39.972742 -218.185746) (xy 39.994872 -218.169852) (xy 40.042692 -218.143744)
			(xy 40.093741 -218.124707) (xy 40.146979 -218.113129) (xy 40.201323 -218.109245) (xy 40.255667 -218.113136)
			(xy 40.308904 -218.12472) (xy 40.35995 -218.143763) (xy 40.407767 -218.169877) (xy 40.451381 -218.20253)
			(xy 40.489903 -218.241058) (xy 40.522551 -218.284676) (xy 40.548658 -218.332496) (xy 40.567694 -218.383545)
			(xy 40.579272 -218.436783) (xy 40.583155 -218.491128) (xy 40.944174 -218.491128) (xy 40.948058 -218.436773)
			(xy 40.959637 -218.383525) (xy 40.978677 -218.332467) (xy 41.004789 -218.284638) (xy 41.037442 -218.241012)
			(xy 41.075972 -218.202477) (xy 41.119593 -218.169818) (xy 41.167418 -218.143699) (xy 41.218474 -218.124652)
			(xy 41.271721 -218.113065) (xy 41.326074 -218.109174) (xy 41.380428 -218.113058) (xy 41.433677 -218.124638)
			(xy 41.484735 -218.143678) (xy 41.532564 -218.16979) (xy 41.554654 -218.185746) (xy 41.573666 -218.199342)
			(xy 41.615549 -218.220074) (xy 41.660517 -218.2328) (xy 41.707054 -218.23709) (xy 41.753591 -218.2328)
			(xy 41.798559 -218.220074) (xy 41.840442 -218.199342) (xy 41.859454 -218.185746) (xy 41.881586 -218.169844)
			(xy 41.929412 -218.143722) (xy 41.980469 -218.124673) (xy 42.033718 -218.113084) (xy 42.088073 -218.109193)
			(xy 42.14243 -218.113077) (xy 42.19568 -218.124658) (xy 42.246739 -218.1437) (xy 42.294569 -218.169815)
			(xy 42.338195 -218.202472) (xy 42.376728 -218.241006) (xy 42.409385 -218.284632) (xy 42.4355 -218.332462)
			(xy 42.454542 -218.383521) (xy 42.466123 -218.436771) (xy 42.470007 -218.491128) (xy 43.185149 -218.491128)
			(xy 43.189033 -218.436768) (xy 43.200614 -218.383514) (xy 43.219657 -218.332451) (xy 43.245773 -218.284617)
			(xy 43.27843 -218.240987) (xy 43.316965 -218.20245) (xy 43.360592 -218.169788) (xy 43.408424 -218.143669)
			(xy 43.459486 -218.124623) (xy 43.512739 -218.113037) (xy 43.567098 -218.109149) (xy 43.621458 -218.113037)
			(xy 43.674711 -218.124622) (xy 43.725773 -218.143667) (xy 43.773605 -218.169786) (xy 43.795696 -218.185746)
			(xy 43.814708 -218.199342) (xy 43.856591 -218.220074) (xy 43.901559 -218.2328) (xy 43.948096 -218.23709)
			(xy 43.994633 -218.2328) (xy 44.039601 -218.220074) (xy 44.081484 -218.199342) (xy 44.100496 -218.185746)
			(xy 44.122627 -218.169848) (xy 44.17045 -218.143732) (xy 44.221503 -218.124689) (xy 44.274747 -218.113106)
			(xy 44.329097 -218.109218) (xy 44.383448 -218.113105) (xy 44.436691 -218.124688) (xy 44.487745 -218.14373)
			(xy 44.535568 -218.169845) (xy 44.579188 -218.2025) (xy 44.617716 -218.241031) (xy 44.650369 -218.284653)
			(xy 44.67648 -218.332478) (xy 44.695519 -218.383533) (xy 44.707099 -218.436777) (xy 44.710982 -218.491128)
			(xy 45.089159 -218.491128) (xy 45.093043 -218.43677) (xy 45.104623 -218.383518) (xy 45.123664 -218.332457)
			(xy 45.149779 -218.284625) (xy 45.182435 -218.240997) (xy 45.220968 -218.20246) (xy 45.264593 -218.1698)
			(xy 45.312422 -218.14368) (xy 45.363481 -218.124634) (xy 45.416732 -218.113048) (xy 45.471089 -218.109159)
			(xy 45.525447 -218.113045) (xy 45.578698 -218.124628) (xy 45.629758 -218.143671) (xy 45.677589 -218.169788)
			(xy 45.69968 -218.185746) (xy 45.718692 -218.199342) (xy 45.760575 -218.220074) (xy 45.805543 -218.2328)
			(xy 45.85208 -218.23709) (xy 45.898617 -218.2328) (xy 45.943585 -218.220074) (xy 45.985468 -218.199342)
			(xy 46.00448 -218.185746) (xy 46.026612 -218.169846) (xy 46.074436 -218.143728) (xy 46.12549 -218.124683)
			(xy 46.178736 -218.113098) (xy 46.233088 -218.109208) (xy 46.287441 -218.113094) (xy 46.340687 -218.124676)
			(xy 46.391743 -218.143719) (xy 46.439568 -218.169834) (xy 46.48319 -218.20249) (xy 46.521721 -218.241021)
			(xy 46.554375 -218.284645) (xy 46.580488 -218.332472) (xy 46.599528 -218.383528) (xy 46.611108 -218.436775)
			(xy 46.614992 -218.491128) (xy 46.6111 -218.54548) (xy 46.599513 -218.598725) (xy 46.580465 -218.649778)
			(xy 46.554345 -218.697602) (xy 46.521685 -218.74122) (xy 46.483149 -218.779747) (xy 46.439522 -218.812396)
			(xy 46.391692 -218.838504) (xy 46.340634 -218.857539) (xy 46.287386 -218.869114) (xy 46.233033 -218.872992)
			(xy 46.178681 -218.869095) (xy 46.125437 -218.857501) (xy 46.074386 -218.838449) (xy 46.026565 -218.812324)
			(xy 46.00448 -218.796362) (xy 45.985468 -218.782766) (xy 45.943585 -218.762034) (xy 45.898617 -218.749308)
			(xy 45.85208 -218.745018) (xy 45.805543 -218.749308) (xy 45.760575 -218.762034) (xy 45.718692 -218.782766)
			(xy 45.69968 -218.796362) (xy 45.677635 -218.812382) (xy 45.629809 -218.838506) (xy 45.578751 -218.857557)
			(xy 45.525501 -218.869147) (xy 45.471144 -218.873041) (xy 45.416786 -218.86916) (xy 45.363534 -218.857582)
			(xy 45.312472 -218.838543) (xy 45.264639 -218.81243) (xy 45.221009 -218.779776) (xy 45.182471 -218.741245)
			(xy 45.149809 -218.697621) (xy 45.123687 -218.649793) (xy 45.104639 -218.598735) (xy 45.09305 -218.545485)
			(xy 45.089159 -218.491128) (xy 44.710982 -218.491128) (xy 44.707091 -218.545478) (xy 44.695504 -218.59872)
			(xy 44.676457 -218.649772) (xy 44.650339 -218.697594) (xy 44.61768 -218.741211) (xy 44.579146 -218.779736)
			(xy 44.535522 -218.812385) (xy 44.487694 -218.838493) (xy 44.436638 -218.857528) (xy 44.383393 -218.869103)
			(xy 44.329042 -218.872982) (xy 44.274692 -218.869086) (xy 44.221451 -218.857495) (xy 44.1704 -218.838445)
			(xy 44.122581 -218.812322) (xy 44.100496 -218.796362) (xy 44.081484 -218.782766) (xy 44.039601 -218.762034)
			(xy 43.994633 -218.749308) (xy 43.948096 -218.745018) (xy 43.901559 -218.749308) (xy 43.856591 -218.762034)
			(xy 43.814708 -218.782766) (xy 43.795696 -218.796362) (xy 43.773651 -218.812384) (xy 43.725823 -218.83851)
			(xy 43.674764 -218.857563) (xy 43.621512 -218.869155) (xy 43.567153 -218.873051) (xy 43.512793 -218.86917)
			(xy 43.459539 -218.857593) (xy 43.408474 -218.838554) (xy 43.360639 -218.812441) (xy 43.317007 -218.779787)
			(xy 43.278466 -218.741254) (xy 43.245802 -218.697629) (xy 43.21968 -218.6498) (xy 43.20063 -218.598739)
			(xy 43.189041 -218.545487) (xy 43.185149 -218.491128) (xy 42.470007 -218.491128) (xy 42.466115 -218.545483)
			(xy 42.454527 -218.598732) (xy 42.435477 -218.649789) (xy 42.409355 -218.697614) (xy 42.376692 -218.741236)
			(xy 42.338153 -218.779764) (xy 42.294522 -218.812414) (xy 42.246689 -218.838523) (xy 42.195627 -218.857558)
			(xy 42.142375 -218.869131) (xy 42.088018 -218.873007) (xy 42.033663 -218.869108) (xy 41.980416 -218.857512)
			(xy 41.929362 -218.838455) (xy 41.88154 -218.812326) (xy 41.859454 -218.796362) (xy 41.840442 -218.782766)
			(xy 41.798559 -218.762034) (xy 41.753591 -218.749308) (xy 41.707054 -218.745018) (xy 41.660517 -218.749308)
			(xy 41.615549 -218.762034) (xy 41.573666 -218.782766) (xy 41.554654 -218.796362) (xy 41.53261 -218.81238)
			(xy 41.484785 -218.838499) (xy 41.43373 -218.857547) (xy 41.380483 -218.869134) (xy 41.326129 -218.873026)
			(xy 41.271775 -218.869142) (xy 41.218527 -218.857563) (xy 41.167469 -218.838524) (xy 41.11964 -218.812412)
			(xy 41.076013 -218.779759) (xy 41.037478 -218.74123) (xy 41.004819 -218.697608) (xy 40.9787 -218.649783)
			(xy 40.959653 -218.598728) (xy 40.948066 -218.545481) (xy 40.944174 -218.491128) (xy 40.583155 -218.491128)
			(xy 40.579264 -218.545471) (xy 40.567679 -218.598708) (xy 40.548635 -218.649754) (xy 40.522521 -218.697571)
			(xy 40.489867 -218.741184) (xy 40.451339 -218.779706) (xy 40.407721 -218.812353) (xy 40.3599 -218.83846)
			(xy 40.308851 -218.857495) (xy 40.255613 -218.869072) (xy 40.201268 -218.872955) (xy 40.146925 -218.869063)
			(xy 40.093688 -218.857478) (xy 40.042642 -218.838433) (xy 39.994826 -218.812318) (xy 39.972742 -218.796362)
			(xy 39.95373 -218.782766) (xy 39.911847 -218.762034) (xy 39.866879 -218.749308) (xy 39.820342 -218.745018)
			(xy 39.773805 -218.749308) (xy 39.728837 -218.762034) (xy 39.686954 -218.782766) (xy 39.667942 -218.796362)
			(xy 39.645896 -218.812388) (xy 39.598065 -218.838521) (xy 39.547001 -218.857581) (xy 39.493745 -218.869179)
			(xy 39.43938 -218.873079) (xy 39.385013 -218.869201) (xy 39.331751 -218.857625) (xy 39.28068 -218.838587)
			(xy 39.232838 -218.812474) (xy 39.1892 -218.779817) (xy 39.150653 -218.741281) (xy 39.117984 -218.697652)
			(xy 39.091857 -218.649818) (xy 39.072805 -218.598751) (xy 39.061214 -218.545493) (xy 39.057321 -218.491128)
			(xy 28.753816 -218.491128) (xy 28.753816 -219.533486) (xy 29.519874 -219.533486) (xy 29.519874 -219.446586)
			(xy 29.527892 -219.360057) (xy 29.54386 -219.274637) (xy 29.567641 -219.191055) (xy 29.599033 -219.110023)
			(xy 29.637767 -219.032234) (xy 29.683514 -218.95835) (xy 29.735883 -218.889003) (xy 29.794427 -218.824783)
			(xy 29.858647 -218.766239) (xy 29.927994 -218.71387) (xy 30.001878 -218.668123) (xy 30.079667 -218.629389)
			(xy 30.160699 -218.597997) (xy 30.244281 -218.574216) (xy 30.329701 -218.558248) (xy 30.41623 -218.55023)
			(xy 30.50313 -218.55023) (xy 30.589659 -218.558248) (xy 30.675079 -218.574216) (xy 30.758661 -218.597997)
			(xy 30.839693 -218.629389) (xy 30.917482 -218.668123) (xy 30.991366 -218.71387) (xy 31.060713 -218.766239)
			(xy 31.124933 -218.824783) (xy 31.183477 -218.889003) (xy 31.235846 -218.95835) (xy 31.281593 -219.032234)
			(xy 31.320327 -219.110023) (xy 31.351719 -219.191055) (xy 31.3755 -219.274637) (xy 31.391468 -219.360057)
			(xy 31.399486 -219.446586) (xy 31.399988 -219.490036) (xy 31.399486 -219.533486) (xy 34.599874 -219.533486)
			(xy 34.599874 -219.446586) (xy 34.607892 -219.360057) (xy 34.62386 -219.274637) (xy 34.647641 -219.191055)
			(xy 34.679033 -219.110023) (xy 34.717767 -219.032234) (xy 34.763514 -218.95835) (xy 34.815883 -218.889003)
			(xy 34.874427 -218.824783) (xy 34.938647 -218.766239) (xy 35.007994 -218.71387) (xy 35.081878 -218.668123)
			(xy 35.159667 -218.629389) (xy 35.240699 -218.597997) (xy 35.324281 -218.574216) (xy 35.409701 -218.558248)
			(xy 35.49623 -218.55023) (xy 35.58313 -218.55023) (xy 35.669659 -218.558248) (xy 35.755079 -218.574216)
			(xy 35.838661 -218.597997) (xy 35.919693 -218.629389) (xy 35.997482 -218.668123) (xy 36.071366 -218.71387)
			(xy 36.140713 -218.766239) (xy 36.204933 -218.824783) (xy 36.263477 -218.889003) (xy 36.315846 -218.95835)
			(xy 36.361593 -219.032234) (xy 36.400327 -219.110023) (xy 36.431719 -219.191055) (xy 36.4555 -219.274637)
			(xy 36.471468 -219.360057) (xy 36.479486 -219.446586) (xy 36.479988 -219.490036) (xy 36.479486 -219.533486)
			(xy 36.471468 -219.620015) (xy 36.4555 -219.705435) (xy 36.431719 -219.789017) (xy 36.400327 -219.870049)
			(xy 36.361593 -219.947838) (xy 36.315846 -220.021722) (xy 36.263477 -220.091069) (xy 36.204933 -220.155289)
			(xy 36.140713 -220.213833) (xy 36.071366 -220.266202) (xy 35.997482 -220.311949) (xy 35.919693 -220.350683)
			(xy 35.838661 -220.382075) (xy 35.772455 -220.400912) (xy 39.057342 -220.400912) (xy 39.061229 -220.346549)
			(xy 39.072814 -220.293293) (xy 39.09186 -220.242227) (xy 39.11798 -220.194392) (xy 39.150643 -220.150762)
			(xy 39.189183 -220.112225) (xy 39.232816 -220.079565) (xy 39.280652 -220.053448) (xy 39.331719 -220.034406)
			(xy 39.384977 -220.022825) (xy 39.43934 -220.018942) (xy 39.493702 -220.022836) (xy 39.546957 -220.034428)
			(xy 39.59802 -220.053482) (xy 39.645851 -220.079609) (xy 39.667942 -220.095572) (xy 39.686954 -220.109168)
			(xy 39.728837 -220.1299) (xy 39.773805 -220.142626) (xy 39.820342 -220.146916) (xy 39.866879 -220.142626)
			(xy 39.911847 -220.1299) (xy 39.95373 -220.109168) (xy 39.972742 -220.095572) (xy 39.994848 -220.079643)
			(xy 40.042669 -220.053531) (xy 40.09372 -220.034491) (xy 40.146961 -220.022911) (xy 40.201308 -220.019025)
			(xy 40.255655 -220.022913) (xy 40.308895 -220.034496) (xy 40.359945 -220.053538) (xy 40.407765 -220.079651)
			(xy 40.451383 -220.112304) (xy 40.489909 -220.150832) (xy 40.52256 -220.194451) (xy 40.548671 -220.242273)
			(xy 40.56771 -220.293324) (xy 40.57929 -220.346565) (xy 40.583175 -220.400912) (xy 40.944195 -220.400912)
			(xy 40.948081 -220.346561) (xy 40.959662 -220.293316) (xy 40.978702 -220.242261) (xy 41.004815 -220.194436)
			(xy 41.037468 -220.150814) (xy 41.075997 -220.112283) (xy 41.119617 -220.079627) (xy 41.167441 -220.053511)
			(xy 41.218495 -220.034468) (xy 41.271739 -220.022884) (xy 41.32609 -220.018995) (xy 41.380441 -220.022881)
			(xy 41.433686 -220.034462) (xy 41.48474 -220.053503) (xy 41.532565 -220.079616) (xy 41.554654 -220.095572)
			(xy 41.573666 -220.109168) (xy 41.615549 -220.1299) (xy 41.660517 -220.142626) (xy 41.707054 -220.146916)
			(xy 41.753591 -220.142626) (xy 41.798559 -220.1299) (xy 41.840442 -220.109168) (xy 41.859454 -220.095572)
			(xy 41.881562 -220.079635) (xy 41.92939 -220.05351) (xy 41.980448 -220.034457) (xy 42.033699 -220.022866)
			(xy 42.088058 -220.018972) (xy 42.142417 -220.022854) (xy 42.195671 -220.034434) (xy 42.246734 -220.053475)
			(xy 42.294567 -220.079589) (xy 42.338196 -220.112247) (xy 42.376734 -220.150781) (xy 42.409394 -220.194408)
			(xy 42.435513 -220.242239) (xy 42.454558 -220.2933) (xy 42.466142 -220.346553) (xy 42.470028 -220.400912)
			(xy 43.18517 -220.400912) (xy 43.189056 -220.346555) (xy 43.200639 -220.293305) (xy 43.219682 -220.242245)
			(xy 43.245799 -220.194415) (xy 43.278456 -220.150789) (xy 43.316991 -220.112255) (xy 43.360617 -220.079598)
			(xy 43.408447 -220.053481) (xy 43.459507 -220.034438) (xy 43.512757 -220.022856) (xy 43.567114 -220.01897)
			(xy 43.62147 -220.02286) (xy 43.67472 -220.034446) (xy 43.725778 -220.053493) (xy 43.773606 -220.079612)
			(xy 43.795696 -220.095572) (xy 43.814708 -220.109168) (xy 43.856591 -220.1299) (xy 43.901559 -220.142626)
			(xy 43.948096 -220.146916) (xy 43.994633 -220.142626) (xy 44.039601 -220.1299) (xy 44.081484 -220.109168)
			(xy 44.100496 -220.095572) (xy 44.122603 -220.079639) (xy 44.170428 -220.05352) (xy 44.221483 -220.034474)
			(xy 44.274729 -220.022887) (xy 44.329082 -220.018997) (xy 44.383435 -220.022882) (xy 44.436682 -220.034463)
			(xy 44.487739 -220.053505) (xy 44.535566 -220.079619) (xy 44.57919 -220.112274) (xy 44.617722 -220.150805)
			(xy 44.650378 -220.194429) (xy 44.676493 -220.242255) (xy 44.695535 -220.293312) (xy 44.707117 -220.346559)
			(xy 44.711003 -220.400912) (xy 45.089179 -220.400912) (xy 45.093065 -220.346557) (xy 45.104647 -220.293309)
			(xy 45.12369 -220.242251) (xy 45.149805 -220.194423) (xy 45.182461 -220.150799) (xy 45.220993 -220.112266)
			(xy 45.264617 -220.079609) (xy 45.312445 -220.053493) (xy 45.363502 -220.034449) (xy 45.41675 -220.022866)
			(xy 45.471105 -220.018979) (xy 45.525459 -220.022868) (xy 45.578707 -220.034452) (xy 45.629764 -220.053497)
			(xy 45.677591 -220.079614) (xy 45.69968 -220.095572) (xy 45.718692 -220.109168) (xy 45.760575 -220.1299)
			(xy 45.805543 -220.142626) (xy 45.85208 -220.146916) (xy 45.898617 -220.142626) (xy 45.943585 -220.1299)
			(xy 45.985468 -220.109168) (xy 46.00448 -220.095572) (xy 46.026587 -220.079637) (xy 46.074413 -220.053516)
			(xy 46.12547 -220.034467) (xy 46.178718 -220.022879) (xy 46.233073 -220.018988) (xy 46.287428 -220.022871)
			(xy 46.340678 -220.034452) (xy 46.391737 -220.053493) (xy 46.439566 -220.079608) (xy 46.483192 -220.112264)
			(xy 46.521726 -220.150796) (xy 46.554384 -220.194421) (xy 46.5805 -220.242249) (xy 46.599544 -220.293307)
			(xy 46.611126 -220.346557) (xy 46.615013 -220.400912) (xy 46.611123 -220.455267) (xy 46.599537 -220.508516)
			(xy 46.58049 -220.559573) (xy 46.554371 -220.6074) (xy 46.521711 -220.651022) (xy 46.483174 -220.689552)
			(xy 46.439546 -220.722205) (xy 46.391715 -220.748317) (xy 46.340655 -220.767355) (xy 46.287404 -220.778932)
			(xy 46.233049 -220.782812) (xy 46.178694 -220.778917) (xy 46.125447 -220.767326) (xy 46.074391 -220.748274)
			(xy 46.026567 -220.72215) (xy 46.00448 -220.706188) (xy 45.985468 -220.692592) (xy 45.943585 -220.67186)
			(xy 45.898617 -220.659134) (xy 45.85208 -220.654844) (xy 45.805543 -220.659134) (xy 45.760575 -220.67186)
			(xy 45.718692 -220.692592) (xy 45.69968 -220.706188) (xy 45.677611 -220.722173) (xy 45.629786 -220.748293)
			(xy 45.57873 -220.767341) (xy 45.525483 -220.778929) (xy 45.471129 -220.782821) (xy 45.416774 -220.778937)
			(xy 45.363525 -220.767357) (xy 45.312466 -220.748317) (xy 45.264637 -220.722204) (xy 45.221011 -220.68955)
			(xy 45.182477 -220.65102) (xy 45.149818 -220.607397) (xy 45.1237 -220.559571) (xy 45.104654 -220.508514)
			(xy 45.093069 -220.455266) (xy 45.089179 -220.400912) (xy 44.711003 -220.400912) (xy 44.707114 -220.455265)
			(xy 44.695528 -220.508511) (xy 44.676483 -220.559567) (xy 44.650365 -220.607392) (xy 44.617706 -220.651013)
			(xy 44.579172 -220.689542) (xy 44.535546 -220.722194) (xy 44.487717 -220.748305) (xy 44.436659 -220.767344)
			(xy 44.383411 -220.778921) (xy 44.329058 -220.782803) (xy 44.274705 -220.778909) (xy 44.22146 -220.76732)
			(xy 44.170406 -220.74827) (xy 44.122583 -220.722148) (xy 44.100496 -220.706188) (xy 44.081484 -220.692592)
			(xy 44.039601 -220.67186) (xy 43.994633 -220.659134) (xy 43.948096 -220.654844) (xy 43.901559 -220.659134)
			(xy 43.856591 -220.67186) (xy 43.814708 -220.692592) (xy 43.795696 -220.706188) (xy 43.773627 -220.722175)
			(xy 43.7258 -220.748297) (xy 43.674743 -220.767347) (xy 43.621494 -220.778937) (xy 43.567138 -220.78283)
			(xy 43.512781 -220.778948) (xy 43.45953 -220.767369) (xy 43.408468 -220.748329) (xy 43.360637 -220.722215)
			(xy 43.317009 -220.689561) (xy 43.278472 -220.651029) (xy 43.245811 -220.607405) (xy 43.219692 -220.559577)
			(xy 43.200645 -220.508518) (xy 43.189059 -220.455269) (xy 43.18517 -220.400912) (xy 42.470028 -220.400912)
			(xy 42.466138 -220.455271) (xy 42.454551 -220.508523) (xy 42.435503 -220.559583) (xy 42.409381 -220.607413)
			(xy 42.376718 -220.651037) (xy 42.338178 -220.689569) (xy 42.294547 -220.722223) (xy 42.246712 -220.748335)
			(xy 42.195648 -220.767373) (xy 42.142393 -220.778949) (xy 42.088034 -220.782828) (xy 42.033676 -220.77893)
			(xy 41.980425 -220.767336) (xy 41.929368 -220.74828) (xy 41.881542 -220.722152) (xy 41.859454 -220.706188)
			(xy 41.840442 -220.692592) (xy 41.798559 -220.67186) (xy 41.753591 -220.659134) (xy 41.707054 -220.654844)
			(xy 41.660517 -220.659134) (xy 41.615549 -220.67186) (xy 41.573666 -220.692592) (xy 41.554654 -220.706188)
			(xy 41.532586 -220.722171) (xy 41.484762 -220.748287) (xy 41.433709 -220.767331) (xy 41.380465 -220.778916)
			(xy 41.326114 -220.782805) (xy 41.271763 -220.77892) (xy 41.218518 -220.767339) (xy 41.167463 -220.748299)
			(xy 41.119638 -220.722186) (xy 41.076015 -220.689533) (xy 41.037484 -220.651004) (xy 41.004828 -220.607384)
			(xy 40.978712 -220.55956) (xy 40.959668 -220.508507) (xy 40.948084 -220.455263) (xy 40.944195 -220.400912)
			(xy 40.583175 -220.400912) (xy 40.579287 -220.455259) (xy 40.567703 -220.508499) (xy 40.548661 -220.559549)
			(xy 40.522547 -220.607369) (xy 40.489893 -220.650986) (xy 40.451364 -220.689511) (xy 40.407745 -220.722162)
			(xy 40.359923 -220.748272) (xy 40.308872 -220.767311) (xy 40.255631 -220.778891) (xy 40.201284 -220.782775)
			(xy 40.146937 -220.778886) (xy 40.093697 -220.767302) (xy 40.042648 -220.748259) (xy 39.994828 -220.722144)
			(xy 39.972742 -220.706188) (xy 39.95373 -220.692592) (xy 39.911847 -220.67186) (xy 39.866879 -220.659134)
			(xy 39.820342 -220.654844) (xy 39.773805 -220.659134) (xy 39.728837 -220.67186) (xy 39.686954 -220.692592)
			(xy 39.667942 -220.706188) (xy 39.645872 -220.722178) (xy 39.598042 -220.748308) (xy 39.54698 -220.767365)
			(xy 39.493726 -220.77896) (xy 39.439364 -220.782858) (xy 39.385 -220.778978) (xy 39.331742 -220.767401)
			(xy 39.280674 -220.748362) (xy 39.232836 -220.722248) (xy 39.189201 -220.689591) (xy 39.150659 -220.651056)
			(xy 39.117993 -220.607428) (xy 39.09187 -220.559595) (xy 39.07282 -220.508531) (xy 39.061232 -220.455275)
			(xy 39.057342 -220.400912) (xy 35.772455 -220.400912) (xy 35.755079 -220.405856) (xy 35.669659 -220.421824)
			(xy 35.58313 -220.429842) (xy 35.49623 -220.429842) (xy 35.409701 -220.421824) (xy 35.324281 -220.405856)
			(xy 35.240699 -220.382075) (xy 35.159667 -220.350683) (xy 35.081878 -220.311949) (xy 35.007994 -220.266202)
			(xy 34.938647 -220.213833) (xy 34.874427 -220.155289) (xy 34.815883 -220.091069) (xy 34.763514 -220.021722)
			(xy 34.717767 -219.947838) (xy 34.679033 -219.870049) (xy 34.647641 -219.789017) (xy 34.62386 -219.705435)
			(xy 34.607892 -219.620015) (xy 34.599874 -219.533486) (xy 31.399486 -219.533486) (xy 31.391468 -219.620015)
			(xy 31.3755 -219.705435) (xy 31.351719 -219.789017) (xy 31.320327 -219.870049) (xy 31.281593 -219.947838)
			(xy 31.235846 -220.021722) (xy 31.183477 -220.091069) (xy 31.124933 -220.155289) (xy 31.060713 -220.213833)
			(xy 30.991366 -220.266202) (xy 30.917482 -220.311949) (xy 30.839693 -220.350683) (xy 30.758661 -220.382075)
			(xy 30.675079 -220.405856) (xy 30.589659 -220.421824) (xy 30.50313 -220.429842) (xy 30.41623 -220.429842)
			(xy 30.329701 -220.421824) (xy 30.244281 -220.405856) (xy 30.160699 -220.382075) (xy 30.079667 -220.350683)
			(xy 30.001878 -220.311949) (xy 29.927994 -220.266202) (xy 29.858647 -220.213833) (xy 29.794427 -220.155289)
			(xy 29.735883 -220.091069) (xy 29.683514 -220.021722) (xy 29.637767 -219.947838) (xy 29.599033 -219.870049)
			(xy 29.567641 -219.789017) (xy 29.54386 -219.705435) (xy 29.527892 -219.620015) (xy 29.519874 -219.533486)
			(xy 28.753816 -219.533486) (xy 28.753816 -222.073486) (xy 29.519874 -222.073486) (xy 29.519874 -221.986586)
			(xy 29.527892 -221.900057) (xy 29.54386 -221.814637) (xy 29.567641 -221.731055) (xy 29.599033 -221.650023)
			(xy 29.637767 -221.572234) (xy 29.683514 -221.49835) (xy 29.735883 -221.429003) (xy 29.794427 -221.364783)
			(xy 29.858647 -221.306239) (xy 29.927994 -221.25387) (xy 30.001878 -221.208123) (xy 30.079667 -221.169389)
			(xy 30.160699 -221.137997) (xy 30.244281 -221.114216) (xy 30.329701 -221.098248) (xy 30.41623 -221.09023)
			(xy 30.50313 -221.09023) (xy 30.589659 -221.098248) (xy 30.675079 -221.114216) (xy 30.758661 -221.137997)
			(xy 30.839693 -221.169389) (xy 30.917482 -221.208123) (xy 30.991366 -221.25387) (xy 31.060713 -221.306239)
			(xy 31.124933 -221.364783) (xy 31.183477 -221.429003) (xy 31.235846 -221.49835) (xy 31.281593 -221.572234)
			(xy 31.320327 -221.650023) (xy 31.351719 -221.731055) (xy 31.3755 -221.814637) (xy 31.391468 -221.900057)
			(xy 31.399486 -221.986586) (xy 31.399988 -222.030036) (xy 31.399486 -222.073486) (xy 34.599874 -222.073486)
			(xy 34.599874 -221.986586) (xy 34.607892 -221.900057) (xy 34.62386 -221.814637) (xy 34.647641 -221.731055)
			(xy 34.679033 -221.650023) (xy 34.717767 -221.572234) (xy 34.763514 -221.49835) (xy 34.815883 -221.429003)
			(xy 34.874427 -221.364783) (xy 34.938647 -221.306239) (xy 35.007994 -221.25387) (xy 35.081878 -221.208123)
			(xy 35.159667 -221.169389) (xy 35.240699 -221.137997) (xy 35.324281 -221.114216) (xy 35.409701 -221.098248)
			(xy 35.49623 -221.09023) (xy 35.58313 -221.09023) (xy 35.669659 -221.098248) (xy 35.755079 -221.114216)
			(xy 35.838661 -221.137997) (xy 35.919693 -221.169389) (xy 35.997482 -221.208123) (xy 36.071366 -221.25387)
			(xy 36.140713 -221.306239) (xy 36.204933 -221.364783) (xy 36.263477 -221.429003) (xy 36.315846 -221.49835)
			(xy 36.361593 -221.572234) (xy 36.400327 -221.650023) (xy 36.431719 -221.731055) (xy 36.4555 -221.814637)
			(xy 36.471468 -221.900057) (xy 36.479486 -221.986586) (xy 36.479988 -222.030036) (xy 36.479486 -222.073486)
			(xy 36.471468 -222.160015) (xy 36.4555 -222.245435) (xy 36.431719 -222.329017) (xy 36.400327 -222.410049)
			(xy 36.361593 -222.487838) (xy 36.315846 -222.561722) (xy 36.263477 -222.631069) (xy 36.204933 -222.695289)
			(xy 36.140713 -222.753833) (xy 36.071366 -222.806202) (xy 35.997482 -222.851949) (xy 35.919693 -222.890683)
			(xy 35.838661 -222.922075) (xy 35.755079 -222.945856) (xy 35.669659 -222.961824) (xy 35.58313 -222.969842)
			(xy 35.49623 -222.969842) (xy 35.409701 -222.961824) (xy 35.324281 -222.945856) (xy 35.240699 -222.922075)
			(xy 35.159667 -222.890683) (xy 35.081878 -222.851949) (xy 35.007994 -222.806202) (xy 34.938647 -222.753833)
			(xy 34.874427 -222.695289) (xy 34.815883 -222.631069) (xy 34.763514 -222.561722) (xy 34.717767 -222.487838)
			(xy 34.679033 -222.410049) (xy 34.647641 -222.329017) (xy 34.62386 -222.245435) (xy 34.607892 -222.160015)
			(xy 34.599874 -222.073486) (xy 31.399486 -222.073486) (xy 31.391468 -222.160015) (xy 31.3755 -222.245435)
			(xy 31.351719 -222.329017) (xy 31.320327 -222.410049) (xy 31.281593 -222.487838) (xy 31.235846 -222.561722)
			(xy 31.183477 -222.631069) (xy 31.124933 -222.695289) (xy 31.060713 -222.753833) (xy 30.991366 -222.806202)
			(xy 30.917482 -222.851949) (xy 30.839693 -222.890683) (xy 30.758661 -222.922075) (xy 30.675079 -222.945856)
			(xy 30.589659 -222.961824) (xy 30.50313 -222.969842) (xy 30.41623 -222.969842) (xy 30.329701 -222.961824)
			(xy 30.244281 -222.945856) (xy 30.160699 -222.922075) (xy 30.079667 -222.890683) (xy 30.001878 -222.851949)
			(xy 29.927994 -222.806202) (xy 29.858647 -222.753833) (xy 29.794427 -222.695289) (xy 29.735883 -222.631069)
			(xy 29.683514 -222.561722) (xy 29.637767 -222.487838) (xy 29.599033 -222.410049) (xy 29.567641 -222.329017)
			(xy 29.54386 -222.245435) (xy 29.527892 -222.160015) (xy 29.519874 -222.073486) (xy 28.753816 -222.073486)
			(xy 28.753816 -222.180404) (xy 28.942538 -222.369126) (xy 28.942538 -224.613486) (xy 29.519874 -224.613486)
			(xy 29.519874 -224.526586) (xy 29.527892 -224.440057) (xy 29.54386 -224.354637) (xy 29.567641 -224.271055)
			(xy 29.599033 -224.190023) (xy 29.637767 -224.112234) (xy 29.683514 -224.03835) (xy 29.735883 -223.969003)
			(xy 29.794427 -223.904783) (xy 29.858647 -223.846239) (xy 29.927994 -223.79387) (xy 30.001878 -223.748123)
			(xy 30.079667 -223.709389) (xy 30.160699 -223.677997) (xy 30.244281 -223.654216) (xy 30.329701 -223.638248)
			(xy 30.41623 -223.63023) (xy 30.50313 -223.63023) (xy 30.589659 -223.638248) (xy 30.675079 -223.654216)
			(xy 30.758661 -223.677997) (xy 30.839693 -223.709389) (xy 30.917482 -223.748123) (xy 30.991366 -223.79387)
			(xy 31.060713 -223.846239) (xy 31.124933 -223.904783) (xy 31.183477 -223.969003) (xy 31.235846 -224.03835)
			(xy 31.281593 -224.112234) (xy 31.320327 -224.190023) (xy 31.351719 -224.271055) (xy 31.3755 -224.354637)
			(xy 31.391468 -224.440057) (xy 31.399486 -224.526586) (xy 31.399988 -224.570036) (xy 31.399486 -224.613486)
			(xy 34.599874 -224.613486) (xy 34.599874 -224.526586) (xy 34.607892 -224.440057) (xy 34.62386 -224.354637)
			(xy 34.647641 -224.271055) (xy 34.679033 -224.190023) (xy 34.717767 -224.112234) (xy 34.763514 -224.03835)
			(xy 34.815883 -223.969003) (xy 34.874427 -223.904783) (xy 34.938647 -223.846239) (xy 35.007994 -223.79387)
			(xy 35.081878 -223.748123) (xy 35.159667 -223.709389) (xy 35.240699 -223.677997) (xy 35.324281 -223.654216)
			(xy 35.409701 -223.638248) (xy 35.49623 -223.63023) (xy 35.58313 -223.63023) (xy 35.669659 -223.638248)
			(xy 35.755079 -223.654216) (xy 35.838661 -223.677997) (xy 35.919693 -223.709389) (xy 35.997482 -223.748123)
			(xy 36.071366 -223.79387) (xy 36.140713 -223.846239) (xy 36.204933 -223.904783) (xy 36.263477 -223.969003)
			(xy 36.315846 -224.03835) (xy 36.361593 -224.112234) (xy 36.400327 -224.190023) (xy 36.431719 -224.271055)
			(xy 36.4555 -224.354637) (xy 36.471468 -224.440057) (xy 36.479486 -224.526586) (xy 36.479988 -224.570036)
			(xy 36.479486 -224.613486) (xy 36.471468 -224.700015) (xy 36.4555 -224.785435) (xy 36.431719 -224.869017)
			(xy 36.400327 -224.950049) (xy 36.361593 -225.027838) (xy 36.315846 -225.101722) (xy 36.263477 -225.171069)
			(xy 36.204933 -225.235289) (xy 36.140713 -225.293833) (xy 36.071366 -225.346202) (xy 35.997482 -225.391949)
			(xy 35.919693 -225.430683) (xy 35.838661 -225.462075) (xy 35.755079 -225.485856) (xy 35.669659 -225.501824)
			(xy 35.58313 -225.509842) (xy 35.49623 -225.509842) (xy 35.409701 -225.501824) (xy 35.324281 -225.485856)
			(xy 35.240699 -225.462075) (xy 35.159667 -225.430683) (xy 35.081878 -225.391949) (xy 35.007994 -225.346202)
			(xy 34.938647 -225.293833) (xy 34.874427 -225.235289) (xy 34.815883 -225.171069) (xy 34.763514 -225.101722)
			(xy 34.717767 -225.027838) (xy 34.679033 -224.950049) (xy 34.647641 -224.869017) (xy 34.62386 -224.785435)
			(xy 34.607892 -224.700015) (xy 34.599874 -224.613486) (xy 31.399486 -224.613486) (xy 31.391468 -224.700015)
			(xy 31.3755 -224.785435) (xy 31.351719 -224.869017) (xy 31.320327 -224.950049) (xy 31.281593 -225.027838)
			(xy 31.235846 -225.101722) (xy 31.183477 -225.171069) (xy 31.124933 -225.235289) (xy 31.060713 -225.293833)
			(xy 30.991366 -225.346202) (xy 30.917482 -225.391949) (xy 30.839693 -225.430683) (xy 30.758661 -225.462075)
			(xy 30.675079 -225.485856) (xy 30.589659 -225.501824) (xy 30.50313 -225.509842) (xy 30.41623 -225.509842)
			(xy 30.329701 -225.501824) (xy 30.244281 -225.485856) (xy 30.160699 -225.462075) (xy 30.079667 -225.430683)
			(xy 30.001878 -225.391949) (xy 29.927994 -225.346202) (xy 29.858647 -225.293833) (xy 29.794427 -225.235289)
			(xy 29.735883 -225.171069) (xy 29.683514 -225.101722) (xy 29.637767 -225.027838) (xy 29.599033 -224.950049)
			(xy 29.567641 -224.869017) (xy 29.54386 -224.785435) (xy 29.527892 -224.700015) (xy 29.519874 -224.613486)
			(xy 28.942538 -224.613486) (xy 28.942538 -227.153486) (xy 29.519874 -227.153486) (xy 29.519874 -227.066586)
			(xy 29.527892 -226.980057) (xy 29.54386 -226.894637) (xy 29.567641 -226.811055) (xy 29.599033 -226.730023)
			(xy 29.637767 -226.652234) (xy 29.683514 -226.57835) (xy 29.735883 -226.509003) (xy 29.794427 -226.444783)
			(xy 29.858647 -226.386239) (xy 29.927994 -226.33387) (xy 30.001878 -226.288123) (xy 30.079667 -226.249389)
			(xy 30.160699 -226.217997) (xy 30.244281 -226.194216) (xy 30.329701 -226.178248) (xy 30.41623 -226.17023)
			(xy 30.50313 -226.17023) (xy 30.589659 -226.178248) (xy 30.675079 -226.194216) (xy 30.758661 -226.217997)
			(xy 30.839693 -226.249389) (xy 30.917482 -226.288123) (xy 30.991366 -226.33387) (xy 31.060713 -226.386239)
			(xy 31.124933 -226.444783) (xy 31.183477 -226.509003) (xy 31.235846 -226.57835) (xy 31.281593 -226.652234)
			(xy 31.320327 -226.730023) (xy 31.351719 -226.811055) (xy 31.3755 -226.894637) (xy 31.391468 -226.980057)
			(xy 31.399486 -227.066586) (xy 31.399988 -227.110036) (xy 31.399486 -227.153486) (xy 34.599874 -227.153486)
			(xy 34.599874 -227.066586) (xy 34.607892 -226.980057) (xy 34.62386 -226.894637) (xy 34.647641 -226.811055)
			(xy 34.679033 -226.730023) (xy 34.717767 -226.652234) (xy 34.763514 -226.57835) (xy 34.815883 -226.509003)
			(xy 34.874427 -226.444783) (xy 34.938647 -226.386239) (xy 35.007994 -226.33387) (xy 35.081878 -226.288123)
			(xy 35.159667 -226.249389) (xy 35.240699 -226.217997) (xy 35.324281 -226.194216) (xy 35.409701 -226.178248)
			(xy 35.49623 -226.17023) (xy 35.58313 -226.17023) (xy 35.669659 -226.178248) (xy 35.755079 -226.194216)
			(xy 35.838661 -226.217997) (xy 35.919693 -226.249389) (xy 35.997482 -226.288123) (xy 36.071366 -226.33387)
			(xy 36.140713 -226.386239) (xy 36.204933 -226.444783) (xy 36.263477 -226.509003) (xy 36.315846 -226.57835)
			(xy 36.361593 -226.652234) (xy 36.400327 -226.730023) (xy 36.431719 -226.811055) (xy 36.4555 -226.894637)
			(xy 36.471468 -226.980057) (xy 36.479486 -227.066586) (xy 36.479988 -227.110036) (xy 36.479486 -227.153486)
			(xy 36.471468 -227.240015) (xy 36.4555 -227.325435) (xy 36.431719 -227.409017) (xy 36.400327 -227.490049)
			(xy 36.361593 -227.567838) (xy 36.315846 -227.641722) (xy 36.263477 -227.711069) (xy 36.204933 -227.775289)
			(xy 36.140713 -227.833833) (xy 36.071366 -227.886202) (xy 35.997482 -227.931949) (xy 35.919693 -227.970683)
			(xy 35.838661 -228.002075) (xy 35.755079 -228.025856) (xy 35.669659 -228.041824) (xy 35.58313 -228.049842)
			(xy 35.49623 -228.049842) (xy 35.409701 -228.041824) (xy 35.324281 -228.025856) (xy 35.240699 -228.002075)
			(xy 35.159667 -227.970683) (xy 35.081878 -227.931949) (xy 35.007994 -227.886202) (xy 34.938647 -227.833833)
			(xy 34.874427 -227.775289) (xy 34.815883 -227.711069) (xy 34.763514 -227.641722) (xy 34.717767 -227.567838)
			(xy 34.679033 -227.490049) (xy 34.647641 -227.409017) (xy 34.62386 -227.325435) (xy 34.607892 -227.240015)
			(xy 34.599874 -227.153486) (xy 31.399486 -227.153486) (xy 31.391468 -227.240015) (xy 31.3755 -227.325435)
			(xy 31.351719 -227.409017) (xy 31.320327 -227.490049) (xy 31.281593 -227.567838) (xy 31.235846 -227.641722)
			(xy 31.183477 -227.711069) (xy 31.124933 -227.775289) (xy 31.060713 -227.833833) (xy 30.991366 -227.886202)
			(xy 30.917482 -227.931949) (xy 30.839693 -227.970683) (xy 30.758661 -228.002075) (xy 30.675079 -228.025856)
			(xy 30.589659 -228.041824) (xy 30.50313 -228.049842) (xy 30.41623 -228.049842) (xy 30.329701 -228.041824)
			(xy 30.244281 -228.025856) (xy 30.160699 -228.002075) (xy 30.079667 -227.970683) (xy 30.001878 -227.931949)
			(xy 29.927994 -227.886202) (xy 29.858647 -227.833833) (xy 29.794427 -227.775289) (xy 29.735883 -227.711069)
			(xy 29.683514 -227.641722) (xy 29.637767 -227.567838) (xy 29.599033 -227.490049) (xy 29.567641 -227.409017)
			(xy 29.54386 -227.325435) (xy 29.527892 -227.240015) (xy 29.519874 -227.153486) (xy 28.942538 -227.153486)
			(xy 28.942538 -229.693486) (xy 29.519874 -229.693486) (xy 29.519874 -229.606586) (xy 29.527892 -229.520057)
			(xy 29.54386 -229.434637) (xy 29.567641 -229.351055) (xy 29.599033 -229.270023) (xy 29.637767 -229.192234)
			(xy 29.683514 -229.11835) (xy 29.735883 -229.049003) (xy 29.794427 -228.984783) (xy 29.858647 -228.926239)
			(xy 29.927994 -228.87387) (xy 30.001878 -228.828123) (xy 30.079667 -228.789389) (xy 30.160699 -228.757997)
			(xy 30.244281 -228.734216) (xy 30.329701 -228.718248) (xy 30.41623 -228.71023) (xy 30.50313 -228.71023)
			(xy 30.589659 -228.718248) (xy 30.675079 -228.734216) (xy 30.758661 -228.757997) (xy 30.839693 -228.789389)
			(xy 30.917482 -228.828123) (xy 30.991366 -228.87387) (xy 31.060713 -228.926239) (xy 31.124933 -228.984783)
			(xy 31.183477 -229.049003) (xy 31.235846 -229.11835) (xy 31.281593 -229.192234) (xy 31.320327 -229.270023)
			(xy 31.351719 -229.351055) (xy 31.3755 -229.434637) (xy 31.391468 -229.520057) (xy 31.399486 -229.606586)
			(xy 31.399988 -229.650036) (xy 31.399486 -229.693486) (xy 34.599874 -229.693486) (xy 34.599874 -229.606586)
			(xy 34.607892 -229.520057) (xy 34.62386 -229.434637) (xy 34.647641 -229.351055) (xy 34.679033 -229.270023)
			(xy 34.717767 -229.192234) (xy 34.763514 -229.11835) (xy 34.815883 -229.049003) (xy 34.874427 -228.984783)
			(xy 34.938647 -228.926239) (xy 35.007994 -228.87387) (xy 35.081878 -228.828123) (xy 35.159667 -228.789389)
			(xy 35.240699 -228.757997) (xy 35.324281 -228.734216) (xy 35.409701 -228.718248) (xy 35.49623 -228.71023)
			(xy 35.58313 -228.71023) (xy 35.669659 -228.718248) (xy 35.755079 -228.734216) (xy 35.838661 -228.757997)
			(xy 35.919693 -228.789389) (xy 35.997482 -228.828123) (xy 36.071366 -228.87387) (xy 36.140713 -228.926239)
			(xy 36.204933 -228.984783) (xy 36.263477 -229.049003) (xy 36.315846 -229.11835) (xy 36.341678 -229.16007)
			(xy 39.818564 -229.16007) (xy 39.819058 -229.102661) (xy 39.826902 -228.988113) (xy 39.842544 -228.874366)
			(xy 39.865911 -228.761952) (xy 39.896896 -228.651394) (xy 39.935352 -228.543209) (xy 39.981101 -228.4379)
			(xy 40.03393 -228.335958) (xy 40.093592 -228.237859) (xy 40.159809 -228.14406) (xy 40.232272 -228.054998)
			(xy 40.310645 -227.971089) (xy 40.39456 -227.892723) (xy 40.483627 -227.820266) (xy 40.577431 -227.754056)
			(xy 40.675535 -227.694402) (xy 40.777481 -227.641581) (xy 40.882793 -227.595839) (xy 40.990981 -227.557391)
			(xy 41.101541 -227.526415) (xy 41.213957 -227.503056) (xy 41.327705 -227.487423) (xy 41.442254 -227.479588)
			(xy 41.557072 -227.479588) (xy 41.671621 -227.487423) (xy 41.785369 -227.503056) (xy 41.897785 -227.526415)
			(xy 42.008345 -227.557391) (xy 42.116533 -227.595839) (xy 42.221845 -227.641581) (xy 42.323791 -227.694402)
			(xy 42.421895 -227.754056) (xy 42.501239 -227.81006) (xy 43.327577 -227.81006) (xy 43.331612 -227.734356)
			(xy 43.343671 -227.659511) (xy 43.363617 -227.58637) (xy 43.391224 -227.515765) (xy 43.42618 -227.448494)
			(xy 43.468088 -227.385319) (xy 43.516474 -227.326957) (xy 43.57079 -227.274069) (xy 43.630419 -227.227254)
			(xy 43.694687 -227.187042) (xy 43.762864 -227.15389) (xy 43.83418 -227.128172) (xy 43.907825 -227.11018)
			(xy 43.982965 -227.100118) (xy 44.058749 -227.098099) (xy 44.134319 -227.104148) (xy 44.208817 -227.118195)
			(xy 44.2814 -227.140081) (xy 44.351246 -227.169558) (xy 44.417563 -227.206293) (xy 44.479599 -227.249868)
			(xy 44.536652 -227.29979) (xy 44.588076 -227.355494) (xy 44.633287 -227.416349) (xy 44.671774 -227.481664)
			(xy 44.7031 -227.5507) (xy 44.72691 -227.622675) (xy 44.742935 -227.696773) (xy 44.750994 -227.772154)
			(xy 44.751498 -227.81006) (xy 45.867577 -227.81006) (xy 45.871612 -227.734356) (xy 45.883671 -227.659511)
			(xy 45.903617 -227.58637) (xy 45.931224 -227.515765) (xy 45.96618 -227.448494) (xy 46.008088 -227.385319)
			(xy 46.056474 -227.326957) (xy 46.11079 -227.274069) (xy 46.170419 -227.227254) (xy 46.234687 -227.187042)
			(xy 46.302864 -227.15389) (xy 46.37418 -227.128172) (xy 46.447825 -227.11018) (xy 46.522965 -227.100118)
			(xy 46.598749 -227.098099) (xy 46.674319 -227.104148) (xy 46.748817 -227.118195) (xy 46.8214 -227.140081)
			(xy 46.891246 -227.169558) (xy 46.957563 -227.206293) (xy 47.019599 -227.249868) (xy 47.076652 -227.29979)
			(xy 47.128076 -227.355494) (xy 47.173287 -227.416349) (xy 47.211774 -227.481664) (xy 47.2431 -227.5507)
			(xy 47.26691 -227.622675) (xy 47.282935 -227.696773) (xy 47.290994 -227.772154) (xy 47.291498 -227.81006)
			(xy 48.407577 -227.81006) (xy 48.411612 -227.734356) (xy 48.423671 -227.659511) (xy 48.443617 -227.58637)
			(xy 48.471224 -227.515765) (xy 48.50618 -227.448494) (xy 48.548088 -227.385319) (xy 48.596474 -227.326957)
			(xy 48.65079 -227.274069) (xy 48.710419 -227.227254) (xy 48.774687 -227.187042) (xy 48.842864 -227.15389)
			(xy 48.91418 -227.128172) (xy 48.987825 -227.11018) (xy 49.062965 -227.100118) (xy 49.138749 -227.098099)
			(xy 49.214319 -227.104148) (xy 49.288817 -227.118195) (xy 49.3614 -227.140081) (xy 49.431246 -227.169558)
			(xy 49.497563 -227.206293) (xy 49.559599 -227.249868) (xy 49.616652 -227.29979) (xy 49.668076 -227.355494)
			(xy 49.713287 -227.416349) (xy 49.751774 -227.481664) (xy 49.7831 -227.5507) (xy 49.80691 -227.622675)
			(xy 49.822935 -227.696773) (xy 49.830994 -227.772154) (xy 49.831498 -227.81006) (xy 50.947577 -227.81006)
			(xy 50.951612 -227.734356) (xy 50.963671 -227.659511) (xy 50.983617 -227.58637) (xy 51.011224 -227.515765)
			(xy 51.04618 -227.448494) (xy 51.088088 -227.385319) (xy 51.136474 -227.326957) (xy 51.19079 -227.274069)
			(xy 51.250419 -227.227254) (xy 51.314687 -227.187042) (xy 51.382864 -227.15389) (xy 51.45418 -227.128172)
			(xy 51.527825 -227.11018) (xy 51.602965 -227.100118) (xy 51.678749 -227.098099) (xy 51.754319 -227.104148)
			(xy 51.828817 -227.118195) (xy 51.9014 -227.140081) (xy 51.971246 -227.169558) (xy 52.037563 -227.206293)
			(xy 52.099599 -227.249868) (xy 52.156652 -227.29979) (xy 52.208076 -227.355494) (xy 52.253287 -227.416349)
			(xy 52.291774 -227.481664) (xy 52.3231 -227.5507) (xy 52.34691 -227.622675) (xy 52.362935 -227.696773)
			(xy 52.370994 -227.772154) (xy 52.371498 -227.81006) (xy 53.487577 -227.81006) (xy 53.491612 -227.734356)
			(xy 53.503671 -227.659511) (xy 53.523617 -227.58637) (xy 53.551224 -227.515765) (xy 53.58618 -227.448494)
			(xy 53.628088 -227.385319) (xy 53.676474 -227.326957) (xy 53.73079 -227.274069) (xy 53.790419 -227.227254)
			(xy 53.854687 -227.187042) (xy 53.922864 -227.15389) (xy 53.99418 -227.128172) (xy 54.067825 -227.11018)
			(xy 54.142965 -227.100118) (xy 54.218749 -227.098099) (xy 54.294319 -227.104148) (xy 54.368817 -227.118195)
			(xy 54.4414 -227.140081) (xy 54.511246 -227.169558) (xy 54.577563 -227.206293) (xy 54.639599 -227.249868)
			(xy 54.696652 -227.29979) (xy 54.748076 -227.355494) (xy 54.793287 -227.416349) (xy 54.831774 -227.481664)
			(xy 54.8631 -227.5507) (xy 54.88691 -227.622675) (xy 54.902935 -227.696773) (xy 54.910994 -227.772154)
			(xy 54.911498 -227.81006) (xy 56.027577 -227.81006) (xy 56.031612 -227.734356) (xy 56.043671 -227.659511)
			(xy 56.063617 -227.58637) (xy 56.091224 -227.515765) (xy 56.12618 -227.448494) (xy 56.168088 -227.385319)
			(xy 56.216474 -227.326957) (xy 56.27079 -227.274069) (xy 56.330419 -227.227254) (xy 56.394687 -227.187042)
			(xy 56.462864 -227.15389) (xy 56.53418 -227.128172) (xy 56.607825 -227.11018) (xy 56.682965 -227.100118)
			(xy 56.758749 -227.098099) (xy 56.834319 -227.104148) (xy 56.908817 -227.118195) (xy 56.9814 -227.140081)
			(xy 57.051246 -227.169558) (xy 57.117563 -227.206293) (xy 57.179599 -227.249868) (xy 57.236652 -227.29979)
			(xy 57.288076 -227.355494) (xy 57.333287 -227.416349) (xy 57.371774 -227.481664) (xy 57.4031 -227.5507)
			(xy 57.42691 -227.622675) (xy 57.442935 -227.696773) (xy 57.450994 -227.772154) (xy 57.451498 -227.81006)
			(xy 58.567577 -227.81006) (xy 58.571612 -227.734356) (xy 58.583671 -227.659511) (xy 58.603617 -227.58637)
			(xy 58.631224 -227.515765) (xy 58.66618 -227.448494) (xy 58.708088 -227.385319) (xy 58.756474 -227.326957)
			(xy 58.81079 -227.274069) (xy 58.870419 -227.227254) (xy 58.934687 -227.187042) (xy 59.002864 -227.15389)
			(xy 59.07418 -227.128172) (xy 59.147825 -227.11018) (xy 59.222965 -227.100118) (xy 59.298749 -227.098099)
			(xy 59.374319 -227.104148) (xy 59.448817 -227.118195) (xy 59.5214 -227.140081) (xy 59.591246 -227.169558)
			(xy 59.657563 -227.206293) (xy 59.719599 -227.249868) (xy 59.776652 -227.29979) (xy 59.828076 -227.355494)
			(xy 59.873287 -227.416349) (xy 59.911774 -227.481664) (xy 59.9431 -227.5507) (xy 59.96691 -227.622675)
			(xy 59.982935 -227.696773) (xy 59.990994 -227.772154) (xy 59.991498 -227.81006) (xy 61.107577 -227.81006)
			(xy 61.111612 -227.734356) (xy 61.123671 -227.659511) (xy 61.143617 -227.58637) (xy 61.171224 -227.515765)
			(xy 61.20618 -227.448494) (xy 61.248088 -227.385319) (xy 61.296474 -227.326957) (xy 61.35079 -227.274069)
			(xy 61.410419 -227.227254) (xy 61.474687 -227.187042) (xy 61.542864 -227.15389) (xy 61.61418 -227.128172)
			(xy 61.687825 -227.11018) (xy 61.762965 -227.100118) (xy 61.838749 -227.098099) (xy 61.914319 -227.104148)
			(xy 61.988817 -227.118195) (xy 62.0614 -227.140081) (xy 62.131246 -227.169558) (xy 62.197563 -227.206293)
			(xy 62.259599 -227.249868) (xy 62.265544 -227.25507) (xy 86.197697 -227.25507) (xy 86.201732 -227.179366)
			(xy 86.213791 -227.104521) (xy 86.233737 -227.03138) (xy 86.261344 -226.960775) (xy 86.2963 -226.893504)
			(xy 86.338208 -226.830329) (xy 86.386594 -226.771967) (xy 86.44091 -226.719079) (xy 86.500539 -226.672264)
			(xy 86.564807 -226.632052) (xy 86.632984 -226.5989) (xy 86.7043 -226.573182) (xy 86.777945 -226.55519)
			(xy 86.853085 -226.545128) (xy 86.928869 -226.543109) (xy 87.004439 -226.549158) (xy 87.078937 -226.563205)
			(xy 87.15152 -226.585091) (xy 87.221366 -226.614568) (xy 87.287683 -226.651303) (xy 87.349719 -226.694878)
			(xy 87.406772 -226.7448) (xy 87.458196 -226.800504) (xy 87.503407 -226.861359) (xy 87.541894 -226.926674)
			(xy 87.57322 -226.99571) (xy 87.59703 -227.067685) (xy 87.613055 -227.141783) (xy 87.621114 -227.217164)
			(xy 87.621618 -227.25507) (xy 88.737697 -227.25507) (xy 88.741732 -227.179366) (xy 88.753791 -227.104521)
			(xy 88.773737 -227.03138) (xy 88.801344 -226.960775) (xy 88.8363 -226.893504) (xy 88.878208 -226.830329)
			(xy 88.926594 -226.771967) (xy 88.98091 -226.719079) (xy 89.040539 -226.672264) (xy 89.104807 -226.632052)
			(xy 89.172984 -226.5989) (xy 89.2443 -226.573182) (xy 89.317945 -226.55519) (xy 89.393085 -226.545128)
			(xy 89.468869 -226.543109) (xy 89.544439 -226.549158) (xy 89.618937 -226.563205) (xy 89.69152 -226.585091)
			(xy 89.761366 -226.614568) (xy 89.827683 -226.651303) (xy 89.889719 -226.694878) (xy 89.946772 -226.7448)
			(xy 89.998196 -226.800504) (xy 90.043407 -226.861359) (xy 90.081894 -226.926674) (xy 90.11322 -226.99571)
			(xy 90.13703 -227.067685) (xy 90.153055 -227.141783) (xy 90.161114 -227.217164) (xy 90.161618 -227.25507)
			(xy 91.277697 -227.25507) (xy 91.281732 -227.179366) (xy 91.293791 -227.104521) (xy 91.313737 -227.03138)
			(xy 91.341344 -226.960775) (xy 91.3763 -226.893504) (xy 91.418208 -226.830329) (xy 91.466594 -226.771967)
			(xy 91.52091 -226.719079) (xy 91.580539 -226.672264) (xy 91.644807 -226.632052) (xy 91.712984 -226.5989)
			(xy 91.7843 -226.573182) (xy 91.857945 -226.55519) (xy 91.933085 -226.545128) (xy 92.008869 -226.543109)
			(xy 92.084439 -226.549158) (xy 92.158937 -226.563205) (xy 92.23152 -226.585091) (xy 92.301366 -226.614568)
			(xy 92.367683 -226.651303) (xy 92.429719 -226.694878) (xy 92.486772 -226.7448) (xy 92.538196 -226.800504)
			(xy 92.583407 -226.861359) (xy 92.621894 -226.926674) (xy 92.65322 -226.99571) (xy 92.67703 -227.067685)
			(xy 92.693055 -227.141783) (xy 92.701114 -227.217164) (xy 92.701618 -227.25507) (xy 92.701114 -227.292976)
			(xy 92.693055 -227.368357) (xy 92.67703 -227.442455) (xy 92.65322 -227.51443) (xy 92.621894 -227.583466)
			(xy 92.583407 -227.648781) (xy 92.538196 -227.709636) (xy 92.486772 -227.76534) (xy 92.429719 -227.815262)
			(xy 92.367683 -227.858837) (xy 92.301366 -227.895572) (xy 92.23152 -227.925049) (xy 92.158937 -227.946935)
			(xy 92.084439 -227.960982) (xy 92.008869 -227.967031) (xy 91.933085 -227.965012) (xy 91.857945 -227.95495)
			(xy 91.7843 -227.936958) (xy 91.712984 -227.91124) (xy 91.644807 -227.878088) (xy 91.580539 -227.837876)
			(xy 91.52091 -227.791061) (xy 91.466594 -227.738173) (xy 91.418208 -227.679811) (xy 91.3763 -227.616636)
			(xy 91.341344 -227.549365) (xy 91.313737 -227.47876) (xy 91.293791 -227.405619) (xy 91.281732 -227.330774)
			(xy 91.277697 -227.25507) (xy 90.161618 -227.25507) (xy 90.161114 -227.292976) (xy 90.153055 -227.368357)
			(xy 90.13703 -227.442455) (xy 90.11322 -227.51443) (xy 90.081894 -227.583466) (xy 90.043407 -227.648781)
			(xy 89.998196 -227.709636) (xy 89.946772 -227.76534) (xy 89.889719 -227.815262) (xy 89.827683 -227.858837)
			(xy 89.761366 -227.895572) (xy 89.69152 -227.925049) (xy 89.618937 -227.946935) (xy 89.544439 -227.960982)
			(xy 89.468869 -227.967031) (xy 89.393085 -227.965012) (xy 89.317945 -227.95495) (xy 89.2443 -227.936958)
			(xy 89.172984 -227.91124) (xy 89.104807 -227.878088) (xy 89.040539 -227.837876) (xy 88.98091 -227.791061)
			(xy 88.926594 -227.738173) (xy 88.878208 -227.679811) (xy 88.8363 -227.616636) (xy 88.801344 -227.549365)
			(xy 88.773737 -227.47876) (xy 88.753791 -227.405619) (xy 88.741732 -227.330774) (xy 88.737697 -227.25507)
			(xy 87.621618 -227.25507) (xy 87.621114 -227.292976) (xy 87.613055 -227.368357) (xy 87.59703 -227.442455)
			(xy 87.57322 -227.51443) (xy 87.541894 -227.583466) (xy 87.503407 -227.648781) (xy 87.458196 -227.709636)
			(xy 87.406772 -227.76534) (xy 87.349719 -227.815262) (xy 87.287683 -227.858837) (xy 87.221366 -227.895572)
			(xy 87.15152 -227.925049) (xy 87.078937 -227.946935) (xy 87.004439 -227.960982) (xy 86.928869 -227.967031)
			(xy 86.853085 -227.965012) (xy 86.777945 -227.95495) (xy 86.7043 -227.936958) (xy 86.632984 -227.91124)
			(xy 86.564807 -227.878088) (xy 86.500539 -227.837876) (xy 86.44091 -227.791061) (xy 86.386594 -227.738173)
			(xy 86.338208 -227.679811) (xy 86.2963 -227.616636) (xy 86.261344 -227.549365) (xy 86.233737 -227.47876)
			(xy 86.213791 -227.405619) (xy 86.201732 -227.330774) (xy 86.197697 -227.25507) (xy 62.265544 -227.25507)
			(xy 62.316652 -227.29979) (xy 62.368076 -227.355494) (xy 62.413287 -227.416349) (xy 62.451774 -227.481664)
			(xy 62.4831 -227.5507) (xy 62.50691 -227.622675) (xy 62.522935 -227.696773) (xy 62.530994 -227.772154)
			(xy 62.531498 -227.81006) (xy 62.530994 -227.847966) (xy 62.522935 -227.923347) (xy 62.50691 -227.997445)
			(xy 62.4831 -228.06942) (xy 62.451774 -228.138456) (xy 62.413287 -228.203771) (xy 62.368076 -228.264626)
			(xy 62.316652 -228.32033) (xy 62.259599 -228.370252) (xy 62.197563 -228.413827) (xy 62.131246 -228.450562)
			(xy 62.0614 -228.480039) (xy 61.988817 -228.501925) (xy 61.914319 -228.515972) (xy 61.838749 -228.522021)
			(xy 61.762965 -228.520002) (xy 61.687825 -228.50994) (xy 61.61418 -228.491948) (xy 61.542864 -228.46623)
			(xy 61.474687 -228.433078) (xy 61.410419 -228.392866) (xy 61.35079 -228.346051) (xy 61.296474 -228.293163)
			(xy 61.248088 -228.234801) (xy 61.20618 -228.171626) (xy 61.171224 -228.104355) (xy 61.143617 -228.03375)
			(xy 61.123671 -227.960609) (xy 61.111612 -227.885764) (xy 61.107577 -227.81006) (xy 59.991498 -227.81006)
			(xy 59.990994 -227.847966) (xy 59.982935 -227.923347) (xy 59.96691 -227.997445) (xy 59.9431 -228.06942)
			(xy 59.911774 -228.138456) (xy 59.873287 -228.203771) (xy 59.828076 -228.264626) (xy 59.776652 -228.32033)
			(xy 59.719599 -228.370252) (xy 59.657563 -228.413827) (xy 59.591246 -228.450562) (xy 59.5214 -228.480039)
			(xy 59.448817 -228.501925) (xy 59.374319 -228.515972) (xy 59.298749 -228.522021) (xy 59.222965 -228.520002)
			(xy 59.147825 -228.50994) (xy 59.07418 -228.491948) (xy 59.002864 -228.46623) (xy 58.934687 -228.433078)
			(xy 58.870419 -228.392866) (xy 58.81079 -228.346051) (xy 58.756474 -228.293163) (xy 58.708088 -228.234801)
			(xy 58.66618 -228.171626) (xy 58.631224 -228.104355) (xy 58.603617 -228.03375) (xy 58.583671 -227.960609)
			(xy 58.571612 -227.885764) (xy 58.567577 -227.81006) (xy 57.451498 -227.81006) (xy 57.450994 -227.847966)
			(xy 57.442935 -227.923347) (xy 57.42691 -227.997445) (xy 57.4031 -228.06942) (xy 57.371774 -228.138456)
			(xy 57.333287 -228.203771) (xy 57.288076 -228.264626) (xy 57.236652 -228.32033) (xy 57.179599 -228.370252)
			(xy 57.117563 -228.413827) (xy 57.051246 -228.450562) (xy 56.9814 -228.480039) (xy 56.908817 -228.501925)
			(xy 56.834319 -228.515972) (xy 56.758749 -228.522021) (xy 56.682965 -228.520002) (xy 56.607825 -228.50994)
			(xy 56.53418 -228.491948) (xy 56.462864 -228.46623) (xy 56.394687 -228.433078) (xy 56.330419 -228.392866)
			(xy 56.27079 -228.346051) (xy 56.216474 -228.293163) (xy 56.168088 -228.234801) (xy 56.12618 -228.171626)
			(xy 56.091224 -228.104355) (xy 56.063617 -228.03375) (xy 56.043671 -227.960609) (xy 56.031612 -227.885764)
			(xy 56.027577 -227.81006) (xy 54.911498 -227.81006) (xy 54.910994 -227.847966) (xy 54.902935 -227.923347)
			(xy 54.88691 -227.997445) (xy 54.8631 -228.06942) (xy 54.831774 -228.138456) (xy 54.793287 -228.203771)
			(xy 54.748076 -228.264626) (xy 54.696652 -228.32033) (xy 54.639599 -228.370252) (xy 54.577563 -228.413827)
			(xy 54.511246 -228.450562) (xy 54.4414 -228.480039) (xy 54.368817 -228.501925) (xy 54.294319 -228.515972)
			(xy 54.218749 -228.522021) (xy 54.142965 -228.520002) (xy 54.067825 -228.50994) (xy 53.99418 -228.491948)
			(xy 53.922864 -228.46623) (xy 53.854687 -228.433078) (xy 53.790419 -228.392866) (xy 53.73079 -228.346051)
			(xy 53.676474 -228.293163) (xy 53.628088 -228.234801) (xy 53.58618 -228.171626) (xy 53.551224 -228.104355)
			(xy 53.523617 -228.03375) (xy 53.503671 -227.960609) (xy 53.491612 -227.885764) (xy 53.487577 -227.81006)
			(xy 52.371498 -227.81006) (xy 52.370994 -227.847966) (xy 52.362935 -227.923347) (xy 52.34691 -227.997445)
			(xy 52.3231 -228.06942) (xy 52.291774 -228.138456) (xy 52.253287 -228.203771) (xy 52.208076 -228.264626)
			(xy 52.156652 -228.32033) (xy 52.099599 -228.370252) (xy 52.037563 -228.413827) (xy 51.971246 -228.450562)
			(xy 51.9014 -228.480039) (xy 51.828817 -228.501925) (xy 51.754319 -228.515972) (xy 51.678749 -228.522021)
			(xy 51.602965 -228.520002) (xy 51.527825 -228.50994) (xy 51.45418 -228.491948) (xy 51.382864 -228.46623)
			(xy 51.314687 -228.433078) (xy 51.250419 -228.392866) (xy 51.19079 -228.346051) (xy 51.136474 -228.293163)
			(xy 51.088088 -228.234801) (xy 51.04618 -228.171626) (xy 51.011224 -228.104355) (xy 50.983617 -228.03375)
			(xy 50.963671 -227.960609) (xy 50.951612 -227.885764) (xy 50.947577 -227.81006) (xy 49.831498 -227.81006)
			(xy 49.830994 -227.847966) (xy 49.822935 -227.923347) (xy 49.80691 -227.997445) (xy 49.7831 -228.06942)
			(xy 49.751774 -228.138456) (xy 49.713287 -228.203771) (xy 49.668076 -228.264626) (xy 49.616652 -228.32033)
			(xy 49.559599 -228.370252) (xy 49.497563 -228.413827) (xy 49.431246 -228.450562) (xy 49.3614 -228.480039)
			(xy 49.288817 -228.501925) (xy 49.214319 -228.515972) (xy 49.138749 -228.522021) (xy 49.062965 -228.520002)
			(xy 48.987825 -228.50994) (xy 48.91418 -228.491948) (xy 48.842864 -228.46623) (xy 48.774687 -228.433078)
			(xy 48.710419 -228.392866) (xy 48.65079 -228.346051) (xy 48.596474 -228.293163) (xy 48.548088 -228.234801)
			(xy 48.50618 -228.171626) (xy 48.471224 -228.104355) (xy 48.443617 -228.03375) (xy 48.423671 -227.960609)
			(xy 48.411612 -227.885764) (xy 48.407577 -227.81006) (xy 47.291498 -227.81006) (xy 47.290994 -227.847966)
			(xy 47.282935 -227.923347) (xy 47.26691 -227.997445) (xy 47.2431 -228.06942) (xy 47.211774 -228.138456)
			(xy 47.173287 -228.203771) (xy 47.128076 -228.264626) (xy 47.076652 -228.32033) (xy 47.019599 -228.370252)
			(xy 46.957563 -228.413827) (xy 46.891246 -228.450562) (xy 46.8214 -228.480039) (xy 46.748817 -228.501925)
			(xy 46.674319 -228.515972) (xy 46.598749 -228.522021) (xy 46.522965 -228.520002) (xy 46.447825 -228.50994)
			(xy 46.37418 -228.491948) (xy 46.302864 -228.46623) (xy 46.234687 -228.433078) (xy 46.170419 -228.392866)
			(xy 46.11079 -228.346051) (xy 46.056474 -228.293163) (xy 46.008088 -228.234801) (xy 45.96618 -228.171626)
			(xy 45.931224 -228.104355) (xy 45.903617 -228.03375) (xy 45.883671 -227.960609) (xy 45.871612 -227.885764)
			(xy 45.867577 -227.81006) (xy 44.751498 -227.81006) (xy 44.750994 -227.847966) (xy 44.742935 -227.923347)
			(xy 44.72691 -227.997445) (xy 44.7031 -228.06942) (xy 44.671774 -228.138456) (xy 44.633287 -228.203771)
			(xy 44.588076 -228.264626) (xy 44.536652 -228.32033) (xy 44.479599 -228.370252) (xy 44.417563 -228.413827)
			(xy 44.351246 -228.450562) (xy 44.2814 -228.480039) (xy 44.208817 -228.501925) (xy 44.134319 -228.515972)
			(xy 44.058749 -228.522021) (xy 43.982965 -228.520002) (xy 43.907825 -228.50994) (xy 43.83418 -228.491948)
			(xy 43.762864 -228.46623) (xy 43.694687 -228.433078) (xy 43.630419 -228.392866) (xy 43.57079 -228.346051)
			(xy 43.516474 -228.293163) (xy 43.468088 -228.234801) (xy 43.42618 -228.171626) (xy 43.391224 -228.104355)
			(xy 43.363617 -228.03375) (xy 43.343671 -227.960609) (xy 43.331612 -227.885764) (xy 43.327577 -227.81006)
			(xy 42.501239 -227.81006) (xy 42.515699 -227.820266) (xy 42.604766 -227.892723) (xy 42.688681 -227.971089)
			(xy 42.767054 -228.054998) (xy 42.839517 -228.14406) (xy 42.905734 -228.237859) (xy 42.965396 -228.335958)
			(xy 43.018225 -228.4379) (xy 43.056094 -228.52507) (xy 84.927697 -228.52507) (xy 84.931732 -228.449366)
			(xy 84.943791 -228.374521) (xy 84.963737 -228.30138) (xy 84.991344 -228.230775) (xy 85.0263 -228.163504)
			(xy 85.068208 -228.100329) (xy 85.116594 -228.041967) (xy 85.17091 -227.989079) (xy 85.230539 -227.942264)
			(xy 85.294807 -227.902052) (xy 85.362984 -227.8689) (xy 85.4343 -227.843182) (xy 85.507945 -227.82519)
			(xy 85.583085 -227.815128) (xy 85.658869 -227.813109) (xy 85.734439 -227.819158) (xy 85.808937 -227.833205)
			(xy 85.88152 -227.855091) (xy 85.951366 -227.884568) (xy 86.017683 -227.921303) (xy 86.079719 -227.964878)
			(xy 86.136772 -228.0148) (xy 86.188196 -228.070504) (xy 86.233407 -228.131359) (xy 86.271894 -228.196674)
			(xy 86.30322 -228.26571) (xy 86.32703 -228.337685) (xy 86.343055 -228.411783) (xy 86.351114 -228.487164)
			(xy 86.351618 -228.52507) (xy 87.467697 -228.52507) (xy 87.471732 -228.449366) (xy 87.483791 -228.374521)
			(xy 87.503737 -228.30138) (xy 87.531344 -228.230775) (xy 87.5663 -228.163504) (xy 87.608208 -228.100329)
			(xy 87.656594 -228.041967) (xy 87.71091 -227.989079) (xy 87.770539 -227.942264) (xy 87.834807 -227.902052)
			(xy 87.902984 -227.8689) (xy 87.9743 -227.843182) (xy 88.047945 -227.82519) (xy 88.123085 -227.815128)
			(xy 88.198869 -227.813109) (xy 88.274439 -227.819158) (xy 88.348937 -227.833205) (xy 88.42152 -227.855091)
			(xy 88.491366 -227.884568) (xy 88.557683 -227.921303) (xy 88.619719 -227.964878) (xy 88.676772 -228.0148)
			(xy 88.728196 -228.070504) (xy 88.773407 -228.131359) (xy 88.811894 -228.196674) (xy 88.84322 -228.26571)
			(xy 88.86703 -228.337685) (xy 88.883055 -228.411783) (xy 88.891114 -228.487164) (xy 88.891618 -228.52507)
			(xy 90.007697 -228.52507) (xy 90.011732 -228.449366) (xy 90.023791 -228.374521) (xy 90.043737 -228.30138)
			(xy 90.071344 -228.230775) (xy 90.1063 -228.163504) (xy 90.148208 -228.100329) (xy 90.196594 -228.041967)
			(xy 90.25091 -227.989079) (xy 90.310539 -227.942264) (xy 90.374807 -227.902052) (xy 90.442984 -227.8689)
			(xy 90.5143 -227.843182) (xy 90.587945 -227.82519) (xy 90.663085 -227.815128) (xy 90.738869 -227.813109)
			(xy 90.814439 -227.819158) (xy 90.888937 -227.833205) (xy 90.96152 -227.855091) (xy 91.031366 -227.884568)
			(xy 91.097683 -227.921303) (xy 91.159719 -227.964878) (xy 91.216772 -228.0148) (xy 91.268196 -228.070504)
			(xy 91.313407 -228.131359) (xy 91.351894 -228.196674) (xy 91.38322 -228.26571) (xy 91.40703 -228.337685)
			(xy 91.423055 -228.411783) (xy 91.431114 -228.487164) (xy 91.431618 -228.52507) (xy 91.431114 -228.562976)
			(xy 91.423055 -228.638357) (xy 91.40703 -228.712455) (xy 91.38322 -228.78443) (xy 91.351894 -228.853466)
			(xy 91.313407 -228.918781) (xy 91.268196 -228.979636) (xy 91.216772 -229.03534) (xy 91.159719 -229.085262)
			(xy 91.097683 -229.128837) (xy 91.031366 -229.165572) (xy 90.96152 -229.195049) (xy 90.888937 -229.216935)
			(xy 90.814439 -229.230982) (xy 90.738869 -229.237031) (xy 90.663085 -229.235012) (xy 90.587945 -229.22495)
			(xy 90.5143 -229.206958) (xy 90.442984 -229.18124) (xy 90.374807 -229.148088) (xy 90.310539 -229.107876)
			(xy 90.25091 -229.061061) (xy 90.196594 -229.008173) (xy 90.148208 -228.949811) (xy 90.1063 -228.886636)
			(xy 90.071344 -228.819365) (xy 90.043737 -228.74876) (xy 90.023791 -228.675619) (xy 90.011732 -228.600774)
			(xy 90.007697 -228.52507) (xy 88.891618 -228.52507) (xy 88.891114 -228.562976) (xy 88.883055 -228.638357)
			(xy 88.86703 -228.712455) (xy 88.84322 -228.78443) (xy 88.811894 -228.853466) (xy 88.773407 -228.918781)
			(xy 88.728196 -228.979636) (xy 88.676772 -229.03534) (xy 88.619719 -229.085262) (xy 88.557683 -229.128837)
			(xy 88.491366 -229.165572) (xy 88.42152 -229.195049) (xy 88.348937 -229.216935) (xy 88.274439 -229.230982)
			(xy 88.198869 -229.237031) (xy 88.123085 -229.235012) (xy 88.047945 -229.22495) (xy 87.9743 -229.206958)
			(xy 87.902984 -229.18124) (xy 87.834807 -229.148088) (xy 87.770539 -229.107876) (xy 87.71091 -229.061061)
			(xy 87.656594 -229.008173) (xy 87.608208 -228.949811) (xy 87.5663 -228.886636) (xy 87.531344 -228.819365)
			(xy 87.503737 -228.74876) (xy 87.483791 -228.675619) (xy 87.471732 -228.600774) (xy 87.467697 -228.52507)
			(xy 86.351618 -228.52507) (xy 86.351114 -228.562976) (xy 86.343055 -228.638357) (xy 86.32703 -228.712455)
			(xy 86.30322 -228.78443) (xy 86.271894 -228.853466) (xy 86.233407 -228.918781) (xy 86.188196 -228.979636)
			(xy 86.136772 -229.03534) (xy 86.079719 -229.085262) (xy 86.017683 -229.128837) (xy 85.951366 -229.165572)
			(xy 85.88152 -229.195049) (xy 85.808937 -229.216935) (xy 85.734439 -229.230982) (xy 85.658869 -229.237031)
			(xy 85.583085 -229.235012) (xy 85.507945 -229.22495) (xy 85.4343 -229.206958) (xy 85.362984 -229.18124)
			(xy 85.294807 -229.148088) (xy 85.230539 -229.107876) (xy 85.17091 -229.061061) (xy 85.116594 -229.008173)
			(xy 85.068208 -228.949811) (xy 85.0263 -228.886636) (xy 84.991344 -228.819365) (xy 84.963737 -228.74876)
			(xy 84.943791 -228.675619) (xy 84.931732 -228.600774) (xy 84.927697 -228.52507) (xy 43.056094 -228.52507)
			(xy 43.063974 -228.543209) (xy 43.10243 -228.651394) (xy 43.133415 -228.761952) (xy 43.156782 -228.874366)
			(xy 43.172424 -228.988113) (xy 43.180268 -229.102661) (xy 43.180762 -229.16007) (xy 43.180576 -229.193253)
			(xy 43.177909 -229.259567) (xy 43.175428 -229.292658) (xy 43.170272 -229.350942) (xy 43.152948 -229.466671)
			(xy 43.127616 -229.580914) (xy 43.094401 -229.693119) (xy 43.056327 -229.79507) (xy 86.197697 -229.79507)
			(xy 86.201732 -229.719366) (xy 86.213791 -229.644521) (xy 86.233737 -229.57138) (xy 86.261344 -229.500775)
			(xy 86.2963 -229.433504) (xy 86.338208 -229.370329) (xy 86.386594 -229.311967) (xy 86.44091 -229.259079)
			(xy 86.500539 -229.212264) (xy 86.564807 -229.172052) (xy 86.632984 -229.1389) (xy 86.7043 -229.113182)
			(xy 86.777945 -229.09519) (xy 86.853085 -229.085128) (xy 86.928869 -229.083109) (xy 87.004439 -229.089158)
			(xy 87.078937 -229.103205) (xy 87.15152 -229.125091) (xy 87.221366 -229.154568) (xy 87.287683 -229.191303)
			(xy 87.349719 -229.234878) (xy 87.406772 -229.2848) (xy 87.458196 -229.340504) (xy 87.503407 -229.401359)
			(xy 87.541894 -229.466674) (xy 87.57322 -229.53571) (xy 87.59703 -229.607685) (xy 87.613055 -229.681783)
			(xy 87.621114 -229.757164) (xy 87.621618 -229.79507) (xy 88.737697 -229.79507) (xy 88.741732 -229.719366)
			(xy 88.753791 -229.644521) (xy 88.773737 -229.57138) (xy 88.801344 -229.500775) (xy 88.8363 -229.433504)
			(xy 88.878208 -229.370329) (xy 88.926594 -229.311967) (xy 88.98091 -229.259079) (xy 89.040539 -229.212264)
			(xy 89.104807 -229.172052) (xy 89.172984 -229.1389) (xy 89.2443 -229.113182) (xy 89.317945 -229.09519)
			(xy 89.393085 -229.085128) (xy 89.468869 -229.083109) (xy 89.544439 -229.089158) (xy 89.618937 -229.103205)
			(xy 89.69152 -229.125091) (xy 89.761366 -229.154568) (xy 89.827683 -229.191303) (xy 89.889719 -229.234878)
			(xy 89.946772 -229.2848) (xy 89.998196 -229.340504) (xy 90.043407 -229.401359) (xy 90.081894 -229.466674)
			(xy 90.11322 -229.53571) (xy 90.13703 -229.607685) (xy 90.153055 -229.681783) (xy 90.161114 -229.757164)
			(xy 90.161618 -229.79507) (xy 91.277697 -229.79507) (xy 91.281732 -229.719366) (xy 91.293791 -229.644521)
			(xy 91.313737 -229.57138) (xy 91.341344 -229.500775) (xy 91.3763 -229.433504) (xy 91.418208 -229.370329)
			(xy 91.466594 -229.311967) (xy 91.52091 -229.259079) (xy 91.580539 -229.212264) (xy 91.644807 -229.172052)
			(xy 91.712984 -229.1389) (xy 91.7843 -229.113182) (xy 91.857945 -229.09519) (xy 91.933085 -229.085128)
			(xy 92.008869 -229.083109) (xy 92.084439 -229.089158) (xy 92.158937 -229.103205) (xy 92.23152 -229.125091)
			(xy 92.301366 -229.154568) (xy 92.367683 -229.191303) (xy 92.429719 -229.234878) (xy 92.486772 -229.2848)
			(xy 92.538196 -229.340504) (xy 92.583407 -229.401359) (xy 92.621894 -229.466674) (xy 92.65322 -229.53571)
			(xy 92.67703 -229.607685) (xy 92.693055 -229.681783) (xy 92.701114 -229.757164) (xy 92.701618 -229.79507)
			(xy 92.701114 -229.832976) (xy 92.693055 -229.908357) (xy 92.67703 -229.982455) (xy 92.65322 -230.05443)
			(xy 92.621894 -230.123466) (xy 92.583407 -230.188781) (xy 92.538196 -230.249636) (xy 92.486772 -230.30534)
			(xy 92.429719 -230.355262) (xy 92.367683 -230.398837) (xy 92.301366 -230.435572) (xy 92.23152 -230.465049)
			(xy 92.158937 -230.486935) (xy 92.084439 -230.500982) (xy 92.008869 -230.507031) (xy 91.933085 -230.505012)
			(xy 91.857945 -230.49495) (xy 91.7843 -230.476958) (xy 91.712984 -230.45124) (xy 91.644807 -230.418088)
			(xy 91.580539 -230.377876) (xy 91.52091 -230.331061) (xy 91.466594 -230.278173) (xy 91.418208 -230.219811)
			(xy 91.3763 -230.156636) (xy 91.341344 -230.089365) (xy 91.313737 -230.01876) (xy 91.293791 -229.945619)
			(xy 91.281732 -229.870774) (xy 91.277697 -229.79507) (xy 90.161618 -229.79507) (xy 90.161114 -229.832976)
			(xy 90.153055 -229.908357) (xy 90.13703 -229.982455) (xy 90.11322 -230.05443) (xy 90.081894 -230.123466)
			(xy 90.043407 -230.188781) (xy 89.998196 -230.249636) (xy 89.946772 -230.30534) (xy 89.889719 -230.355262)
			(xy 89.827683 -230.398837) (xy 89.761366 -230.435572) (xy 89.69152 -230.465049) (xy 89.618937 -230.486935)
			(xy 89.544439 -230.500982) (xy 89.468869 -230.507031) (xy 89.393085 -230.505012) (xy 89.317945 -230.49495)
			(xy 89.2443 -230.476958) (xy 89.172984 -230.45124) (xy 89.104807 -230.418088) (xy 89.040539 -230.377876)
			(xy 88.98091 -230.331061) (xy 88.926594 -230.278173) (xy 88.878208 -230.219811) (xy 88.8363 -230.156636)
			(xy 88.801344 -230.089365) (xy 88.773737 -230.01876) (xy 88.753791 -229.945619) (xy 88.741732 -229.870774)
			(xy 88.737697 -229.79507) (xy 87.621618 -229.79507) (xy 87.621114 -229.832976) (xy 87.613055 -229.908357)
			(xy 87.59703 -229.982455) (xy 87.57322 -230.05443) (xy 87.541894 -230.123466) (xy 87.503407 -230.188781)
			(xy 87.458196 -230.249636) (xy 87.406772 -230.30534) (xy 87.349719 -230.355262) (xy 87.287683 -230.398837)
			(xy 87.221366 -230.435572) (xy 87.15152 -230.465049) (xy 87.078937 -230.486935) (xy 87.004439 -230.500982)
			(xy 86.928869 -230.507031) (xy 86.853085 -230.505012) (xy 86.777945 -230.49495) (xy 86.7043 -230.476958)
			(xy 86.632984 -230.45124) (xy 86.564807 -230.418088) (xy 86.500539 -230.377876) (xy 86.44091 -230.331061)
			(xy 86.386594 -230.278173) (xy 86.338208 -230.219811) (xy 86.2963 -230.156636) (xy 86.261344 -230.089365)
			(xy 86.233737 -230.01876) (xy 86.213791 -229.945619) (xy 86.201732 -229.870774) (xy 86.197697 -229.79507)
			(xy 43.056327 -229.79507) (xy 43.055094 -229.798372) (xy 43.328336 -229.798372) (xy 44.751244 -229.798372)
			(xy 44.751244 -230.51008) (xy 45.867577 -230.51008) (xy 45.871612 -230.434376) (xy 45.883671 -230.359531)
			(xy 45.903617 -230.28639) (xy 45.931224 -230.215785) (xy 45.96618 -230.148514) (xy 46.008088 -230.085339)
			(xy 46.056474 -230.026977) (xy 46.11079 -229.974089) (xy 46.170419 -229.927274) (xy 46.234687 -229.887062)
			(xy 46.302864 -229.85391) (xy 46.37418 -229.828192) (xy 46.447825 -229.8102) (xy 46.522965 -229.800138)
			(xy 46.598749 -229.798119) (xy 46.674319 -229.804168) (xy 46.748817 -229.818215) (xy 46.8214 -229.840101)
			(xy 46.891246 -229.869578) (xy 46.957563 -229.906313) (xy 47.019599 -229.949888) (xy 47.076652 -229.99981)
			(xy 47.128076 -230.055514) (xy 47.173287 -230.116369) (xy 47.211774 -230.181684) (xy 47.2431 -230.25072)
			(xy 47.26691 -230.322695) (xy 47.282935 -230.396793) (xy 47.290994 -230.472174) (xy 47.291498 -230.51008)
			(xy 48.407577 -230.51008) (xy 48.411612 -230.434376) (xy 48.423671 -230.359531) (xy 48.443617 -230.28639)
			(xy 48.471224 -230.215785) (xy 48.50618 -230.148514) (xy 48.548088 -230.085339) (xy 48.596474 -230.026977)
			(xy 48.65079 -229.974089) (xy 48.710419 -229.927274) (xy 48.774687 -229.887062) (xy 48.842864 -229.85391)
			(xy 48.91418 -229.828192) (xy 48.987825 -229.8102) (xy 49.062965 -229.800138) (xy 49.138749 -229.798119)
			(xy 49.214319 -229.804168) (xy 49.288817 -229.818215) (xy 49.3614 -229.840101) (xy 49.431246 -229.869578)
			(xy 49.497563 -229.906313) (xy 49.559599 -229.949888) (xy 49.616652 -229.99981) (xy 49.668076 -230.055514)
			(xy 49.713287 -230.116369) (xy 49.751774 -230.181684) (xy 49.7831 -230.25072) (xy 49.80691 -230.322695)
			(xy 49.822935 -230.396793) (xy 49.830994 -230.472174) (xy 49.831498 -230.51008) (xy 50.947577 -230.51008)
			(xy 50.951612 -230.434376) (xy 50.963671 -230.359531) (xy 50.983617 -230.28639) (xy 51.011224 -230.215785)
			(xy 51.04618 -230.148514) (xy 51.088088 -230.085339) (xy 51.136474 -230.026977) (xy 51.19079 -229.974089)
			(xy 51.250419 -229.927274) (xy 51.314687 -229.887062) (xy 51.382864 -229.85391) (xy 51.45418 -229.828192)
			(xy 51.527825 -229.8102) (xy 51.602965 -229.800138) (xy 51.678749 -229.798119) (xy 51.754319 -229.804168)
			(xy 51.828817 -229.818215) (xy 51.9014 -229.840101) (xy 51.971246 -229.869578) (xy 52.037563 -229.906313)
			(xy 52.099599 -229.949888) (xy 52.156652 -229.99981) (xy 52.208076 -230.055514) (xy 52.253287 -230.116369)
			(xy 52.291774 -230.181684) (xy 52.3231 -230.25072) (xy 52.34691 -230.322695) (xy 52.362935 -230.396793)
			(xy 52.370994 -230.472174) (xy 52.371498 -230.51008) (xy 53.487577 -230.51008) (xy 53.491612 -230.434376)
			(xy 53.503671 -230.359531) (xy 53.523617 -230.28639) (xy 53.551224 -230.215785) (xy 53.58618 -230.148514)
			(xy 53.628088 -230.085339) (xy 53.676474 -230.026977) (xy 53.73079 -229.974089) (xy 53.790419 -229.927274)
			(xy 53.854687 -229.887062) (xy 53.922864 -229.85391) (xy 53.99418 -229.828192) (xy 54.067825 -229.8102)
			(xy 54.142965 -229.800138) (xy 54.218749 -229.798119) (xy 54.294319 -229.804168) (xy 54.368817 -229.818215)
			(xy 54.4414 -229.840101) (xy 54.511246 -229.869578) (xy 54.577563 -229.906313) (xy 54.639599 -229.949888)
			(xy 54.696652 -229.99981) (xy 54.748076 -230.055514) (xy 54.793287 -230.116369) (xy 54.831774 -230.181684)
			(xy 54.8631 -230.25072) (xy 54.88691 -230.322695) (xy 54.902935 -230.396793) (xy 54.910994 -230.472174)
			(xy 54.911498 -230.51008) (xy 56.027577 -230.51008) (xy 56.031612 -230.434376) (xy 56.043671 -230.359531)
			(xy 56.063617 -230.28639) (xy 56.091224 -230.215785) (xy 56.12618 -230.148514) (xy 56.168088 -230.085339)
			(xy 56.216474 -230.026977) (xy 56.27079 -229.974089) (xy 56.330419 -229.927274) (xy 56.394687 -229.887062)
			(xy 56.462864 -229.85391) (xy 56.53418 -229.828192) (xy 56.607825 -229.8102) (xy 56.682965 -229.800138)
			(xy 56.758749 -229.798119) (xy 56.834319 -229.804168) (xy 56.908817 -229.818215) (xy 56.9814 -229.840101)
			(xy 57.051246 -229.869578) (xy 57.117563 -229.906313) (xy 57.179599 -229.949888) (xy 57.236652 -229.99981)
			(xy 57.288076 -230.055514) (xy 57.333287 -230.116369) (xy 57.371774 -230.181684) (xy 57.4031 -230.25072)
			(xy 57.42691 -230.322695) (xy 57.442935 -230.396793) (xy 57.450994 -230.472174) (xy 57.451498 -230.51008)
			(xy 58.567577 -230.51008) (xy 58.571612 -230.434376) (xy 58.583671 -230.359531) (xy 58.603617 -230.28639)
			(xy 58.631224 -230.215785) (xy 58.66618 -230.148514) (xy 58.708088 -230.085339) (xy 58.756474 -230.026977)
			(xy 58.81079 -229.974089) (xy 58.870419 -229.927274) (xy 58.934687 -229.887062) (xy 59.002864 -229.85391)
			(xy 59.07418 -229.828192) (xy 59.147825 -229.8102) (xy 59.222965 -229.800138) (xy 59.298749 -229.798119)
			(xy 59.374319 -229.804168) (xy 59.448817 -229.818215) (xy 59.5214 -229.840101) (xy 59.591246 -229.869578)
			(xy 59.657563 -229.906313) (xy 59.719599 -229.949888) (xy 59.776652 -229.99981) (xy 59.828076 -230.055514)
			(xy 59.873287 -230.116369) (xy 59.911774 -230.181684) (xy 59.9431 -230.25072) (xy 59.96691 -230.322695)
			(xy 59.982935 -230.396793) (xy 59.990994 -230.472174) (xy 59.991498 -230.51008) (xy 61.107577 -230.51008)
			(xy 61.111612 -230.434376) (xy 61.123671 -230.359531) (xy 61.143617 -230.28639) (xy 61.171224 -230.215785)
			(xy 61.20618 -230.148514) (xy 61.248088 -230.085339) (xy 61.296474 -230.026977) (xy 61.35079 -229.974089)
			(xy 61.410419 -229.927274) (xy 61.474687 -229.887062) (xy 61.542864 -229.85391) (xy 61.61418 -229.828192)
			(xy 61.687825 -229.8102) (xy 61.762965 -229.800138) (xy 61.838749 -229.798119) (xy 61.914319 -229.804168)
			(xy 61.988817 -229.818215) (xy 62.0614 -229.840101) (xy 62.131246 -229.869578) (xy 62.197563 -229.906313)
			(xy 62.259599 -229.949888) (xy 62.316652 -229.99981) (xy 62.368076 -230.055514) (xy 62.413287 -230.116369)
			(xy 62.451774 -230.181684) (xy 62.4831 -230.25072) (xy 62.50691 -230.322695) (xy 62.522935 -230.396793)
			(xy 62.530994 -230.472174) (xy 62.531498 -230.51008) (xy 62.530994 -230.547986) (xy 62.522935 -230.623367)
			(xy 62.50691 -230.697465) (xy 62.4831 -230.76944) (xy 62.451774 -230.838476) (xy 62.413287 -230.903791)
			(xy 62.368076 -230.964646) (xy 62.316652 -231.02035) (xy 62.265544 -231.06507) (xy 84.927697 -231.06507)
			(xy 84.931732 -230.989366) (xy 84.943791 -230.914521) (xy 84.963737 -230.84138) (xy 84.991344 -230.770775)
			(xy 85.0263 -230.703504) (xy 85.068208 -230.640329) (xy 85.116594 -230.581967) (xy 85.17091 -230.529079)
			(xy 85.230539 -230.482264) (xy 85.294807 -230.442052) (xy 85.362984 -230.4089) (xy 85.4343 -230.383182)
			(xy 85.507945 -230.36519) (xy 85.583085 -230.355128) (xy 85.658869 -230.353109) (xy 85.734439 -230.359158)
			(xy 85.808937 -230.373205) (xy 85.88152 -230.395091) (xy 85.951366 -230.424568) (xy 86.017683 -230.461303)
			(xy 86.079719 -230.504878) (xy 86.136772 -230.5548) (xy 86.188196 -230.610504) (xy 86.233407 -230.671359)
			(xy 86.271894 -230.736674) (xy 86.30322 -230.80571) (xy 86.32703 -230.877685) (xy 86.343055 -230.951783)
			(xy 86.351114 -231.027164) (xy 86.351618 -231.06507) (xy 87.467697 -231.06507) (xy 87.471732 -230.989366)
			(xy 87.483791 -230.914521) (xy 87.503737 -230.84138) (xy 87.531344 -230.770775) (xy 87.5663 -230.703504)
			(xy 87.608208 -230.640329) (xy 87.656594 -230.581967) (xy 87.71091 -230.529079) (xy 87.770539 -230.482264)
			(xy 87.834807 -230.442052) (xy 87.902984 -230.4089) (xy 87.9743 -230.383182) (xy 88.047945 -230.36519)
			(xy 88.123085 -230.355128) (xy 88.198869 -230.353109) (xy 88.274439 -230.359158) (xy 88.348937 -230.373205)
			(xy 88.42152 -230.395091) (xy 88.491366 -230.424568) (xy 88.557683 -230.461303) (xy 88.619719 -230.504878)
			(xy 88.676772 -230.5548) (xy 88.728196 -230.610504) (xy 88.773407 -230.671359) (xy 88.811894 -230.736674)
			(xy 88.84322 -230.80571) (xy 88.86703 -230.877685) (xy 88.883055 -230.951783) (xy 88.891114 -231.027164)
			(xy 88.891618 -231.06507) (xy 90.007697 -231.06507) (xy 90.011732 -230.989366) (xy 90.023791 -230.914521)
			(xy 90.043737 -230.84138) (xy 90.071344 -230.770775) (xy 90.1063 -230.703504) (xy 90.148208 -230.640329)
			(xy 90.196594 -230.581967) (xy 90.25091 -230.529079) (xy 90.310539 -230.482264) (xy 90.374807 -230.442052)
			(xy 90.442984 -230.4089) (xy 90.5143 -230.383182) (xy 90.587945 -230.36519) (xy 90.663085 -230.355128)
			(xy 90.738869 -230.353109) (xy 90.814439 -230.359158) (xy 90.888937 -230.373205) (xy 90.96152 -230.395091)
			(xy 91.031366 -230.424568) (xy 91.097683 -230.461303) (xy 91.159719 -230.504878) (xy 91.165664 -230.51008)
			(xy 93.154506 -230.51008) (xy 93.158522 -230.39381) (xy 93.170549 -230.278095) (xy 93.190531 -230.163485)
			(xy 93.218373 -230.050526) (xy 93.253942 -229.939758) (xy 93.297068 -229.831707) (xy 93.347545 -229.726889)
			(xy 93.405134 -229.625804) (xy 93.46956 -229.528932) (xy 93.540515 -229.436736) (xy 93.617662 -229.349655)
			(xy 93.700633 -229.268104) (xy 93.789033 -229.192472) (xy 93.88244 -229.123118) (xy 93.980409 -229.060375)
			(xy 94.082473 -229.004539) (xy 94.188147 -228.955878) (xy 94.296926 -228.914624) (xy 94.408291 -228.880973)
			(xy 94.521714 -228.855085) (xy 94.636651 -228.837084) (xy 94.752557 -228.827055) (xy 94.868879 -228.825047)
			(xy 94.985062 -228.831069) (xy 95.100553 -228.845092) (xy 95.214801 -228.86705) (xy 95.327262 -228.896837)
			(xy 95.4374 -228.934312) (xy 95.54469 -228.979297) (xy 95.648621 -229.031576) (xy 95.748697 -229.090901)
			(xy 95.844443 -229.156989) (xy 95.9354 -229.229525) (xy 96.021136 -229.308164) (xy 96.101243 -229.39253)
			(xy 96.175339 -229.482222) (xy 96.243069 -229.576812) (xy 96.304113 -229.67585) (xy 96.358178 -229.778863)
			(xy 96.405008 -229.88536) (xy 96.444379 -229.994835) (xy 96.476103 -230.106765) (xy 96.500029 -230.220617)
			(xy 96.516043 -230.335849) (xy 96.52407 -230.451911) (xy 96.524572 -230.51008) (xy 96.52407 -230.568249)
			(xy 96.516043 -230.684311) (xy 96.500029 -230.799543) (xy 96.476103 -230.913395) (xy 96.444379 -231.025325)
			(xy 96.405008 -231.1348) (xy 96.358178 -231.241297) (xy 96.304113 -231.34431) (xy 96.243069 -231.443348)
			(xy 96.175339 -231.537938) (xy 96.101243 -231.62763) (xy 96.021136 -231.711996) (xy 95.9354 -231.790635)
			(xy 95.844443 -231.863171) (xy 95.748697 -231.929259) (xy 95.648621 -231.988584) (xy 95.54469 -232.040863)
			(xy 95.4374 -232.085848) (xy 95.327262 -232.123323) (xy 95.214801 -232.15311) (xy 95.100553 -232.175068)
			(xy 94.985062 -232.189091) (xy 94.868879 -232.195113) (xy 94.752557 -232.193105) (xy 94.636651 -232.183076)
			(xy 94.521714 -232.165075) (xy 94.408291 -232.139187) (xy 94.296926 -232.105536) (xy 94.188147 -232.064282)
			(xy 94.082473 -232.015621) (xy 93.980409 -231.959785) (xy 93.88244 -231.897042) (xy 93.789033 -231.827688)
			(xy 93.700633 -231.752056) (xy 93.617662 -231.670505) (xy 93.540515 -231.583424) (xy 93.46956 -231.491228)
			(xy 93.405134 -231.394356) (xy 93.347545 -231.293271) (xy 93.297068 -231.188453) (xy 93.253942 -231.080402)
			(xy 93.218373 -230.969634) (xy 93.190531 -230.856675) (xy 93.170549 -230.742065) (xy 93.158522 -230.62635)
			(xy 93.154506 -230.51008) (xy 91.165664 -230.51008) (xy 91.216772 -230.5548) (xy 91.268196 -230.610504)
			(xy 91.313407 -230.671359) (xy 91.351894 -230.736674) (xy 91.38322 -230.80571) (xy 91.40703 -230.877685)
			(xy 91.423055 -230.951783) (xy 91.431114 -231.027164) (xy 91.431618 -231.06507) (xy 91.431114 -231.102976)
			(xy 91.423055 -231.178357) (xy 91.40703 -231.252455) (xy 91.38322 -231.32443) (xy 91.351894 -231.393466)
			(xy 91.313407 -231.458781) (xy 91.268196 -231.519636) (xy 91.216772 -231.57534) (xy 91.159719 -231.625262)
			(xy 91.097683 -231.668837) (xy 91.031366 -231.705572) (xy 90.96152 -231.735049) (xy 90.888937 -231.756935)
			(xy 90.814439 -231.770982) (xy 90.738869 -231.777031) (xy 90.663085 -231.775012) (xy 90.587945 -231.76495)
			(xy 90.5143 -231.746958) (xy 90.442984 -231.72124) (xy 90.374807 -231.688088) (xy 90.310539 -231.647876)
			(xy 90.25091 -231.601061) (xy 90.196594 -231.548173) (xy 90.148208 -231.489811) (xy 90.1063 -231.426636)
			(xy 90.071344 -231.359365) (xy 90.043737 -231.28876) (xy 90.023791 -231.215619) (xy 90.011732 -231.140774)
			(xy 90.007697 -231.06507) (xy 88.891618 -231.06507) (xy 88.891114 -231.102976) (xy 88.883055 -231.178357)
			(xy 88.86703 -231.252455) (xy 88.84322 -231.32443) (xy 88.811894 -231.393466) (xy 88.773407 -231.458781)
			(xy 88.728196 -231.519636) (xy 88.676772 -231.57534) (xy 88.619719 -231.625262) (xy 88.557683 -231.668837)
			(xy 88.491366 -231.705572) (xy 88.42152 -231.735049) (xy 88.348937 -231.756935) (xy 88.274439 -231.770982)
			(xy 88.198869 -231.777031) (xy 88.123085 -231.775012) (xy 88.047945 -231.76495) (xy 87.9743 -231.746958)
			(xy 87.902984 -231.72124) (xy 87.834807 -231.688088) (xy 87.770539 -231.647876) (xy 87.71091 -231.601061)
			(xy 87.656594 -231.548173) (xy 87.608208 -231.489811) (xy 87.5663 -231.426636) (xy 87.531344 -231.359365)
			(xy 87.503737 -231.28876) (xy 87.483791 -231.215619) (xy 87.471732 -231.140774) (xy 87.467697 -231.06507)
			(xy 86.351618 -231.06507) (xy 86.351114 -231.102976) (xy 86.343055 -231.178357) (xy 86.32703 -231.252455)
			(xy 86.30322 -231.32443) (xy 86.271894 -231.393466) (xy 86.233407 -231.458781) (xy 86.188196 -231.519636)
			(xy 86.136772 -231.57534) (xy 86.079719 -231.625262) (xy 86.017683 -231.668837) (xy 85.951366 -231.705572)
			(xy 85.88152 -231.735049) (xy 85.808937 -231.756935) (xy 85.734439 -231.770982) (xy 85.658869 -231.777031)
			(xy 85.583085 -231.775012) (xy 85.507945 -231.76495) (xy 85.4343 -231.746958) (xy 85.362984 -231.72124)
			(xy 85.294807 -231.688088) (xy 85.230539 -231.647876) (xy 85.17091 -231.601061) (xy 85.116594 -231.548173)
			(xy 85.068208 -231.489811) (xy 85.0263 -231.426636) (xy 84.991344 -231.359365) (xy 84.963737 -231.28876)
			(xy 84.943791 -231.215619) (xy 84.931732 -231.140774) (xy 84.927697 -231.06507) (xy 62.265544 -231.06507)
			(xy 62.259599 -231.070272) (xy 62.197563 -231.113847) (xy 62.131246 -231.150582) (xy 62.0614 -231.180059)
			(xy 61.988817 -231.201945) (xy 61.914319 -231.215992) (xy 61.838749 -231.222041) (xy 61.762965 -231.220022)
			(xy 61.687825 -231.20996) (xy 61.61418 -231.191968) (xy 61.542864 -231.16625) (xy 61.474687 -231.133098)
			(xy 61.410419 -231.092886) (xy 61.35079 -231.046071) (xy 61.296474 -230.993183) (xy 61.248088 -230.934821)
			(xy 61.20618 -230.871646) (xy 61.171224 -230.804375) (xy 61.143617 -230.73377) (xy 61.123671 -230.660629)
			(xy 61.111612 -230.585784) (xy 61.107577 -230.51008) (xy 59.991498 -230.51008) (xy 59.990994 -230.547986)
			(xy 59.982935 -230.623367) (xy 59.96691 -230.697465) (xy 59.9431 -230.76944) (xy 59.911774 -230.838476)
			(xy 59.873287 -230.903791) (xy 59.828076 -230.964646) (xy 59.776652 -231.02035) (xy 59.719599 -231.070272)
			(xy 59.657563 -231.113847) (xy 59.591246 -231.150582) (xy 59.5214 -231.180059) (xy 59.448817 -231.201945)
			(xy 59.374319 -231.215992) (xy 59.298749 -231.222041) (xy 59.222965 -231.220022) (xy 59.147825 -231.20996)
			(xy 59.07418 -231.191968) (xy 59.002864 -231.16625) (xy 58.934687 -231.133098) (xy 58.870419 -231.092886)
			(xy 58.81079 -231.046071) (xy 58.756474 -230.993183) (xy 58.708088 -230.934821) (xy 58.66618 -230.871646)
			(xy 58.631224 -230.804375) (xy 58.603617 -230.73377) (xy 58.583671 -230.660629) (xy 58.571612 -230.585784)
			(xy 58.567577 -230.51008) (xy 57.451498 -230.51008) (xy 57.450994 -230.547986) (xy 57.442935 -230.623367)
			(xy 57.42691 -230.697465) (xy 57.4031 -230.76944) (xy 57.371774 -230.838476) (xy 57.333287 -230.903791)
			(xy 57.288076 -230.964646) (xy 57.236652 -231.02035) (xy 57.179599 -231.070272) (xy 57.117563 -231.113847)
			(xy 57.051246 -231.150582) (xy 56.9814 -231.180059) (xy 56.908817 -231.201945) (xy 56.834319 -231.215992)
			(xy 56.758749 -231.222041) (xy 56.682965 -231.220022) (xy 56.607825 -231.20996) (xy 56.53418 -231.191968)
			(xy 56.462864 -231.16625) (xy 56.394687 -231.133098) (xy 56.330419 -231.092886) (xy 56.27079 -231.046071)
			(xy 56.216474 -230.993183) (xy 56.168088 -230.934821) (xy 56.12618 -230.871646) (xy 56.091224 -230.804375)
			(xy 56.063617 -230.73377) (xy 56.043671 -230.660629) (xy 56.031612 -230.585784) (xy 56.027577 -230.51008)
			(xy 54.911498 -230.51008) (xy 54.910994 -230.547986) (xy 54.902935 -230.623367) (xy 54.88691 -230.697465)
			(xy 54.8631 -230.76944) (xy 54.831774 -230.838476) (xy 54.793287 -230.903791) (xy 54.748076 -230.964646)
			(xy 54.696652 -231.02035) (xy 54.639599 -231.070272) (xy 54.577563 -231.113847) (xy 54.511246 -231.150582)
			(xy 54.4414 -231.180059) (xy 54.368817 -231.201945) (xy 54.294319 -231.215992) (xy 54.218749 -231.222041)
			(xy 54.142965 -231.220022) (xy 54.067825 -231.20996) (xy 53.99418 -231.191968) (xy 53.922864 -231.16625)
			(xy 53.854687 -231.133098) (xy 53.790419 -231.092886) (xy 53.73079 -231.046071) (xy 53.676474 -230.993183)
			(xy 53.628088 -230.934821) (xy 53.58618 -230.871646) (xy 53.551224 -230.804375) (xy 53.523617 -230.73377)
			(xy 53.503671 -230.660629) (xy 53.491612 -230.585784) (xy 53.487577 -230.51008) (xy 52.371498 -230.51008)
			(xy 52.370994 -230.547986) (xy 52.362935 -230.623367) (xy 52.34691 -230.697465) (xy 52.3231 -230.76944)
			(xy 52.291774 -230.838476) (xy 52.253287 -230.903791) (xy 52.208076 -230.964646) (xy 52.156652 -231.02035)
			(xy 52.099599 -231.070272) (xy 52.037563 -231.113847) (xy 51.971246 -231.150582) (xy 51.9014 -231.180059)
			(xy 51.828817 -231.201945) (xy 51.754319 -231.215992) (xy 51.678749 -231.222041) (xy 51.602965 -231.220022)
			(xy 51.527825 -231.20996) (xy 51.45418 -231.191968) (xy 51.382864 -231.16625) (xy 51.314687 -231.133098)
			(xy 51.250419 -231.092886) (xy 51.19079 -231.046071) (xy 51.136474 -230.993183) (xy 51.088088 -230.934821)
			(xy 51.04618 -230.871646) (xy 51.011224 -230.804375) (xy 50.983617 -230.73377) (xy 50.963671 -230.660629)
			(xy 50.951612 -230.585784) (xy 50.947577 -230.51008) (xy 49.831498 -230.51008) (xy 49.830994 -230.547986)
			(xy 49.822935 -230.623367) (xy 49.80691 -230.697465) (xy 49.7831 -230.76944) (xy 49.751774 -230.838476)
			(xy 49.713287 -230.903791) (xy 49.668076 -230.964646) (xy 49.616652 -231.02035) (xy 49.559599 -231.070272)
			(xy 49.497563 -231.113847) (xy 49.431246 -231.150582) (xy 49.3614 -231.180059) (xy 49.288817 -231.201945)
			(xy 49.214319 -231.215992) (xy 49.138749 -231.222041) (xy 49.062965 -231.220022) (xy 48.987825 -231.20996)
			(xy 48.91418 -231.191968) (xy 48.842864 -231.16625) (xy 48.774687 -231.133098) (xy 48.710419 -231.092886)
			(xy 48.65079 -231.046071) (xy 48.596474 -230.993183) (xy 48.548088 -230.934821) (xy 48.50618 -230.871646)
			(xy 48.471224 -230.804375) (xy 48.443617 -230.73377) (xy 48.423671 -230.660629) (xy 48.411612 -230.585784)
			(xy 48.407577 -230.51008) (xy 47.291498 -230.51008) (xy 47.290994 -230.547986) (xy 47.282935 -230.623367)
			(xy 47.26691 -230.697465) (xy 47.2431 -230.76944) (xy 47.211774 -230.838476) (xy 47.173287 -230.903791)
			(xy 47.128076 -230.964646) (xy 47.076652 -231.02035) (xy 47.019599 -231.070272) (xy 46.957563 -231.113847)
			(xy 46.891246 -231.150582) (xy 46.8214 -231.180059) (xy 46.748817 -231.201945) (xy 46.674319 -231.215992)
			(xy 46.598749 -231.222041) (xy 46.522965 -231.220022) (xy 46.447825 -231.20996) (xy 46.37418 -231.191968)
			(xy 46.302864 -231.16625) (xy 46.234687 -231.133098) (xy 46.170419 -231.092886) (xy 46.11079 -231.046071)
			(xy 46.056474 -230.993183) (xy 46.008088 -230.934821) (xy 45.96618 -230.871646) (xy 45.931224 -230.804375)
			(xy 45.903617 -230.73377) (xy 45.883671 -230.660629) (xy 45.871612 -230.585784) (xy 45.867577 -230.51008)
			(xy 44.751244 -230.51008) (xy 44.751244 -231.221788) (xy 43.328336 -231.221788) (xy 43.328336 -229.798372)
			(xy 43.055094 -229.798372) (xy 43.053462 -229.802742) (xy 43.004999 -229.909253) (xy 42.949245 -230.012135)
			(xy 42.886471 -230.110891) (xy 42.816981 -230.205042) (xy 42.741111 -230.294132) (xy 42.659229 -230.377729)
			(xy 42.571732 -230.45543) (xy 42.479042 -230.526857) (xy 42.381609 -230.591665) (xy 42.279905 -230.64954)
			(xy 42.174422 -230.700202) (xy 42.065671 -230.743404) (xy 41.954179 -230.778939) (xy 41.840485 -230.806634)
			(xy 41.725141 -230.826354) (xy 41.608704 -230.838005) (xy 41.491739 -230.84153) (xy 41.374812 -230.836912)
			(xy 41.258489 -230.824173) (xy 41.143334 -230.803375) (xy 41.029905 -230.774618) (xy 40.91875 -230.738042)
			(xy 40.810407 -230.693825) (xy 40.705403 -230.642179) (xy 40.604244 -230.583356) (xy 40.507421 -230.51764)
			(xy 40.415403 -230.445349) (xy 40.328636 -230.366834) (xy 40.247539 -230.282474) (xy 40.172506 -230.192679)
			(xy 40.103899 -230.097883) (xy 40.042051 -229.998544) (xy 39.987262 -229.895145) (xy 39.939796 -229.788186)
			(xy 39.899884 -229.678185) (xy 39.86772 -229.565674) (xy 39.843457 -229.451199) (xy 39.827215 -229.335313)
			(xy 39.819072 -229.218579) (xy 39.818564 -229.16007) (xy 36.341678 -229.16007) (xy 36.361593 -229.192234)
			(xy 36.400327 -229.270023) (xy 36.431719 -229.351055) (xy 36.4555 -229.434637) (xy 36.471468 -229.520057)
			(xy 36.479486 -229.606586) (xy 36.479988 -229.650036) (xy 36.479486 -229.693486) (xy 36.471468 -229.780015)
			(xy 36.4555 -229.865435) (xy 36.431719 -229.949017) (xy 36.400327 -230.030049) (xy 36.361593 -230.107838)
			(xy 36.315846 -230.181722) (xy 36.263477 -230.251069) (xy 36.204933 -230.315289) (xy 36.140713 -230.373833)
			(xy 36.071366 -230.426202) (xy 35.997482 -230.471949) (xy 35.919693 -230.510683) (xy 35.838661 -230.542075)
			(xy 35.755079 -230.565856) (xy 35.669659 -230.581824) (xy 35.58313 -230.589842) (xy 35.49623 -230.589842)
			(xy 35.409701 -230.581824) (xy 35.324281 -230.565856) (xy 35.240699 -230.542075) (xy 35.159667 -230.510683)
			(xy 35.081878 -230.471949) (xy 35.007994 -230.426202) (xy 34.938647 -230.373833) (xy 34.874427 -230.315289)
			(xy 34.815883 -230.251069) (xy 34.763514 -230.181722) (xy 34.717767 -230.107838) (xy 34.679033 -230.030049)
			(xy 34.647641 -229.949017) (xy 34.62386 -229.865435) (xy 34.607892 -229.780015) (xy 34.599874 -229.693486)
			(xy 31.399486 -229.693486) (xy 31.391468 -229.780015) (xy 31.3755 -229.865435) (xy 31.351719 -229.949017)
			(xy 31.320327 -230.030049) (xy 31.281593 -230.107838) (xy 31.235846 -230.181722) (xy 31.183477 -230.251069)
			(xy 31.124933 -230.315289) (xy 31.060713 -230.373833) (xy 30.991366 -230.426202) (xy 30.917482 -230.471949)
			(xy 30.839693 -230.510683) (xy 30.758661 -230.542075) (xy 30.675079 -230.565856) (xy 30.589659 -230.581824)
			(xy 30.50313 -230.589842) (xy 30.41623 -230.589842) (xy 30.329701 -230.581824) (xy 30.244281 -230.565856)
			(xy 30.160699 -230.542075) (xy 30.079667 -230.510683) (xy 30.001878 -230.471949) (xy 29.927994 -230.426202)
			(xy 29.858647 -230.373833) (xy 29.794427 -230.315289) (xy 29.735883 -230.251069) (xy 29.683514 -230.181722)
			(xy 29.637767 -230.107838) (xy 29.599033 -230.030049) (xy 29.567641 -229.949017) (xy 29.54386 -229.865435)
			(xy 29.527892 -229.780015) (xy 29.519874 -229.693486) (xy 28.942538 -229.693486) (xy 28.942538 -236.214412)
			(xy 81.880454 -236.214412) (xy 81.884525 -236.15879) (xy 81.896651 -236.104353) (xy 81.916574 -236.052262)
			(xy 81.94387 -236.003627) (xy 81.977956 -235.959484) (xy 82.018105 -235.920775) (xy 82.063463 -235.888324)
			(xy 82.113063 -235.862823) (xy 82.165847 -235.844816) (xy 82.22069 -235.834686) (xy 82.276424 -235.832649)
			(xy 82.331861 -235.838749) (xy 82.385818 -235.852855) (xy 82.437147 -235.874667) (xy 82.484753 -235.903721)
			(xy 82.527621 -235.939396) (xy 82.564838 -235.980933) (xy 82.595611 -236.027446) (xy 82.619283 -236.077943)
			(xy 82.635351 -236.13135) (xy 82.643471 -236.186526) (xy 82.64398 -236.214412) (xy 82.643471 -236.242298)
			(xy 82.635351 -236.297474) (xy 82.619283 -236.350881) (xy 82.595611 -236.401378) (xy 82.564838 -236.447891)
			(xy 82.527621 -236.489428) (xy 82.484753 -236.525103) (xy 82.437147 -236.554157) (xy 82.385818 -236.575969)
			(xy 82.331861 -236.590075) (xy 82.276424 -236.596175) (xy 82.22069 -236.594138) (xy 82.165847 -236.584008)
			(xy 82.113063 -236.566001) (xy 82.063463 -236.5405) (xy 82.018105 -236.508049) (xy 81.977956 -236.46934)
			(xy 81.94387 -236.425197) (xy 81.916574 -236.376562) (xy 81.896651 -236.324471) (xy 81.884525 -236.270034)
			(xy 81.880454 -236.214412) (xy 28.942538 -236.214412) (xy 28.942538 -237.048548) (xy 83.078064 -237.048548)
			(xy 83.082135 -236.992926) (xy 83.094261 -236.938489) (xy 83.114184 -236.886398) (xy 83.14148 -236.837763)
			(xy 83.175566 -236.79362) (xy 83.215715 -236.754911) (xy 83.261073 -236.72246) (xy 83.310673 -236.696959)
			(xy 83.363457 -236.678952) (xy 83.4183 -236.668822) (xy 83.474034 -236.666785) (xy 83.529471 -236.672885)
			(xy 83.583428 -236.686991) (xy 83.634757 -236.708803) (xy 83.682363 -236.737857) (xy 83.725231 -236.773532)
			(xy 83.762448 -236.815069) (xy 83.793221 -236.861582) (xy 83.816893 -236.912079) (xy 83.832961 -236.965486)
			(xy 83.841081 -237.020662) (xy 83.84159 -237.048548) (xy 83.841081 -237.076434) (xy 83.832961 -237.13161)
			(xy 83.822569 -237.16615) (xy 86.906606 -237.16615) (xy 86.910677 -237.110528) (xy 86.922803 -237.056091)
			(xy 86.942726 -237.004) (xy 86.970022 -236.955365) (xy 87.004108 -236.911222) (xy 87.044257 -236.872513)
			(xy 87.089615 -236.840062) (xy 87.139215 -236.814561) (xy 87.191999 -236.796554) (xy 87.246842 -236.786424)
			(xy 87.302576 -236.784387) (xy 87.358013 -236.790487) (xy 87.41197 -236.804593) (xy 87.463299 -236.826405)
			(xy 87.510905 -236.855459) (xy 87.553773 -236.891134) (xy 87.59099 -236.932671) (xy 87.621763 -236.979184)
			(xy 87.645435 -237.029681) (xy 87.661503 -237.083088) (xy 87.669623 -237.138264) (xy 87.670132 -237.16615)
			(xy 87.669623 -237.194036) (xy 87.661503 -237.249212) (xy 87.645435 -237.302619) (xy 87.621763 -237.353116)
			(xy 87.59099 -237.399629) (xy 87.553773 -237.441166) (xy 87.510905 -237.476841) (xy 87.463299 -237.505895)
			(xy 87.41197 -237.527707) (xy 87.358013 -237.541813) (xy 87.302576 -237.547913) (xy 87.246842 -237.545876)
			(xy 87.191999 -237.535746) (xy 87.139215 -237.517739) (xy 87.089615 -237.492238) (xy 87.044257 -237.459787)
			(xy 87.004108 -237.421078) (xy 86.970022 -237.376935) (xy 86.942726 -237.3283) (xy 86.922803 -237.276209)
			(xy 86.910677 -237.221772) (xy 86.906606 -237.16615) (xy 83.822569 -237.16615) (xy 83.816893 -237.185017)
			(xy 83.793221 -237.235514) (xy 83.762448 -237.282027) (xy 83.725231 -237.323564) (xy 83.682363 -237.359239)
			(xy 83.634757 -237.388293) (xy 83.583428 -237.410105) (xy 83.529471 -237.424211) (xy 83.474034 -237.430311)
			(xy 83.4183 -237.428274) (xy 83.363457 -237.418144) (xy 83.310673 -237.400137) (xy 83.261073 -237.374636)
			(xy 83.215715 -237.342185) (xy 83.175566 -237.303476) (xy 83.14148 -237.259333) (xy 83.114184 -237.210698)
			(xy 83.094261 -237.158607) (xy 83.082135 -237.10417) (xy 83.078064 -237.048548) (xy 28.942538 -237.048548)
			(xy 28.942538 -237.986199) (xy 44.224173 -237.986199) (xy 44.224173 -237.922933) (xy 44.232431 -237.860209)
			(xy 44.248805 -237.7991) (xy 44.273016 -237.74065) (xy 44.304649 -237.685861) (xy 44.343162 -237.635669)
			(xy 44.387897 -237.590934) (xy 44.438089 -237.552421) (xy 44.492878 -237.520788) (xy 44.551328 -237.496577)
			(xy 44.612437 -237.480203) (xy 44.675161 -237.471945) (xy 44.738427 -237.471945) (xy 44.801151 -237.480203)
			(xy 44.86226 -237.496577) (xy 44.92071 -237.520788) (xy 44.975499 -237.552421) (xy 45.025691 -237.590934)
			(xy 45.048424 -237.612936) (xy 45.161962 -237.726474) (xy 45.1741 -237.737861) (xy 45.202876 -237.754555)
			(xy 45.234991 -237.763233) (xy 45.251624 -237.763812) (xy 46.030642 -237.763812) (xy 46.058931 -237.764181)
			(xy 46.115126 -237.770737) (xy 46.170168 -237.783824) (xy 46.2233 -237.803263) (xy 46.273793 -237.828786)
			(xy 46.297596 -237.844076) (xy 46.329346 -237.865412) (xy 46.386496 -237.865412) (xy 46.386496 -237.920276)
			(xy 46.406327 -237.942626) (xy 46.440973 -237.991307) (xy 46.469348 -238.043891) (xy 46.477387 -238.064548)
			(xy 85.002622 -238.064548) (xy 85.006693 -238.008926) (xy 85.018819 -237.954489) (xy 85.038742 -237.902398)
			(xy 85.066038 -237.853763) (xy 85.100124 -237.80962) (xy 85.140273 -237.770911) (xy 85.185631 -237.73846)
			(xy 85.235231 -237.712959) (xy 85.288015 -237.694952) (xy 85.342858 -237.684822) (xy 85.398592 -237.682785)
			(xy 85.454029 -237.688885) (xy 85.507986 -237.702991) (xy 85.559315 -237.724803) (xy 85.606921 -237.753857)
			(xy 85.649789 -237.789532) (xy 85.687006 -237.831069) (xy 85.717779 -237.877582) (xy 85.741451 -237.928079)
			(xy 85.757519 -237.981486) (xy 85.765639 -238.036662) (xy 85.766148 -238.064548) (xy 85.765639 -238.092434)
			(xy 85.757519 -238.14761) (xy 85.741451 -238.201017) (xy 85.717779 -238.251514) (xy 85.687006 -238.298027)
			(xy 85.649789 -238.339564) (xy 85.606921 -238.375239) (xy 85.559315 -238.404293) (xy 85.507986 -238.426105)
			(xy 85.454029 -238.440211) (xy 85.398592 -238.446311) (xy 85.342858 -238.444274) (xy 85.288015 -238.434144)
			(xy 85.235231 -238.416137) (xy 85.185631 -238.390636) (xy 85.140273 -238.358185) (xy 85.100124 -238.319476)
			(xy 85.066038 -238.275333) (xy 85.038742 -238.226698) (xy 85.018819 -238.174607) (xy 85.006693 -238.12017)
			(xy 85.002622 -238.064548) (xy 46.477387 -238.064548) (xy 46.491019 -238.099574) (xy 46.505654 -238.157505)
			(xy 46.513029 -238.216799) (xy 46.513032 -238.276551) (xy 46.505663 -238.335846) (xy 46.491034 -238.393778)
			(xy 46.469369 -238.449464) (xy 46.441 -238.50205) (xy 46.406358 -238.550735) (xy 46.386496 -238.573056)
			(xy 46.386496 -238.62792) (xy 46.329346 -238.62792) (xy 46.297596 -238.649256) (xy 46.273789 -238.664536)
			(xy 46.223286 -238.690028) (xy 46.170153 -238.709452) (xy 46.115116 -238.722545) (xy 46.058928 -238.729128)
			(xy 46.030642 -238.72952) (xy 44.798742 -238.72952) (xy 44.365164 -238.296196) (xy 44.343162 -238.273463)
			(xy 44.304649 -238.223271) (xy 44.273016 -238.168482) (xy 44.248805 -238.110032) (xy 44.232431 -238.048923)
			(xy 44.224173 -237.986199) (xy 28.942538 -237.986199) (xy 28.942538 -239.059212) (xy 80.53146 -239.059212)
			(xy 80.535531 -239.00359) (xy 80.547657 -238.949153) (xy 80.56758 -238.897062) (xy 80.594876 -238.848427)
			(xy 80.628962 -238.804284) (xy 80.669111 -238.765575) (xy 80.714469 -238.733124) (xy 80.764069 -238.707623)
			(xy 80.816853 -238.689616) (xy 80.871696 -238.679486) (xy 80.92743 -238.677449) (xy 80.982867 -238.683549)
			(xy 81.036824 -238.697655) (xy 81.05682 -238.706152) (xy 82.586066 -238.706152) (xy 82.590137 -238.65053)
			(xy 82.602263 -238.596093) (xy 82.622186 -238.544002) (xy 82.649482 -238.495367) (xy 82.683568 -238.451224)
			(xy 82.723717 -238.412515) (xy 82.769075 -238.380064) (xy 82.818675 -238.354563) (xy 82.871459 -238.336556)
			(xy 82.926302 -238.326426) (xy 82.982036 -238.324389) (xy 83.037473 -238.330489) (xy 83.09143 -238.344595)
			(xy 83.142759 -238.366407) (xy 83.190365 -238.395461) (xy 83.233233 -238.431136) (xy 83.27045 -238.472673)
			(xy 83.301223 -238.519186) (xy 83.324895 -238.569683) (xy 83.340963 -238.62309) (xy 83.349083 -238.678266)
			(xy 83.349592 -238.706152) (xy 83.349083 -238.734038) (xy 83.340963 -238.789214) (xy 83.324895 -238.842621)
			(xy 83.301223 -238.893118) (xy 83.27045 -238.939631) (xy 83.233233 -238.981168) (xy 83.190365 -239.016843)
			(xy 83.142759 -239.045897) (xy 83.09143 -239.067709) (xy 83.037473 -239.081815) (xy 82.982036 -239.087915)
			(xy 82.926302 -239.085878) (xy 82.871459 -239.075748) (xy 82.818675 -239.057741) (xy 82.769075 -239.03224)
			(xy 82.723717 -238.999789) (xy 82.683568 -238.96108) (xy 82.649482 -238.916937) (xy 82.622186 -238.868302)
			(xy 82.602263 -238.816211) (xy 82.590137 -238.761774) (xy 82.586066 -238.706152) (xy 81.05682 -238.706152)
			(xy 81.088153 -238.719467) (xy 81.135759 -238.748521) (xy 81.178627 -238.784196) (xy 81.215844 -238.825733)
			(xy 81.246617 -238.872246) (xy 81.270289 -238.922743) (xy 81.286357 -238.97615) (xy 81.294477 -239.031326)
			(xy 81.294986 -239.059212) (xy 81.294477 -239.087098) (xy 81.286357 -239.142274) (xy 81.270289 -239.195681)
			(xy 81.246617 -239.246178) (xy 81.215844 -239.292691) (xy 81.178627 -239.334228) (xy 81.135759 -239.369903)
			(xy 81.088153 -239.398957) (xy 81.036824 -239.420769) (xy 80.982867 -239.434875) (xy 80.92743 -239.440975)
			(xy 80.871696 -239.438938) (xy 80.816853 -239.428808) (xy 80.764069 -239.410801) (xy 80.714469 -239.3853)
			(xy 80.669111 -239.352849) (xy 80.628962 -239.31414) (xy 80.594876 -239.269997) (xy 80.56758 -239.221362)
			(xy 80.547657 -239.169271) (xy 80.535531 -239.114834) (xy 80.53146 -239.059212) (xy 28.942538 -239.059212)
			(xy 28.942538 -239.944031) (xy 44.218585 -239.944031) (xy 44.218585 -239.880765) (xy 44.226843 -239.818041)
			(xy 44.243217 -239.756932) (xy 44.267428 -239.698482) (xy 44.299061 -239.643693) (xy 44.337574 -239.593501)
			(xy 44.359576 -239.570768) (xy 44.744386 -239.186212) (xy 46.008036 -239.186212) (xy 46.0363 -239.186574)
			(xy 46.092443 -239.193153) (xy 46.147431 -239.20625) (xy 46.200512 -239.225687) (xy 46.250955 -239.251197)
			(xy 46.274736 -239.266476) (xy 46.30674 -239.287558) (xy 46.469554 -239.287558) (xy 46.503336 -239.262158)
			(xy 46.52981 -239.24296) (xy 46.586745 -239.210789) (xy 46.647336 -239.186184) (xy 46.710582 -239.169551)
			(xy 46.775438 -239.161166) (xy 46.840834 -239.161166) (xy 46.90569 -239.169551) (xy 46.968936 -239.186184)
			(xy 47.029527 -239.210789) (xy 47.086462 -239.24296) (xy 47.112936 -239.262158) (xy 47.146718 -239.287558)
			(xy 47.164244 -239.287558) (xy 47.164244 -239.306354) (xy 47.187897 -239.330333) (xy 47.229336 -239.383431)
			(xy 47.2634 -239.441537) (xy 47.289493 -239.503632) (xy 47.307156 -239.568629) (xy 47.316082 -239.635389)
			(xy 47.316644 -239.669066) (xy 47.316644 -239.711484) (xy 84.07984 -239.711484) (xy 84.083911 -239.655862)
			(xy 84.096037 -239.601425) (xy 84.11596 -239.549334) (xy 84.143256 -239.500699) (xy 84.177342 -239.456556)
			(xy 84.217491 -239.417847) (xy 84.262849 -239.385396) (xy 84.312449 -239.359895) (xy 84.365233 -239.341888)
			(xy 84.420076 -239.331758) (xy 84.47581 -239.329721) (xy 84.531247 -239.335821) (xy 84.585204 -239.349927)
			(xy 84.636533 -239.371739) (xy 84.684139 -239.400793) (xy 84.727007 -239.436468) (xy 84.764224 -239.478005)
			(xy 84.794997 -239.524518) (xy 84.818669 -239.575015) (xy 84.834737 -239.628422) (xy 84.842857 -239.683598)
			(xy 84.843366 -239.711484) (xy 84.842857 -239.73937) (xy 84.834737 -239.794546) (xy 84.818669 -239.847953)
			(xy 84.794997 -239.89845) (xy 84.764224 -239.944963) (xy 84.727007 -239.9865) (xy 84.684139 -240.022175)
			(xy 84.636533 -240.051229) (xy 84.585204 -240.073041) (xy 84.531247 -240.087147) (xy 84.47581 -240.093247)
			(xy 84.420076 -240.09121) (xy 84.365233 -240.08108) (xy 84.312449 -240.063073) (xy 84.262849 -240.037572)
			(xy 84.217491 -240.005121) (xy 84.177342 -239.966412) (xy 84.143256 -239.922269) (xy 84.11596 -239.873634)
			(xy 84.096037 -239.821543) (xy 84.083911 -239.767106) (xy 84.07984 -239.711484) (xy 47.316644 -239.711484)
			(xy 47.316644 -239.7633) (xy 52.53736 -239.7633) (xy 54.188868 -239.7633) (xy 54.188868 -240.310416)
			(xy 81.938874 -240.310416) (xy 81.942945 -240.254794) (xy 81.955071 -240.200357) (xy 81.974994 -240.148266)
			(xy 82.00229 -240.099631) (xy 82.036376 -240.055488) (xy 82.076525 -240.016779) (xy 82.121883 -239.984328)
			(xy 82.171483 -239.958827) (xy 82.224267 -239.94082) (xy 82.27911 -239.93069) (xy 82.334844 -239.928653)
			(xy 82.390281 -239.934753) (xy 82.444238 -239.948859) (xy 82.495567 -239.970671) (xy 82.543173 -239.999725)
			(xy 82.586041 -240.0354) (xy 82.623258 -240.076937) (xy 82.654031 -240.12345) (xy 82.677703 -240.173947)
			(xy 82.693771 -240.227354) (xy 82.701891 -240.28253) (xy 82.7024 -240.310416) (xy 82.701891 -240.338302)
			(xy 82.693771 -240.393478) (xy 82.677703 -240.446885) (xy 82.654031 -240.497382) (xy 82.623258 -240.543895)
			(xy 82.586041 -240.585432) (xy 82.543173 -240.621107) (xy 82.495567 -240.650161) (xy 82.444238 -240.671973)
			(xy 82.390281 -240.686079) (xy 82.334844 -240.692179) (xy 82.27911 -240.690142) (xy 82.224267 -240.680012)
			(xy 82.171483 -240.662005) (xy 82.121883 -240.636504) (xy 82.076525 -240.604053) (xy 82.036376 -240.565344)
			(xy 82.00229 -240.521201) (xy 81.974994 -240.472566) (xy 81.955071 -240.420475) (xy 81.942945 -240.366038)
			(xy 81.938874 -240.310416) (xy 54.188868 -240.310416) (xy 54.188868 -240.984024) (xy 83.422234 -240.984024)
			(xy 83.426305 -240.928402) (xy 83.438431 -240.873965) (xy 83.458354 -240.821874) (xy 83.48565 -240.773239)
			(xy 83.519736 -240.729096) (xy 83.559885 -240.690387) (xy 83.605243 -240.657936) (xy 83.654843 -240.632435)
			(xy 83.707627 -240.614428) (xy 83.76247 -240.604298) (xy 83.818204 -240.602261) (xy 83.873641 -240.608361)
			(xy 83.927598 -240.622467) (xy 83.978927 -240.644279) (xy 84.026533 -240.673333) (xy 84.069401 -240.709008)
			(xy 84.106618 -240.750545) (xy 84.137391 -240.797058) (xy 84.161063 -240.847555) (xy 84.177131 -240.900962)
			(xy 84.185251 -240.956138) (xy 84.18576 -240.984024) (xy 84.185251 -241.01191) (xy 84.177131 -241.067086)
			(xy 84.161063 -241.120493) (xy 84.137391 -241.17099) (xy 84.106618 -241.217503) (xy 84.069401 -241.25904)
			(xy 84.026533 -241.294715) (xy 83.978927 -241.323769) (xy 83.927598 -241.345581) (xy 83.873641 -241.359687)
			(xy 83.818204 -241.365787) (xy 83.76247 -241.36375) (xy 83.707627 -241.35362) (xy 83.654843 -241.335613)
			(xy 83.605243 -241.310112) (xy 83.559885 -241.277661) (xy 83.519736 -241.238952) (xy 83.48565 -241.194809)
			(xy 83.458354 -241.146174) (xy 83.438431 -241.094083) (xy 83.426305 -241.039646) (xy 83.422234 -240.984024)
			(xy 54.188868 -240.984024) (xy 54.188868 -241.415316) (xy 52.53736 -241.415316) (xy 52.53736 -239.7633)
			(xy 47.316644 -239.7633) (xy 47.316644 -240.629863) (xy 49.037484 -240.629863) (xy 49.037484 -240.548753)
			(xy 49.045434 -240.468034) (xy 49.061257 -240.388483) (xy 49.084802 -240.310867) (xy 49.115841 -240.235931)
			(xy 49.154076 -240.164399) (xy 49.199138 -240.096959) (xy 49.250593 -240.03426) (xy 49.307946 -239.976907)
			(xy 49.370645 -239.925452) (xy 49.438085 -239.88039) (xy 49.509617 -239.842155) (xy 49.584553 -239.811116)
			(xy 49.662169 -239.787571) (xy 49.74172 -239.771748) (xy 49.822439 -239.763798) (xy 49.903549 -239.763798)
			(xy 49.984268 -239.771748) (xy 50.063819 -239.787571) (xy 50.141435 -239.811116) (xy 50.216371 -239.842155)
			(xy 50.287903 -239.88039) (xy 50.355343 -239.925452) (xy 50.418042 -239.976907) (xy 50.475395 -240.03426)
			(xy 50.52685 -240.096959) (xy 50.571912 -240.164399) (xy 50.610147 -240.235931) (xy 50.641186 -240.310867)
			(xy 50.664731 -240.388483) (xy 50.680554 -240.468034) (xy 50.688504 -240.548753) (xy 50.689002 -240.589308)
			(xy 50.688504 -240.629863) (xy 50.680554 -240.710582) (xy 50.664731 -240.790133) (xy 50.641186 -240.867749)
			(xy 50.610147 -240.942685) (xy 50.571912 -241.014217) (xy 50.52685 -241.081657) (xy 50.475395 -241.144356)
			(xy 50.418042 -241.201709) (xy 50.355343 -241.253164) (xy 50.287903 -241.298226) (xy 50.216371 -241.336461)
			(xy 50.141435 -241.3675) (xy 50.063819 -241.391045) (xy 49.984268 -241.406868) (xy 49.903549 -241.414818)
			(xy 49.822439 -241.414818) (xy 49.74172 -241.406868) (xy 49.662169 -241.391045) (xy 49.584553 -241.3675)
			(xy 49.509617 -241.336461) (xy 49.438085 -241.298226) (xy 49.370645 -241.253164) (xy 49.307946 -241.201709)
			(xy 49.250593 -241.144356) (xy 49.199138 -241.081657) (xy 49.154076 -241.014217) (xy 49.115841 -240.942685)
			(xy 49.084802 -240.867749) (xy 49.061257 -240.790133) (xy 49.045434 -240.710582) (xy 49.037484 -240.629863)
			(xy 47.316644 -240.629863) (xy 47.316644 -240.876074) (xy 47.316142 -240.908035) (xy 47.308131 -240.971453)
			(xy 47.292234 -241.033367) (xy 47.268702 -241.0928) (xy 47.237908 -241.148815) (xy 47.200335 -241.20053)
			(xy 47.156578 -241.247127) (xy 47.107325 -241.287872) (xy 47.053354 -241.322123) (xy 46.995515 -241.34934)
			(xy 46.934722 -241.369093) (xy 46.871932 -241.381071) (xy 46.808136 -241.385085) (xy 46.74434 -241.381071)
			(xy 46.68155 -241.369093) (xy 46.620757 -241.34934) (xy 46.562918 -241.322123) (xy 46.508947 -241.287872)
			(xy 46.459694 -241.247127) (xy 46.415937 -241.20053) (xy 46.378364 -241.148815) (xy 46.34757 -241.0928)
			(xy 46.324038 -241.033367) (xy 46.308141 -240.971453) (xy 46.30013 -240.908035) (xy 46.299628 -240.876074)
			(xy 46.299628 -240.405158) (xy 46.299147 -240.382248) (xy 46.290958 -240.337166) (xy 46.274818 -240.294284)
			(xy 46.251249 -240.254991) (xy 46.221016 -240.220562) (xy 46.185099 -240.192113) (xy 46.144662 -240.170565)
			(xy 46.101017 -240.156619) (xy 46.055579 -240.150725) (xy 46.032674 -240.151412) (xy 46.008036 -240.15192)
			(xy 45.197268 -240.15192) (xy 45.180587 -240.152441) (xy 45.148365 -240.161094) (xy 45.119486 -240.1778)
			(xy 45.107352 -240.189258) (xy 45.042836 -240.254028) (xy 45.020103 -240.27603) (xy 44.969911 -240.314543)
			(xy 44.915122 -240.346176) (xy 44.856672 -240.370387) (xy 44.795563 -240.386761) (xy 44.732839 -240.395019)
			(xy 44.669573 -240.395019) (xy 44.606849 -240.386761) (xy 44.54574 -240.370387) (xy 44.48729 -240.346176)
			(xy 44.432501 -240.314543) (xy 44.382309 -240.27603) (xy 44.337574 -240.231295) (xy 44.299061 -240.181103)
			(xy 44.267428 -240.126314) (xy 44.243217 -240.067864) (xy 44.226843 -240.006755) (xy 44.218585 -239.944031)
			(xy 28.942538 -239.944031) (xy 28.942538 -241.92329) (xy 58.378193 -241.92329) (xy 58.382082 -241.868937)
			(xy 58.393667 -241.81569) (xy 58.412712 -241.764633) (xy 58.438831 -241.716808) (xy 58.471489 -241.673186)
			(xy 58.510024 -241.634656) (xy 58.55365 -241.602003) (xy 58.60148 -241.575891) (xy 58.652538 -241.556853)
			(xy 58.705787 -241.545275) (xy 58.760141 -241.541393) (xy 58.814495 -241.545286) (xy 58.867741 -241.556876)
			(xy 58.918795 -241.575926) (xy 58.966619 -241.602048) (xy 58.988706 -241.618008) (xy 59.007718 -241.631604)
			(xy 59.049601 -241.652336) (xy 59.094569 -241.665062) (xy 59.141106 -241.669352) (xy 59.187643 -241.665062)
			(xy 59.232611 -241.652336) (xy 59.274494 -241.631604) (xy 59.293506 -241.618008) (xy 59.315579 -241.602027)
			(xy 59.363405 -241.575905) (xy 59.414462 -241.556856) (xy 59.46771 -241.545267) (xy 59.522066 -241.541374)
			(xy 59.576422 -241.545257) (xy 59.629672 -241.556837) (xy 59.680733 -241.575877) (xy 59.728563 -241.60199)
			(xy 59.772191 -241.634645) (xy 59.810727 -241.673176) (xy 59.843386 -241.7168) (xy 59.869505 -241.764627)
			(xy 59.888551 -241.815686) (xy 59.900137 -241.868935) (xy 59.904026 -241.92329) (xy 60.264885 -241.92329)
			(xy 60.268775 -241.868935) (xy 60.28036 -241.815686) (xy 60.299407 -241.764629) (xy 60.325526 -241.716802)
			(xy 60.358186 -241.673179) (xy 60.396722 -241.634648) (xy 60.44035 -241.601995) (xy 60.488181 -241.575883)
			(xy 60.539242 -241.556844) (xy 60.592492 -241.545267) (xy 60.646848 -241.541385) (xy 60.701203 -241.54528)
			(xy 60.75445 -241.556871) (xy 60.805506 -241.575923) (xy 60.853331 -241.602046) (xy 60.875418 -241.618008)
			(xy 60.89443 -241.631604) (xy 60.936313 -241.652336) (xy 60.981281 -241.665062) (xy 61.027818 -241.669352)
			(xy 61.074355 -241.665062) (xy 61.119323 -241.652336) (xy 61.161206 -241.631604) (xy 61.180218 -241.618008)
			(xy 61.202291 -241.602028) (xy 61.250116 -241.575908) (xy 61.301172 -241.55686) (xy 61.354419 -241.545273)
			(xy 61.408773 -241.541381) (xy 61.463127 -241.545265) (xy 61.516376 -241.556845) (xy 61.567434 -241.575885)
			(xy 61.615263 -241.601998) (xy 61.658889 -241.634653) (xy 61.697423 -241.673183) (xy 61.730082 -241.716806)
			(xy 61.756199 -241.764632) (xy 61.775245 -241.815689) (xy 61.78683 -241.868936) (xy 61.790719 -241.92329)
			(xy 61.786832 -241.977645) (xy 61.77525 -242.030893) (xy 61.756207 -242.08195) (xy 61.730092 -242.129778)
			(xy 61.697436 -242.173402) (xy 61.658903 -242.211935) (xy 61.615279 -242.244591) (xy 61.567452 -242.270707)
			(xy 61.516394 -242.28975) (xy 61.463146 -242.301332) (xy 61.408792 -242.305219) (xy 61.354438 -242.30133)
			(xy 61.30119 -242.289745) (xy 61.250133 -242.2707) (xy 61.202307 -242.244582) (xy 61.180218 -242.228624)
			(xy 61.161206 -242.215028) (xy 61.119323 -242.194296) (xy 61.074355 -242.18157) (xy 61.027818 -242.17728)
			(xy 60.981281 -242.18157) (xy 60.936313 -242.194296) (xy 60.89443 -242.215028) (xy 60.875418 -242.228624)
			(xy 60.853314 -242.244564) (xy 60.805489 -242.270685) (xy 60.754432 -242.289734) (xy 60.701184 -242.301323)
			(xy 60.646829 -242.305215) (xy 60.592473 -242.301331) (xy 60.539223 -242.28975) (xy 60.488164 -242.270709)
			(xy 60.440334 -242.244595) (xy 60.396708 -242.211939) (xy 60.358173 -242.173407) (xy 60.325515 -242.129782)
			(xy 60.299399 -242.081954) (xy 60.280355 -242.030895) (xy 60.268772 -241.977646) (xy 60.264885 -241.92329)
			(xy 59.904026 -241.92329) (xy 59.900139 -241.977646) (xy 59.888557 -242.030896) (xy 59.869513 -242.081955)
			(xy 59.843397 -242.129784) (xy 59.810739 -242.173409) (xy 59.772205 -242.211943) (xy 59.72858 -242.2446)
			(xy 59.68075 -242.270715) (xy 59.629691 -242.289758) (xy 59.576441 -242.30134) (xy 59.522085 -242.305226)
			(xy 59.467729 -242.301336) (xy 59.41448 -242.28975) (xy 59.363423 -242.270703) (xy 59.315595 -242.244583)
			(xy 59.293506 -242.228624) (xy 59.274494 -242.215028) (xy 59.232611 -242.194296) (xy 59.187643 -242.18157)
			(xy 59.141106 -242.17728) (xy 59.094569 -242.18157) (xy 59.049601 -242.194296) (xy 59.007718 -242.215028)
			(xy 58.988706 -242.228624) (xy 58.966603 -242.244563) (xy 58.918778 -242.270682) (xy 58.867722 -242.28973)
			(xy 58.814476 -242.301317) (xy 58.760122 -242.305207) (xy 58.705768 -242.301323) (xy 58.65252 -242.289742)
			(xy 58.601462 -242.270701) (xy 58.553634 -242.244587) (xy 58.51001 -242.211931) (xy 58.471477 -242.1734)
			(xy 58.43882 -242.129776) (xy 58.412704 -242.081949) (xy 58.393662 -242.030892) (xy 58.382079 -241.977644)
			(xy 58.378193 -241.92329) (xy 28.942538 -241.92329) (xy 28.942538 -242.846489) (xy 44.109873 -242.846489)
			(xy 44.109873 -242.783223) (xy 44.118131 -242.720499) (xy 44.134505 -242.65939) (xy 44.158716 -242.60094)
			(xy 44.190349 -242.546151) (xy 44.228862 -242.495959) (xy 44.273597 -242.451224) (xy 44.323789 -242.412711)
			(xy 44.378578 -242.381078) (xy 44.437028 -242.356867) (xy 44.498137 -242.340493) (xy 44.560861 -242.332235)
			(xy 44.624127 -242.332235) (xy 44.686851 -242.340493) (xy 44.74796 -242.356867) (xy 44.80641 -242.381078)
			(xy 44.861199 -242.412711) (xy 44.911391 -242.451224) (xy 44.934124 -242.473226) (xy 45.036486 -242.575842)
			(xy 45.048623 -242.5873) (xy 45.077496 -242.604023) (xy 45.109719 -242.61268) (xy 45.126402 -242.61318)
			(xy 46.00829 -242.61318) (xy 46.036578 -242.61358) (xy 46.092772 -242.620129) (xy 46.147813 -242.63321)
			(xy 46.200946 -242.652641) (xy 46.25144 -242.678157) (xy 46.275244 -242.693444) (xy 46.306994 -242.71478)
			(xy 46.364144 -242.71478) (xy 46.364144 -242.769644) (xy 46.384044 -242.791935) (xy 46.418692 -242.840623)
			(xy 46.447068 -242.893215) (xy 46.468737 -242.948905) (xy 46.483369 -243.006844) (xy 46.490739 -243.066146)
			(xy 46.490736 -243.125904) (xy 46.483359 -243.185205) (xy 46.468722 -243.243142) (xy 46.447047 -243.298831)
			(xy 46.418666 -243.351419) (xy 46.384013 -243.400104) (xy 46.364144 -243.422424) (xy 46.364144 -243.477288)
			(xy 46.306994 -243.477288) (xy 46.275244 -243.498624) (xy 46.251422 -243.51388) (xy 46.200923 -243.539377)
			(xy 46.147794 -243.558807) (xy 46.092761 -243.571905) (xy 46.036575 -243.578493) (xy 46.00829 -243.578888)
			(xy 44.67352 -243.578888) (xy 44.250864 -243.156486) (xy 44.228862 -243.133753) (xy 44.190349 -243.083561)
			(xy 44.158716 -243.028772) (xy 44.134505 -242.970322) (xy 44.118131 -242.909213) (xy 44.109873 -242.846489)
			(xy 28.942538 -242.846489) (xy 28.942538 -243.756875) (xy 58.378214 -243.756875) (xy 58.382105 -243.702524)
			(xy 58.393691 -243.64928) (xy 58.412738 -243.598228) (xy 58.438856 -243.550406) (xy 58.471515 -243.506788)
			(xy 58.51005 -243.468262) (xy 58.553675 -243.435612) (xy 58.601502 -243.409504) (xy 58.652559 -243.390468)
			(xy 58.705805 -243.378893) (xy 58.760157 -243.375014) (xy 58.814507 -243.378909) (xy 58.86775 -243.3905)
			(xy 58.918801 -243.409551) (xy 58.966621 -243.435673) (xy 58.988706 -243.451634) (xy 59.007718 -243.46523)
			(xy 59.049601 -243.485962) (xy 59.094569 -243.498688) (xy 59.141106 -243.502978) (xy 59.187643 -243.498688)
			(xy 59.232611 -243.485962) (xy 59.274494 -243.46523) (xy 59.293506 -243.451634) (xy 59.315555 -243.435618)
			(xy 59.363382 -243.409493) (xy 59.414441 -243.39044) (xy 59.467692 -243.378849) (xy 59.52205 -243.374953)
			(xy 59.57641 -243.378834) (xy 59.629663 -243.390412) (xy 59.680727 -243.409451) (xy 59.728561 -243.435564)
			(xy 59.772193 -243.468219) (xy 59.810732 -243.506751) (xy 59.843395 -243.550375) (xy 59.869518 -243.598205)
			(xy 59.888567 -243.649265) (xy 59.900155 -243.702516) (xy 59.904047 -243.756875) (xy 60.264906 -243.756875)
			(xy 60.268798 -243.702522) (xy 60.280385 -243.649277) (xy 60.299432 -243.598223) (xy 60.325552 -243.5504)
			(xy 60.358212 -243.506781) (xy 60.396748 -243.468254) (xy 60.440374 -243.435604) (xy 60.488204 -243.409495)
			(xy 60.539262 -243.39046) (xy 60.59251 -243.378885) (xy 60.646863 -243.375006) (xy 60.701215 -243.378903)
			(xy 60.754459 -243.390496) (xy 60.805512 -243.409548) (xy 60.853332 -243.435672) (xy 60.875418 -243.451634)
			(xy 60.89443 -243.46523) (xy 60.936313 -243.485962) (xy 60.981281 -243.498688) (xy 61.027818 -243.502978)
			(xy 61.074355 -243.498688) (xy 61.119323 -243.485962) (xy 61.161206 -243.46523) (xy 61.180218 -243.451634)
			(xy 61.202266 -243.435619) (xy 61.250093 -243.409496) (xy 61.301151 -243.390445) (xy 61.3544 -243.378855)
			(xy 61.408757 -243.374961) (xy 61.463115 -243.378842) (xy 61.516367 -243.390421) (xy 61.567429 -243.40946)
			(xy 61.615261 -243.435572) (xy 61.658891 -243.468227) (xy 61.697429 -243.506758) (xy 61.730091 -243.550381)
			(xy 61.756212 -243.598209) (xy 61.77526 -243.649268) (xy 61.786848 -243.702518) (xy 61.790739 -243.756875)
			(xy 62.506041 -243.756875) (xy 62.509932 -243.70253) (xy 62.521516 -243.649293) (xy 62.54056 -243.598246)
			(xy 62.566674 -243.550429) (xy 62.599328 -243.506815) (xy 62.637857 -243.468292) (xy 62.681476 -243.435644)
			(xy 62.729296 -243.409537) (xy 62.780346 -243.390501) (xy 62.833586 -243.378924) (xy 62.88793 -243.375041)
			(xy 62.942275 -243.378932) (xy 62.995512 -243.390518) (xy 63.046559 -243.409562) (xy 63.094376 -243.435677)
			(xy 63.11646 -243.451634) (xy 63.135472 -243.46523) (xy 63.177355 -243.485962) (xy 63.222323 -243.498688)
			(xy 63.26886 -243.502978) (xy 63.315397 -243.498688) (xy 63.360365 -243.485962) (xy 63.402248 -243.46523)
			(xy 63.42126 -243.451634) (xy 63.44331 -243.435614) (xy 63.49114 -243.409481) (xy 63.542204 -243.390423)
			(xy 63.59546 -243.378825) (xy 63.649824 -243.374926) (xy 63.70419 -243.378804) (xy 63.75745 -243.39038)
			(xy 63.808521 -243.409418) (xy 63.856362 -243.435532) (xy 63.9 -243.468189) (xy 63.938545 -243.506724)
			(xy 63.971213 -243.550352) (xy 63.99734 -243.598187) (xy 64.016392 -243.649252) (xy 64.027982 -243.70251)
			(xy 64.031874 -243.756875) (xy 64.409891 -243.756875) (xy 64.413782 -243.702519) (xy 64.425371 -243.64927)
			(xy 64.44442 -243.598213) (xy 64.470542 -243.550387) (xy 64.503205 -243.506765) (xy 64.541744 -243.468237)
			(xy 64.585374 -243.435586) (xy 64.633207 -243.409477) (xy 64.68427 -243.390441) (xy 64.737521 -243.378868)
			(xy 64.791878 -243.374991) (xy 64.846234 -243.37889) (xy 64.899481 -243.390486) (xy 64.950535 -243.409542)
			(xy 64.998358 -243.43567) (xy 65.020444 -243.451634) (xy 65.039456 -243.46523) (xy 65.081339 -243.485962)
			(xy 65.126307 -243.498688) (xy 65.172844 -243.502978) (xy 65.219381 -243.498688) (xy 65.264349 -243.485962)
			(xy 65.306232 -243.46523) (xy 65.325244 -243.451634) (xy 65.347292 -243.435621) (xy 65.395117 -243.409502)
			(xy 65.446172 -243.390455) (xy 65.499418 -243.378868) (xy 65.553772 -243.374976) (xy 65.608126 -243.37886)
			(xy 65.661374 -243.390439) (xy 65.712432 -243.409479) (xy 65.760261 -243.435591) (xy 65.803887 -243.468244)
			(xy 65.842421 -243.506773) (xy 65.875081 -243.550394) (xy 65.901199 -243.598219) (xy 65.920246 -243.649275)
			(xy 65.931833 -243.702521) (xy 65.935724 -243.756875) (xy 65.934013 -243.780818) (xy 72.126856 -243.780818)
			(xy 72.126856 -242.763294) (xy 72.127538 -242.727228) (xy 72.137867 -242.655836) (xy 72.14743 -242.621054)
			(xy 72.152256 -242.603528) (xy 72.152256 -242.22964) (xy 73.118472 -242.22964) (xy 73.118472 -242.603528)
			(xy 73.123298 -242.621054) (xy 73.132846 -242.655839) (xy 73.143169 -242.727229) (xy 73.143872 -242.763294)
			(xy 73.143872 -242.936268) (xy 73.454768 -242.936268) (xy 73.454768 -241.918744) (xy 73.455296 -241.886009)
			(xy 73.463731 -241.821085) (xy 73.480429 -241.757781) (xy 73.505113 -241.697142) (xy 73.537375 -241.640174)
			(xy 73.556622 -241.61369) (xy 73.581768 -241.579908) (xy 73.581768 -241.562636) (xy 73.597262 -241.562636)
			(xy 73.633076 -241.53241) (xy 73.658253 -241.511557) (xy 73.712985 -241.475806) (xy 73.77185 -241.447367)
			(xy 73.833875 -241.426712) (xy 73.898037 -241.414181) (xy 73.963276 -241.409981) (xy 74.028515 -241.414181)
			(xy 74.092677 -241.426712) (xy 74.154702 -241.447367) (xy 74.213567 -241.475806) (xy 74.268299 -241.511557)
			(xy 74.293476 -241.53241) (xy 74.32929 -241.562636) (xy 74.344784 -241.562636) (xy 74.344784 -241.579908)
			(xy 74.36993 -241.61369) (xy 74.390955 -241.642744) (xy 74.425503 -241.70559) (xy 74.438764 -241.738912)
			(xy 74.444588 -241.753179) (xy 74.462033 -241.778573) (xy 74.485059 -241.799041) (xy 74.512323 -241.813389)
			(xy 74.542232 -241.820779) (xy 74.57304 -241.820779) (xy 74.602949 -241.813389) (xy 74.630213 -241.799041)
			(xy 74.653239 -241.778573) (xy 74.670684 -241.753179) (xy 74.676508 -241.738912) (xy 74.689782 -241.705596)
			(xy 74.724321 -241.642746) (xy 74.745342 -241.61369) (xy 74.770488 -241.579908) (xy 74.770488 -241.562636)
			(xy 74.785982 -241.562636) (xy 74.821796 -241.53241) (xy 74.846973 -241.511557) (xy 74.901705 -241.475806)
			(xy 74.96057 -241.447367) (xy 75.022595 -241.426712) (xy 75.086757 -241.414181) (xy 75.151996 -241.409981)
			(xy 75.217235 -241.414181) (xy 75.281397 -241.426712) (xy 75.343422 -241.447367) (xy 75.402287 -241.475806)
			(xy 75.457019 -241.511557) (xy 75.482196 -241.53241) (xy 75.51801 -241.562636) (xy 75.533504 -241.562636)
			(xy 75.533504 -241.579908) (xy 75.55865 -241.61369) (xy 75.577896 -241.640174) (xy 75.61016 -241.697142)
			(xy 75.611551 -241.700558) (xy 81.259932 -241.700558) (xy 81.264003 -241.644936) (xy 81.276129 -241.590499)
			(xy 81.296052 -241.538408) (xy 81.323348 -241.489773) (xy 81.357434 -241.44563) (xy 81.397583 -241.406921)
			(xy 81.442941 -241.37447) (xy 81.492541 -241.348969) (xy 81.545325 -241.330962) (xy 81.600168 -241.320832)
			(xy 81.655902 -241.318795) (xy 81.711339 -241.324895) (xy 81.765296 -241.339001) (xy 81.816625 -241.360813)
			(xy 81.864231 -241.389867) (xy 81.907099 -241.425542) (xy 81.944316 -241.467079) (xy 81.975089 -241.513592)
			(xy 81.998761 -241.564089) (xy 82.014829 -241.617496) (xy 82.022949 -241.672672) (xy 82.023458 -241.700558)
			(xy 82.022949 -241.728444) (xy 82.014829 -241.78362) (xy 81.998761 -241.837027) (xy 81.975089 -241.887524)
			(xy 81.944316 -241.934037) (xy 81.907099 -241.975574) (xy 81.864231 -242.011249) (xy 81.816625 -242.040303)
			(xy 81.765296 -242.062115) (xy 81.711339 -242.076221) (xy 81.655902 -242.082321) (xy 81.600168 -242.080284)
			(xy 81.545325 -242.070154) (xy 81.492541 -242.052147) (xy 81.442941 -242.026646) (xy 81.397583 -241.994195)
			(xy 81.357434 -241.955486) (xy 81.323348 -241.911343) (xy 81.296052 -241.862708) (xy 81.276129 -241.810617)
			(xy 81.264003 -241.75618) (xy 81.259932 -241.700558) (xy 75.611551 -241.700558) (xy 75.634845 -241.75778)
			(xy 75.651544 -241.821085) (xy 75.659979 -241.886009) (xy 75.660504 -241.918744) (xy 75.660504 -242.26012)
			(xy 86.39887 -242.26012) (xy 86.402874 -242.060022) (xy 86.414881 -241.860244) (xy 86.434872 -241.661107)
			(xy 86.462814 -241.462929) (xy 86.498662 -241.266027) (xy 86.54236 -241.070718) (xy 86.593837 -240.877313)
			(xy 86.653011 -240.686123) (xy 86.719787 -240.497453) (xy 86.794059 -240.311606) (xy 86.875706 -240.128879)
			(xy 86.964599 -239.949566) (xy 87.060595 -239.773952) (xy 87.16354 -239.60232) (xy 87.27327 -239.434944)
			(xy 87.389608 -239.272093) (xy 87.512369 -239.114026) (xy 87.641356 -238.960998) (xy 87.776363 -238.813253)
			(xy 87.917172 -238.671027) (xy 88.063559 -238.53455) (xy 88.215289 -238.404038) (xy 88.37212 -238.279702)
			(xy 88.533799 -238.16174) (xy 88.700069 -238.050341) (xy 88.870662 -237.945684) (xy 89.045306 -237.847936)
			(xy 89.223722 -237.757253) (xy 89.405622 -237.673782) (xy 89.590717 -237.597655) (xy 89.778709 -237.528995)
			(xy 89.969298 -237.467911) (xy 90.162178 -237.414501) (xy 90.35704 -237.368852) (xy 90.553573 -237.331035)
			(xy 90.751462 -237.301111) (xy 90.950389 -237.279129) (xy 91.150037 -237.265124) (xy 91.350085 -237.259118)
			(xy 91.550213 -237.26112) (xy 91.750101 -237.271128) (xy 91.949428 -237.289125) (xy 92.147876 -237.315083)
			(xy 92.345126 -237.34896) (xy 92.540863 -237.390702) (xy 92.734773 -237.440241) (xy 92.926546 -237.497499)
			(xy 93.115875 -237.562384) (xy 93.302455 -237.634792) (xy 93.48599 -237.714608) (xy 93.666184 -237.801702)
			(xy 93.842749 -237.895936) (xy 94.015402 -237.997159) (xy 94.183867 -238.105209) (xy 94.347875 -238.219912)
			(xy 94.507162 -238.341086) (xy 94.661473 -238.468535) (xy 94.810561 -238.602056) (xy 94.954188 -238.741436)
			(xy 95.092124 -238.88645) (xy 95.224147 -239.036867) (xy 95.350046 -239.192445) (xy 95.46962 -239.352937)
			(xy 95.582676 -239.518083) (xy 95.689035 -239.687621) (xy 95.788526 -239.861279) (xy 95.880989 -240.038778)
			(xy 95.966276 -240.219834) (xy 96.044251 -240.404158) (xy 96.114788 -240.591454) (xy 96.177776 -240.781422)
			(xy 96.233113 -240.973758) (xy 96.28071 -241.168154) (xy 96.320491 -241.364299) (xy 96.352393 -241.561878)
			(xy 96.376364 -241.760575) (xy 96.392366 -241.960073) (xy 96.400373 -242.160051) (xy 96.400874 -242.26012)
			(xy 96.400373 -242.360189) (xy 96.392366 -242.560167) (xy 96.376364 -242.759665) (xy 96.352393 -242.958362)
			(xy 96.320491 -243.155941) (xy 96.28071 -243.352086) (xy 96.233113 -243.546482) (xy 96.177776 -243.738818)
			(xy 96.114788 -243.928786) (xy 96.044251 -244.116082) (xy 95.966276 -244.300406) (xy 95.880989 -244.481462)
			(xy 95.788526 -244.658961) (xy 95.689035 -244.832619) (xy 95.582676 -245.002157) (xy 95.46962 -245.167303)
			(xy 95.350046 -245.327795) (xy 95.224147 -245.483373) (xy 95.092124 -245.63379) (xy 94.954188 -245.778804)
			(xy 94.810561 -245.918184) (xy 94.661473 -246.051705) (xy 94.507162 -246.179154) (xy 94.347875 -246.300328)
			(xy 94.183867 -246.415031) (xy 94.015402 -246.523081) (xy 93.842749 -246.624304) (xy 93.666184 -246.718538)
			(xy 93.48599 -246.805632) (xy 93.302455 -246.885448) (xy 93.115875 -246.957856) (xy 92.926546 -247.022741)
			(xy 92.734773 -247.079999) (xy 92.540863 -247.129538) (xy 92.345126 -247.17128) (xy 92.147876 -247.205157)
			(xy 91.949428 -247.231115) (xy 91.750101 -247.249112) (xy 91.550213 -247.25912) (xy 91.350085 -247.261122)
			(xy 91.150037 -247.255116) (xy 90.950389 -247.241111) (xy 90.751462 -247.219129) (xy 90.553573 -247.189205)
			(xy 90.35704 -247.151388) (xy 90.162178 -247.105739) (xy 89.969298 -247.052329) (xy 89.778709 -246.991245)
			(xy 89.590717 -246.922585) (xy 89.405622 -246.846458) (xy 89.223722 -246.762987) (xy 89.045306 -246.672304)
			(xy 88.870662 -246.574556) (xy 88.700069 -246.469899) (xy 88.533799 -246.3585) (xy 88.37212 -246.240538)
			(xy 88.215289 -246.116202) (xy 88.063559 -245.98569) (xy 87.917172 -245.849213) (xy 87.776363 -245.706987)
			(xy 87.641356 -245.559242) (xy 87.512369 -245.406214) (xy 87.389608 -245.248147) (xy 87.27327 -245.085296)
			(xy 87.16354 -244.91792) (xy 87.060595 -244.746288) (xy 86.964599 -244.570674) (xy 86.875706 -244.391361)
			(xy 86.794059 -244.208634) (xy 86.719787 -244.022787) (xy 86.653011 -243.834117) (xy 86.593837 -243.642927)
			(xy 86.54236 -243.449522) (xy 86.498662 -243.254213) (xy 86.462814 -243.057311) (xy 86.434872 -242.859133)
			(xy 86.414881 -242.659996) (xy 86.402874 -242.460218) (xy 86.39887 -242.26012) (xy 75.660504 -242.26012)
			(xy 75.660504 -242.936268) (xy 75.66005 -242.967611) (xy 75.652358 -243.029824) (xy 75.637073 -243.090619)
			(xy 75.614429 -243.149073) (xy 75.584769 -243.204298) (xy 75.548543 -243.255457) (xy 75.506301 -243.301774)
			(xy 75.458684 -243.342544) (xy 75.406415 -243.37715) (xy 75.350287 -243.405065) (xy 75.291153 -243.425867)
			(xy 75.229909 -243.439239) (xy 75.167486 -243.444978) (xy 75.104831 -243.442998) (xy 75.042895 -243.433329)
			(xy 74.982618 -243.416116) (xy 74.924915 -243.391622) (xy 74.870661 -243.360218) (xy 74.820682 -243.322381)
			(xy 74.775734 -243.278685) (xy 74.755756 -243.25453) (xy 74.741121 -243.237127) (xy 74.706789 -243.207319)
			(xy 74.667704 -243.18409) (xy 74.625112 -243.168181) (xy 74.580369 -243.160097) (xy 74.534903 -243.160097)
			(xy 74.49016 -243.168181) (xy 74.447568 -243.18409) (xy 74.408483 -243.207319) (xy 74.374151 -243.237127)
			(xy 74.359516 -243.25453) (xy 74.339608 -243.278737) (xy 74.294646 -243.32241) (xy 74.244657 -243.360224)
			(xy 74.190399 -243.391606) (xy 74.132694 -243.416081) (xy 74.072419 -243.433277) (xy 74.010487 -243.442933)
			(xy 73.947838 -243.444903) (xy 73.885421 -243.439156) (xy 73.824185 -243.425781) (xy 73.765057 -243.404979)
			(xy 73.708934 -243.377067) (xy 73.656669 -243.342467) (xy 73.609053 -243.301705) (xy 73.566809 -243.255399)
			(xy 73.530577 -243.204252) (xy 73.500907 -243.149038) (xy 73.47825 -243.090596) (xy 73.462949 -243.029812)
			(xy 73.455236 -242.967608) (xy 73.454768 -242.936268) (xy 73.143872 -242.936268) (xy 73.143872 -243.780818)
			(xy 73.14337 -243.812779) (xy 73.135359 -243.876197) (xy 73.119462 -243.938111) (xy 73.09593 -243.997544)
			(xy 73.065136 -244.053559) (xy 73.027563 -244.105274) (xy 72.983806 -244.151871) (xy 72.934553 -244.192616)
			(xy 72.880582 -244.226867) (xy 72.822743 -244.254084) (xy 72.76195 -244.273837) (xy 72.69916 -244.285815)
			(xy 72.635364 -244.289829) (xy 72.571568 -244.285815) (xy 72.508778 -244.273837) (xy 72.447985 -244.254084)
			(xy 72.390146 -244.226867) (xy 72.336175 -244.192616) (xy 72.286922 -244.151871) (xy 72.243165 -244.105274)
			(xy 72.205592 -244.053559) (xy 72.174798 -243.997544) (xy 72.151266 -243.938111) (xy 72.135369 -243.876197)
			(xy 72.127358 -243.812779) (xy 72.126856 -243.780818) (xy 65.934013 -243.780818) (xy 65.93184 -243.811229)
			(xy 65.92026 -243.864477) (xy 65.90122 -243.915535) (xy 65.875108 -243.963363) (xy 65.842454 -244.006989)
			(xy 65.803925 -244.045523) (xy 65.760303 -244.078182) (xy 65.712478 -244.104301) (xy 65.661422 -244.123347)
			(xy 65.608176 -244.134933) (xy 65.553822 -244.138824) (xy 65.499468 -244.134939) (xy 65.44622 -244.123359)
			(xy 65.395163 -244.104319) (xy 65.347334 -244.078206) (xy 65.325244 -244.06225) (xy 65.306232 -244.048654)
			(xy 65.264349 -244.027922) (xy 65.219381 -244.015196) (xy 65.172844 -244.010906) (xy 65.126307 -244.015196)
			(xy 65.081339 -244.027922) (xy 65.039456 -244.048654) (xy 65.020444 -244.06225) (xy 64.998315 -244.078157)
			(xy 64.950489 -244.104279) (xy 64.899432 -244.123329) (xy 64.846184 -244.134917) (xy 64.791828 -244.138809)
			(xy 64.737471 -244.134925) (xy 64.684221 -244.123344) (xy 64.633161 -244.104302) (xy 64.585331 -244.078187)
			(xy 64.541705 -244.04553) (xy 64.503172 -244.006997) (xy 64.470514 -243.963371) (xy 64.444399 -243.915541)
			(xy 64.425356 -243.864481) (xy 64.413775 -243.811231) (xy 64.409891 -243.756875) (xy 64.031874 -243.756875)
			(xy 64.027989 -243.81124) (xy 64.016406 -243.864499) (xy 63.997361 -243.915567) (xy 63.971241 -243.963405)
			(xy 63.938578 -244.007038) (xy 63.900038 -244.045578) (xy 63.856405 -244.078241) (xy 63.808567 -244.104361)
			(xy 63.757499 -244.123406) (xy 63.70424 -244.134989) (xy 63.649874 -244.138874) (xy 63.59551 -244.134982)
			(xy 63.542252 -244.123392) (xy 63.491186 -244.104339) (xy 63.443352 -244.078213) (xy 63.42126 -244.06225)
			(xy 63.402248 -244.048654) (xy 63.360365 -244.027922) (xy 63.315397 -244.015196) (xy 63.26886 -244.010906)
			(xy 63.222323 -244.015196) (xy 63.177355 -244.027922) (xy 63.135472 -244.048654) (xy 63.11646 -244.06225)
			(xy 63.094333 -244.07815) (xy 63.046513 -244.104259) (xy 62.995464 -244.123296) (xy 62.942225 -244.134875)
			(xy 62.88788 -244.138759) (xy 62.833536 -244.134869) (xy 62.780298 -244.123285) (xy 62.729251 -244.104242)
			(xy 62.681433 -244.078128) (xy 62.637819 -244.045475) (xy 62.599295 -244.006947) (xy 62.566647 -243.963329)
			(xy 62.540539 -243.915508) (xy 62.521502 -243.864459) (xy 62.509924 -243.81122) (xy 62.506041 -243.756875)
			(xy 61.790739 -243.756875) (xy 61.786855 -243.811232) (xy 61.775274 -243.864484) (xy 61.756233 -243.915545)
			(xy 61.730118 -243.963376) (xy 61.697462 -244.007004) (xy 61.658929 -244.04554) (xy 61.615304 -244.0782)
			(xy 61.567474 -244.104319) (xy 61.516415 -244.123365) (xy 61.463165 -244.13495) (xy 61.408807 -244.138839)
			(xy 61.35445 -244.134953) (xy 61.301199 -244.123369) (xy 61.250139 -244.104325) (xy 61.202309 -244.078208)
			(xy 61.180218 -244.06225) (xy 61.161206 -244.048654) (xy 61.119323 -244.027922) (xy 61.074355 -244.015196)
			(xy 61.027818 -244.010906) (xy 60.981281 -244.015196) (xy 60.936313 -244.027922) (xy 60.89443 -244.048654)
			(xy 60.875418 -244.06225) (xy 60.85329 -244.078155) (xy 60.805466 -244.104273) (xy 60.754411 -244.123319)
			(xy 60.701166 -244.134904) (xy 60.646813 -244.138794) (xy 60.59246 -244.134908) (xy 60.539214 -244.123326)
			(xy 60.488158 -244.104284) (xy 60.440332 -244.078169) (xy 60.39671 -244.045513) (xy 60.358179 -244.006981)
			(xy 60.325524 -243.963358) (xy 60.299411 -243.915531) (xy 60.280371 -243.864474) (xy 60.26879 -243.811228)
			(xy 60.264906 -243.756875) (xy 59.904047 -243.756875) (xy 59.900162 -243.811234) (xy 59.888581 -243.864487)
			(xy 59.869538 -243.91555) (xy 59.843423 -243.963382) (xy 59.810765 -244.007011) (xy 59.772231 -244.045548)
			(xy 59.728604 -244.078209) (xy 59.680773 -244.104328) (xy 59.629712 -244.123374) (xy 59.576459 -244.134958)
			(xy 59.522101 -244.138847) (xy 59.467742 -244.134959) (xy 59.414489 -244.123374) (xy 59.363428 -244.104328)
			(xy 59.315597 -244.078209) (xy 59.293506 -244.06225) (xy 59.274494 -244.048654) (xy 59.232611 -244.027922)
			(xy 59.187643 -244.015196) (xy 59.141106 -244.010906) (xy 59.094569 -244.015196) (xy 59.049601 -244.027922)
			(xy 59.007718 -244.048654) (xy 58.988706 -244.06225) (xy 58.966578 -244.078154) (xy 58.918755 -244.10427)
			(xy 58.867701 -244.123314) (xy 58.814457 -244.134898) (xy 58.760106 -244.138786) (xy 58.705755 -244.1349)
			(xy 58.652511 -244.123318) (xy 58.601456 -244.104275) (xy 58.553632 -244.078161) (xy 58.510011 -244.045505)
			(xy 58.471482 -244.006974) (xy 58.438829 -243.963352) (xy 58.412717 -243.915526) (xy 58.393677 -243.864471)
			(xy 58.382097 -243.811226) (xy 58.378214 -243.756875) (xy 28.942538 -243.756875) (xy 28.942538 -244.757077)
			(xy 44.058565 -244.757077) (xy 44.058565 -244.693811) (xy 44.066823 -244.631087) (xy 44.083197 -244.569978)
			(xy 44.107408 -244.511528) (xy 44.139041 -244.456739) (xy 44.177554 -244.406547) (xy 44.199556 -244.383814)
			(xy 44.548044 -244.03558) (xy 45.985684 -244.03558) (xy 46.013947 -244.035973) (xy 46.070088 -244.042545)
			(xy 46.125077 -244.055636) (xy 46.178157 -244.075066) (xy 46.228602 -244.100568) (xy 46.252384 -244.115844)
			(xy 46.284388 -244.136926) (xy 46.447202 -244.136926) (xy 46.480984 -244.111526) (xy 46.507458 -244.092328)
			(xy 46.564393 -244.060157) (xy 46.624984 -244.035552) (xy 46.68823 -244.018919) (xy 46.753086 -244.010534)
			(xy 46.818482 -244.010534) (xy 46.883338 -244.018919) (xy 46.946584 -244.035552) (xy 47.007175 -244.060157)
			(xy 47.06411 -244.092328) (xy 47.090584 -244.111526) (xy 47.124366 -244.136926) (xy 47.141892 -244.136926)
			(xy 47.141892 -244.155722) (xy 47.165538 -244.179707) (xy 47.206976 -244.232805) (xy 47.24104 -244.290909)
			(xy 47.267134 -244.353003) (xy 47.284799 -244.417999) (xy 47.293728 -244.484758) (xy 47.294292 -244.518434)
			(xy 47.294292 -245.657913) (xy 58.378162 -245.657913) (xy 58.382048 -245.603555) (xy 58.393631 -245.550303)
			(xy 58.412675 -245.499242) (xy 58.438793 -245.45141) (xy 58.471451 -245.407783) (xy 58.509987 -245.369248)
			(xy 58.553615 -245.33659) (xy 58.601446 -245.310473) (xy 58.652508 -245.29143) (xy 58.70576 -245.279848)
			(xy 58.760118 -245.275962) (xy 58.814476 -245.279853) (xy 58.867727 -245.29144) (xy 58.918787 -245.310488)
			(xy 58.966616 -245.33661) (xy 58.988706 -245.35257) (xy 59.007718 -245.366166) (xy 59.049601 -245.386898)
			(xy 59.094569 -245.399624) (xy 59.141106 -245.403914) (xy 59.187643 -245.399624) (xy 59.232611 -245.386898)
			(xy 59.274494 -245.366166) (xy 59.293506 -245.35257) (xy 59.315615 -245.33664) (xy 59.363438 -245.310523)
			(xy 59.414492 -245.291479) (xy 59.467737 -245.279894) (xy 59.522089 -245.276005) (xy 59.57644 -245.279891)
			(xy 59.629686 -245.291472) (xy 59.680741 -245.310514) (xy 59.728566 -245.336628) (xy 59.772188 -245.369283)
			(xy 59.810719 -245.407813) (xy 59.843373 -245.451435) (xy 59.869487 -245.499261) (xy 59.888528 -245.550316)
			(xy 59.90011 -245.603561) (xy 59.903995 -245.657913) (xy 60.264855 -245.657913) (xy 60.268741 -245.603553)
			(xy 60.280325 -245.5503) (xy 60.29937 -245.499237) (xy 60.325488 -245.451404) (xy 60.358148 -245.407776)
			(xy 60.396685 -245.36924) (xy 60.440314 -245.336581) (xy 60.488148 -245.310465) (xy 60.539211 -245.291421)
			(xy 60.592465 -245.27984) (xy 60.646825 -245.275955) (xy 60.701185 -245.279847) (xy 60.754437 -245.291436)
			(xy 60.805498 -245.310485) (xy 60.853328 -245.336609) (xy 60.875418 -245.35257) (xy 60.89443 -245.366166)
			(xy 60.936313 -245.386898) (xy 60.981281 -245.399624) (xy 61.027818 -245.403914) (xy 61.074355 -245.399624)
			(xy 61.119323 -245.386898) (xy 61.161206 -245.366166) (xy 61.180218 -245.35257) (xy 61.202326 -245.336641)
			(xy 61.250149 -245.310526) (xy 61.301202 -245.291483) (xy 61.354445 -245.2799) (xy 61.408795 -245.276012)
			(xy 61.463145 -245.279899) (xy 61.516389 -245.291481) (xy 61.567442 -245.310522) (xy 61.615266 -245.336636)
			(xy 61.658886 -245.369291) (xy 61.697415 -245.40782) (xy 61.730068 -245.451441) (xy 61.756181 -245.499266)
			(xy 61.775222 -245.550319) (xy 61.786803 -245.603563) (xy 61.790688 -245.657913) (xy 62.50599 -245.657913)
			(xy 62.509875 -245.603561) (xy 62.521456 -245.550315) (xy 62.540497 -245.499259) (xy 62.566611 -245.451433)
			(xy 62.599264 -245.40781) (xy 62.637794 -245.369278) (xy 62.681416 -245.336622) (xy 62.72924 -245.310506)
			(xy 62.780295 -245.291462) (xy 62.83354 -245.279878) (xy 62.887892 -245.27599) (xy 62.942244 -245.279876)
			(xy 62.99549 -245.291458) (xy 63.046545 -245.3105) (xy 63.094371 -245.336613) (xy 63.11646 -245.35257)
			(xy 63.135472 -245.366166) (xy 63.177355 -245.386898) (xy 63.222323 -245.399624) (xy 63.26886 -245.403914)
			(xy 63.315397 -245.399624) (xy 63.360365 -245.386898) (xy 63.402248 -245.366166) (xy 63.42126 -245.35257)
			(xy 63.44337 -245.336636) (xy 63.491197 -245.310512) (xy 63.542255 -245.291461) (xy 63.595505 -245.279871)
			(xy 63.649862 -245.275977) (xy 63.704221 -245.27986) (xy 63.757473 -245.29144) (xy 63.808535 -245.310481)
			(xy 63.856367 -245.336596) (xy 63.899995 -245.369252) (xy 63.938532 -245.407786) (xy 63.971191 -245.451412)
			(xy 63.997309 -245.499243) (xy 64.016353 -245.550304) (xy 64.027937 -245.603555) (xy 64.031823 -245.657913)
			(xy 64.409839 -245.657913) (xy 64.413726 -245.60355) (xy 64.425311 -245.550293) (xy 64.444357 -245.499227)
			(xy 64.470478 -245.451391) (xy 64.503141 -245.407761) (xy 64.541681 -245.369223) (xy 64.585314 -245.336563)
			(xy 64.633151 -245.310446) (xy 64.684218 -245.291403) (xy 64.737476 -245.279822) (xy 64.79184 -245.275939)
			(xy 64.846203 -245.279834) (xy 64.899458 -245.291426) (xy 64.950522 -245.310479) (xy 64.998353 -245.336606)
			(xy 65.020444 -245.35257) (xy 65.039456 -245.366166) (xy 65.081339 -245.386898) (xy 65.126307 -245.399624)
			(xy 65.172844 -245.403914) (xy 65.219381 -245.399624) (xy 65.264349 -245.386898) (xy 65.306232 -245.366166)
			(xy 65.325244 -245.35257) (xy 65.347352 -245.336643) (xy 65.395173 -245.310533) (xy 65.446223 -245.291493)
			(xy 65.499464 -245.279913) (xy 65.55381 -245.276027) (xy 65.608156 -245.279916) (xy 65.661396 -245.291499)
			(xy 65.712446 -245.310541) (xy 65.760265 -245.336654) (xy 65.803882 -245.369308) (xy 65.842408 -245.407836)
			(xy 65.875058 -245.451454) (xy 65.901169 -245.499276) (xy 65.920208 -245.550326) (xy 65.931787 -245.603567)
			(xy 65.935673 -245.657913) (xy 65.931784 -245.712259) (xy 65.9202 -245.765499) (xy 65.901158 -245.816548)
			(xy 65.875044 -245.864368) (xy 65.84239 -245.907984) (xy 65.803862 -245.94651) (xy 65.760243 -245.97916)
			(xy 65.712422 -246.00527) (xy 65.661371 -246.024308) (xy 65.60813 -246.035888) (xy 65.553784 -246.039773)
			(xy 65.499438 -246.035883) (xy 65.446198 -246.024299) (xy 65.395149 -246.005256) (xy 65.34733 -245.979142)
			(xy 65.325244 -245.963186) (xy 65.306232 -245.94959) (xy 65.264349 -245.928858) (xy 65.219381 -245.916132)
			(xy 65.172844 -245.911842) (xy 65.126307 -245.916132) (xy 65.081339 -245.928858) (xy 65.039456 -245.94959)
			(xy 65.020444 -245.963186) (xy 64.998375 -245.979179) (xy 64.950546 -246.00531) (xy 64.899484 -246.024367)
			(xy 64.846229 -246.035963) (xy 64.791866 -246.03986) (xy 64.737502 -246.035981) (xy 64.684244 -246.024404)
			(xy 64.633175 -246.005365) (xy 64.585336 -245.979251) (xy 64.541701 -245.946594) (xy 64.503158 -245.908059)
			(xy 64.470492 -245.864431) (xy 64.444368 -245.816597) (xy 64.425318 -245.765533) (xy 64.41373 -245.712276)
			(xy 64.409839 -245.657913) (xy 64.031823 -245.657913) (xy 64.027933 -245.712271) (xy 64.016346 -245.765522)
			(xy 63.997298 -245.816581) (xy 63.971177 -245.86441) (xy 63.938514 -245.908034) (xy 63.899975 -245.946565)
			(xy 63.856345 -245.979219) (xy 63.808511 -246.00533) (xy 63.757448 -246.024368) (xy 63.704195 -246.035944)
			(xy 63.649836 -246.039823) (xy 63.595479 -246.035926) (xy 63.54223 -246.024332) (xy 63.491173 -246.005277)
			(xy 63.443348 -245.979149) (xy 63.42126 -245.963186) (xy 63.402248 -245.94959) (xy 63.360365 -245.928858)
			(xy 63.315397 -245.916132) (xy 63.26886 -245.911842) (xy 63.222323 -245.916132) (xy 63.177355 -245.928858)
			(xy 63.135472 -245.94959) (xy 63.11646 -245.963186) (xy 63.094393 -245.979172) (xy 63.046569 -246.005289)
			(xy 62.995515 -246.024335) (xy 62.94227 -246.03592) (xy 62.887918 -246.03981) (xy 62.833566 -246.035925)
			(xy 62.78032 -246.024345) (xy 62.729264 -246.005305) (xy 62.681438 -245.979192) (xy 62.637814 -245.946539)
			(xy 62.599282 -245.90801) (xy 62.566625 -245.864389) (xy 62.540508 -245.816565) (xy 62.521464 -245.76551)
			(xy 62.509879 -245.712265) (xy 62.50599 -245.657913) (xy 61.790688 -245.657913) (xy 61.786799 -245.712263)
			(xy 61.775214 -245.765506) (xy 61.75617 -245.816558) (xy 61.730054 -245.864381) (xy 61.697398 -245.908)
			(xy 61.658866 -245.946527) (xy 61.615244 -245.979178) (xy 61.567418 -246.005289) (xy 61.516364 -246.024327)
			(xy 61.463119 -246.035905) (xy 61.408769 -246.039788) (xy 61.354419 -246.035896) (xy 61.301177 -246.024309)
			(xy 61.250125 -246.005263) (xy 61.202304 -245.979144) (xy 61.180218 -245.963186) (xy 61.161206 -245.94959)
			(xy 61.119323 -245.928858) (xy 61.074355 -245.916132) (xy 61.027818 -245.911842) (xy 60.981281 -245.916132)
			(xy 60.936313 -245.928858) (xy 60.89443 -245.94959) (xy 60.875418 -245.963186) (xy 60.85335 -245.979177)
			(xy 60.805522 -246.005304) (xy 60.754462 -246.024357) (xy 60.701211 -246.035949) (xy 60.646851 -246.039845)
			(xy 60.592491 -246.035964) (xy 60.539236 -246.024386) (xy 60.488172 -246.005346) (xy 60.440337 -245.979233)
			(xy 60.396705 -245.946577) (xy 60.358165 -245.908044) (xy 60.325502 -245.864418) (xy 60.299381 -245.816587)
			(xy 60.280332 -245.765526) (xy 60.268745 -245.712273) (xy 60.264855 -245.657913) (xy 59.903995 -245.657913)
			(xy 59.900106 -245.712265) (xy 59.888521 -245.765509) (xy 59.869476 -245.816563) (xy 59.843359 -245.864387)
			(xy 59.810701 -245.908007) (xy 59.772168 -245.946535) (xy 59.728544 -245.979186) (xy 59.680717 -246.005297)
			(xy 59.62966 -246.024335) (xy 59.576414 -246.035913) (xy 59.522062 -246.039795) (xy 59.467711 -246.035902)
			(xy 59.414467 -246.024314) (xy 59.363414 -246.005266) (xy 59.315592 -245.979145) (xy 59.293506 -245.963186)
			(xy 59.274494 -245.94959) (xy 59.232611 -245.928858) (xy 59.187643 -245.916132) (xy 59.141106 -245.911842)
			(xy 59.094569 -245.916132) (xy 59.049601 -245.928858) (xy 59.007718 -245.94959) (xy 58.988706 -245.963186)
			(xy 58.966638 -245.979176) (xy 58.918811 -246.005301) (xy 58.867753 -246.024352) (xy 58.814502 -246.035943)
			(xy 58.760145 -246.039838) (xy 58.705786 -246.035956) (xy 58.652533 -246.024378) (xy 58.60147 -246.005338)
			(xy 58.553637 -245.979224) (xy 58.510007 -245.946569) (xy 58.471469 -245.908037) (xy 58.438807 -245.864412)
			(xy 58.412686 -245.816582) (xy 58.393639 -245.765522) (xy 58.382052 -245.712271) (xy 58.378162 -245.657913)
			(xy 47.294292 -245.657913) (xy 47.294292 -245.712234) (xy 47.29379 -245.744195) (xy 47.285779 -245.807613)
			(xy 47.269882 -245.869527) (xy 47.24635 -245.92896) (xy 47.215556 -245.984975) (xy 47.177983 -246.03669)
			(xy 47.134226 -246.083287) (xy 47.084973 -246.124032) (xy 47.031002 -246.158283) (xy 46.973163 -246.1855)
			(xy 46.91237 -246.205253) (xy 46.84958 -246.217231) (xy 46.785784 -246.221245) (xy 46.721988 -246.217231)
			(xy 46.659198 -246.205253) (xy 46.598405 -246.1855) (xy 46.540566 -246.158283) (xy 46.486595 -246.124032)
			(xy 46.437342 -246.083287) (xy 46.393585 -246.03669) (xy 46.356012 -245.984975) (xy 46.325218 -245.92896)
			(xy 46.301686 -245.869527) (xy 46.285789 -245.807613) (xy 46.277778 -245.744195) (xy 46.277276 -245.712234)
			(xy 46.277276 -245.254526) (xy 46.276774 -245.231618) (xy 46.268582 -245.186541) (xy 46.252441 -245.143663)
			(xy 46.228873 -245.104374) (xy 46.198643 -245.069947) (xy 46.16273 -245.041498) (xy 46.122299 -245.019949)
			(xy 46.078659 -245.005998) (xy 46.033225 -245.000098) (xy 46.010322 -245.00078) (xy 45.985684 -245.001288)
			(xy 45.00118 -245.001288) (xy 44.984455 -245.001766) (xy 44.95214 -245.010406) (xy 44.923178 -245.02714)
			(xy 44.91101 -245.038626) (xy 44.882816 -245.067074) (xy 44.860083 -245.089076) (xy 44.809891 -245.127589)
			(xy 44.755102 -245.159222) (xy 44.696652 -245.183433) (xy 44.635543 -245.199807) (xy 44.572819 -245.208065)
			(xy 44.509553 -245.208065) (xy 44.446829 -245.199807) (xy 44.38572 -245.183433) (xy 44.32727 -245.159222)
			(xy 44.272481 -245.127589) (xy 44.222289 -245.089076) (xy 44.177554 -245.044341) (xy 44.139041 -244.994149)
			(xy 44.107408 -244.93936) (xy 44.083197 -244.88091) (xy 44.066823 -244.819801) (xy 44.058565 -244.757077)
			(xy 28.942538 -244.757077) (xy 28.942538 -247.044093) (xy 44.001669 -247.044093) (xy 44.001669 -246.980827)
			(xy 44.009927 -246.918103) (xy 44.026301 -246.856994) (xy 44.050512 -246.798544) (xy 44.082145 -246.743755)
			(xy 44.120658 -246.693563) (xy 44.165393 -246.648828) (xy 44.215585 -246.610315) (xy 44.270374 -246.578682)
			(xy 44.328824 -246.554471) (xy 44.389933 -246.538097) (xy 44.452657 -246.529839) (xy 44.515923 -246.529839)
			(xy 44.578647 -246.538097) (xy 44.639756 -246.554471) (xy 44.698206 -246.578682) (xy 44.752995 -246.610315)
			(xy 44.803187 -246.648828) (xy 44.82592 -246.67083) (xy 44.954698 -246.799608) (xy 46.072806 -246.799608)
			(xy 46.1011 -246.800041) (xy 46.157299 -246.806655) (xy 46.21234 -246.819791) (xy 46.26547 -246.839269)
			(xy 46.315959 -246.864823) (xy 46.33976 -246.880126) (xy 46.37151 -246.901208) (xy 46.42866 -246.901208)
			(xy 46.42866 -246.956326) (xy 46.448542 -246.978633) (xy 46.483189 -247.027319) (xy 46.511564 -247.079908)
			(xy 46.533234 -247.135597) (xy 46.547866 -247.193534) (xy 46.555238 -247.252834) (xy 46.555237 -247.31259)
			(xy 46.552699 -247.332995) (xy 58.378186 -247.332995) (xy 58.382075 -247.27864) (xy 58.393659 -247.225392)
			(xy 58.412705 -247.174335) (xy 58.438823 -247.126508) (xy 58.471481 -247.082885) (xy 58.510016 -247.044354)
			(xy 58.553643 -247.0117) (xy 58.601472 -246.985588) (xy 58.652532 -246.966548) (xy 58.705781 -246.954969)
			(xy 58.760136 -246.951086) (xy 58.814491 -246.954979) (xy 58.867738 -246.966568) (xy 58.918793 -246.985618)
			(xy 58.966618 -247.01174) (xy 58.988706 -247.0277) (xy 59.007718 -247.041296) (xy 59.049601 -247.062028)
			(xy 59.094569 -247.074754) (xy 59.141106 -247.079044) (xy 59.187643 -247.074754) (xy 59.232611 -247.062028)
			(xy 59.274494 -247.041296) (xy 59.293506 -247.0277) (xy 59.315587 -247.01173) (xy 59.363412 -246.985609)
			(xy 59.414468 -246.966561) (xy 59.467716 -246.954973) (xy 59.522071 -246.951081) (xy 59.576426 -246.954964)
			(xy 59.629675 -246.966544) (xy 59.680734 -246.985585) (xy 59.728564 -247.011698) (xy 59.77219 -247.044353)
			(xy 59.810725 -247.082884) (xy 59.843384 -247.126507) (xy 59.869501 -247.174334) (xy 59.888546 -247.225392)
			(xy 59.900131 -247.27864) (xy 59.904019 -247.332995) (xy 60.264879 -247.332995) (xy 60.268768 -247.278639)
			(xy 60.280353 -247.225389) (xy 60.299399 -247.17433) (xy 60.325518 -247.126502) (xy 60.358178 -247.082878)
			(xy 60.396714 -247.044347) (xy 60.440343 -247.011692) (xy 60.488174 -246.985579) (xy 60.539235 -246.966539)
			(xy 60.592486 -246.954961) (xy 60.646843 -246.951079) (xy 60.701199 -246.954973) (xy 60.754448 -246.966564)
			(xy 60.805504 -246.985615) (xy 60.85333 -247.011739) (xy 60.875418 -247.0277) (xy 60.89443 -247.041296)
			(xy 60.936313 -247.062028) (xy 60.981281 -247.074754) (xy 61.027818 -247.079044) (xy 61.074355 -247.074754)
			(xy 61.119323 -247.062028) (xy 61.161206 -247.041296) (xy 61.180218 -247.0277) (xy 61.202298 -247.011731)
			(xy 61.250123 -246.985612) (xy 61.301178 -246.966565) (xy 61.354424 -246.954979) (xy 61.408777 -246.951088)
			(xy 61.463131 -246.954972) (xy 61.516379 -246.966553) (xy 61.567436 -246.985593) (xy 61.615264 -247.011706)
			(xy 61.658888 -247.044361) (xy 61.697421 -247.082891) (xy 61.730079 -247.126513) (xy 61.756195 -247.174339)
			(xy 61.77524 -247.225395) (xy 61.786824 -247.278642) (xy 61.790712 -247.332995) (xy 62.506014 -247.332995)
			(xy 62.509902 -247.278647) (xy 62.521485 -247.225405) (xy 62.540527 -247.174353) (xy 62.566641 -247.126531)
			(xy 62.599294 -247.082912) (xy 62.637824 -247.044385) (xy 62.681444 -247.011733) (xy 62.729267 -246.985621)
			(xy 62.780319 -246.96658) (xy 62.833561 -246.955) (xy 62.88791 -246.951114) (xy 62.942259 -246.955002)
			(xy 62.9955 -246.966586) (xy 63.046552 -246.985629) (xy 63.094373 -247.011743) (xy 63.11646 -247.0277)
			(xy 63.135472 -247.041296) (xy 63.177355 -247.062028) (xy 63.222323 -247.074754) (xy 63.26886 -247.079044)
			(xy 63.315397 -247.074754) (xy 63.360365 -247.062028) (xy 63.402248 -247.041296) (xy 63.42126 -247.0277)
			(xy 63.443342 -247.011726) (xy 63.49117 -246.985598) (xy 63.542231 -246.966543) (xy 63.595484 -246.954949)
			(xy 63.649844 -246.951053) (xy 63.704206 -246.954934) (xy 63.757462 -246.966512) (xy 63.808529 -246.985552)
			(xy 63.856365 -247.011666) (xy 63.899997 -247.044323) (xy 63.938538 -247.082857) (xy 63.971202 -247.126484)
			(xy 63.997323 -247.174317) (xy 64.016371 -247.22538) (xy 64.027958 -247.278634) (xy 64.031847 -247.332995)
			(xy 64.409864 -247.332995) (xy 64.413752 -247.278635) (xy 64.425339 -247.225382) (xy 64.444386 -247.17432)
			(xy 64.470508 -247.126489) (xy 64.503171 -247.082863) (xy 64.54171 -247.04433) (xy 64.585342 -247.011674)
			(xy 64.633177 -246.98556) (xy 64.684242 -246.966521) (xy 64.737497 -246.954944) (xy 64.791858 -246.951064)
			(xy 64.846217 -246.95496) (xy 64.899469 -246.966554) (xy 64.950528 -246.985608) (xy 64.998355 -247.011736)
			(xy 65.020444 -247.0277) (xy 65.039456 -247.041296) (xy 65.081339 -247.062028) (xy 65.126307 -247.074754)
			(xy 65.172844 -247.079044) (xy 65.219381 -247.074754) (xy 65.264349 -247.062028) (xy 65.306232 -247.041296)
			(xy 65.325244 -247.0277) (xy 65.347324 -247.011733) (xy 65.395147 -246.985618) (xy 65.446199 -246.966575)
			(xy 65.499442 -246.954992) (xy 65.553792 -246.951103) (xy 65.608142 -246.95499) (xy 65.661386 -246.966571)
			(xy 65.712439 -246.985612) (xy 65.760263 -247.011725) (xy 65.803884 -247.044378) (xy 65.842414 -247.082906)
			(xy 65.875069 -247.126526) (xy 65.901183 -247.174349) (xy 65.920226 -247.225402) (xy 65.931809 -247.278645)
			(xy 65.935697 -247.332995) (xy 65.93181 -247.387345) (xy 65.920228 -247.440589) (xy 65.901187 -247.491642)
			(xy 65.875074 -247.539466) (xy 65.84242 -247.583086) (xy 65.803891 -247.621616) (xy 65.760271 -247.65427)
			(xy 65.712448 -247.680384) (xy 65.661395 -247.699426) (xy 65.608152 -247.711009) (xy 65.553802 -247.714897)
			(xy 65.499452 -247.71101) (xy 65.446208 -247.699427) (xy 65.395155 -247.680386) (xy 65.347332 -247.654272)
			(xy 65.325244 -247.638316) (xy 65.306232 -247.62472) (xy 65.264349 -247.603988) (xy 65.219381 -247.591262)
			(xy 65.172844 -247.586972) (xy 65.126307 -247.591262) (xy 65.081339 -247.603988) (xy 65.039456 -247.62472)
			(xy 65.020444 -247.638316) (xy 64.998347 -247.654269) (xy 64.950519 -247.680396) (xy 64.89946 -247.699449)
			(xy 64.846208 -247.711041) (xy 64.791848 -247.714936) (xy 64.737488 -247.711055) (xy 64.684233 -247.699476)
			(xy 64.633169 -247.680436) (xy 64.585334 -247.654321) (xy 64.541703 -247.621664) (xy 64.503164 -247.58313)
			(xy 64.470502 -247.539503) (xy 64.444382 -247.491671) (xy 64.425336 -247.440609) (xy 64.413751 -247.387355)
			(xy 64.409864 -247.332995) (xy 64.031847 -247.332995) (xy 64.027959 -247.387357) (xy 64.016374 -247.440611)
			(xy 63.997327 -247.491675) (xy 63.971207 -247.539508) (xy 63.938544 -247.583136) (xy 63.900005 -247.621671)
			(xy 63.856373 -247.654329) (xy 63.808537 -247.680444) (xy 63.757472 -247.699486) (xy 63.704216 -247.711065)
			(xy 63.649854 -247.714947) (xy 63.595493 -247.711052) (xy 63.54224 -247.69946) (xy 63.491179 -247.680406)
			(xy 63.44335 -247.654279) (xy 63.42126 -247.638316) (xy 63.402248 -247.62472) (xy 63.360365 -247.603988)
			(xy 63.315397 -247.591262) (xy 63.26886 -247.586972) (xy 63.222323 -247.591262) (xy 63.177355 -247.603988)
			(xy 63.135472 -247.62472) (xy 63.11646 -247.638316) (xy 63.094365 -247.654262) (xy 63.046543 -247.680375)
			(xy 62.995491 -247.699417) (xy 62.942249 -247.710999) (xy 62.8879 -247.714886) (xy 62.833552 -247.710999)
			(xy 62.78031 -247.699417) (xy 62.729258 -247.680375) (xy 62.681436 -247.654262) (xy 62.637816 -247.621609)
			(xy 62.599288 -247.58308) (xy 62.566635 -247.539461) (xy 62.540523 -247.491638) (xy 62.521482 -247.440586)
			(xy 62.5099 -247.387344) (xy 62.506014 -247.332995) (xy 61.790712 -247.332995) (xy 61.786825 -247.387349)
			(xy 61.775242 -247.440596) (xy 61.756199 -247.491652) (xy 61.730084 -247.539479) (xy 61.697428 -247.583102)
			(xy 61.658896 -247.621633) (xy 61.615272 -247.654288) (xy 61.567445 -247.680403) (xy 61.516388 -247.699445)
			(xy 61.46314 -247.711026) (xy 61.408787 -247.714912) (xy 61.354434 -247.711023) (xy 61.301187 -247.699437)
			(xy 61.250132 -247.680392) (xy 61.202306 -247.654274) (xy 61.180218 -247.638316) (xy 61.161206 -247.62472)
			(xy 61.119323 -247.603988) (xy 61.074355 -247.591262) (xy 61.027818 -247.586972) (xy 60.981281 -247.591262)
			(xy 60.936313 -247.603988) (xy 60.89443 -247.62472) (xy 60.875418 -247.638316) (xy 60.853322 -247.654267)
			(xy 60.805496 -247.680389) (xy 60.754438 -247.699439) (xy 60.70119 -247.711028) (xy 60.646833 -247.714921)
			(xy 60.592477 -247.711038) (xy 60.539226 -247.699458) (xy 60.488165 -247.680417) (xy 60.440334 -247.654303)
			(xy 60.396707 -247.621647) (xy 60.358172 -247.583115) (xy 60.325513 -247.53949) (xy 60.299395 -247.491661)
			(xy 60.28035 -247.440602) (xy 60.268766 -247.387352) (xy 60.264879 -247.332995) (xy 59.904019 -247.332995)
			(xy 59.900132 -247.38735) (xy 59.888549 -247.440599) (xy 59.869505 -247.491657) (xy 59.843389 -247.539485)
			(xy 59.810731 -247.583109) (xy 59.772197 -247.621641) (xy 59.728572 -247.654297) (xy 59.680743 -247.680411)
			(xy 59.629684 -247.699453) (xy 59.576435 -247.711034) (xy 59.52208 -247.714919) (xy 59.467725 -247.711029)
			(xy 59.414478 -247.699442) (xy 59.363421 -247.680395) (xy 59.315595 -247.654275) (xy 59.293506 -247.638316)
			(xy 59.274494 -247.62472) (xy 59.232611 -247.603988) (xy 59.187643 -247.591262) (xy 59.141106 -247.586972)
			(xy 59.094569 -247.591262) (xy 59.049601 -247.603988) (xy 59.007718 -247.62472) (xy 58.988706 -247.638316)
			(xy 58.96661 -247.654266) (xy 58.918785 -247.680386) (xy 58.867729 -247.699434) (xy 58.814481 -247.711022)
			(xy 58.760127 -247.714914) (xy 58.705772 -247.71103) (xy 58.652523 -247.699449) (xy 58.601464 -247.680408)
			(xy 58.553635 -247.654294) (xy 58.510009 -247.621639) (xy 58.471475 -247.583107) (xy 58.438817 -247.539484)
			(xy 58.412701 -247.491656) (xy 58.393657 -247.440598) (xy 58.382073 -247.38735) (xy 58.378186 -247.332995)
			(xy 46.552699 -247.332995) (xy 46.547862 -247.371889) (xy 46.533227 -247.429825) (xy 46.511554 -247.485513)
			(xy 46.483177 -247.538101) (xy 46.448527 -247.586785) (xy 46.42866 -247.609106) (xy 46.42866 -247.664224)
			(xy 46.37151 -247.664224) (xy 46.33976 -247.685306) (xy 46.315954 -247.700603) (xy 46.26547 -247.72617)
			(xy 46.212342 -247.745659) (xy 46.157301 -247.758802) (xy 46.1011 -247.765419) (xy 46.072806 -247.765824)
			(xy 44.554394 -247.765824) (xy 44.14266 -247.35409) (xy 44.120658 -247.331357) (xy 44.082145 -247.281165)
			(xy 44.050512 -247.226376) (xy 44.026301 -247.167926) (xy 44.009927 -247.106817) (xy 44.001669 -247.044093)
			(xy 28.942538 -247.044093) (xy 28.942538 -249.023007) (xy 43.972967 -249.023007) (xy 43.972967 -248.959741)
			(xy 43.981225 -248.897017) (xy 43.997599 -248.835908) (xy 44.02181 -248.777458) (xy 44.053443 -248.722669)
			(xy 44.091956 -248.672477) (xy 44.113958 -248.649744) (xy 44.541694 -248.222008) (xy 46.096428 -248.222008)
			(xy 46.124696 -248.222437) (xy 46.180839 -248.22909) (xy 46.235823 -248.242242) (xy 46.2889 -248.261715)
			(xy 46.339345 -248.287243) (xy 46.363128 -248.302526) (xy 46.395132 -248.323608) (xy 46.557946 -248.323608)
			(xy 46.591728 -248.298208) (xy 46.618202 -248.27901) (xy 46.675137 -248.246839) (xy 46.735728 -248.222234)
			(xy 46.798974 -248.205601) (xy 46.86383 -248.197216) (xy 46.929226 -248.197216) (xy 46.994082 -248.205601)
			(xy 47.057328 -248.222234) (xy 47.117919 -248.246839) (xy 47.174854 -248.27901) (xy 47.201328 -248.298208)
			(xy 47.23511 -248.323608) (xy 47.252636 -248.323608) (xy 47.252636 -248.342404) (xy 47.276312 -248.366362)
			(xy 47.317749 -248.419464) (xy 47.35181 -248.477574) (xy 47.377899 -248.539673) (xy 47.395557 -248.604674)
			(xy 47.404477 -248.671438) (xy 47.405036 -248.705116) (xy 47.405036 -249.344212) (xy 58.334784 -249.344212)
			(xy 58.33867 -249.289859) (xy 58.350252 -249.236611) (xy 58.369294 -249.185554) (xy 58.395408 -249.137727)
			(xy 58.428063 -249.094103) (xy 58.466594 -249.055571) (xy 58.510217 -249.022914) (xy 58.558044 -248.996799)
			(xy 58.6091 -248.977755) (xy 58.662347 -248.966172) (xy 58.7167 -248.962284) (xy 58.771053 -248.966172)
			(xy 58.8243 -248.977755) (xy 58.875357 -248.996799) (xy 58.923183 -249.022914) (xy 58.945272 -249.038872)
			(xy 58.964284 -249.052468) (xy 59.006167 -249.0732) (xy 59.051135 -249.085926) (xy 59.097672 -249.090216)
			(xy 59.144209 -249.085926) (xy 59.189177 -249.0732) (xy 59.23106 -249.052468) (xy 59.250072 -249.038872)
			(xy 59.27218 -249.022937) (xy 59.320006 -248.996814) (xy 59.371063 -248.977764) (xy 59.424312 -248.966175)
			(xy 59.478668 -248.962283) (xy 59.533025 -248.966166) (xy 59.586276 -248.977746) (xy 59.637336 -248.996788)
			(xy 59.685167 -249.022902) (xy 59.728794 -249.055558) (xy 59.767329 -249.094091) (xy 59.799987 -249.137717)
			(xy 59.826104 -249.185546) (xy 59.845148 -249.236605) (xy 59.856731 -249.289855) (xy 59.860617 -249.344212)
			(xy 60.221477 -249.344212) (xy 60.225363 -249.289857) (xy 60.236945 -249.236608) (xy 60.255988 -249.18555)
			(xy 60.282103 -249.137721) (xy 60.31476 -249.094096) (xy 60.353292 -249.055563) (xy 60.396917 -249.022906)
			(xy 60.444745 -248.99679) (xy 60.495803 -248.977747) (xy 60.549052 -248.966164) (xy 60.603407 -248.962277)
			(xy 60.657762 -248.966166) (xy 60.71101 -248.977751) (xy 60.762068 -248.996796) (xy 60.809895 -249.022913)
			(xy 60.831984 -249.038872) (xy 60.850996 -249.052468) (xy 60.892879 -249.0732) (xy 60.937847 -249.085926)
			(xy 60.984384 -249.090216) (xy 61.030921 -249.085926) (xy 61.075889 -249.0732) (xy 61.117772 -249.052468)
			(xy 61.136784 -249.038872) (xy 61.158891 -249.022938) (xy 61.206717 -248.996817) (xy 61.257773 -248.977769)
			(xy 61.31102 -248.966181) (xy 61.365375 -248.96229) (xy 61.41973 -248.966174) (xy 61.472979 -248.977755)
			(xy 61.524038 -248.996796) (xy 61.571866 -249.02291) (xy 61.615492 -249.055566) (xy 61.654025 -249.094098)
			(xy 61.686682 -249.137723) (xy 61.712798 -249.185551) (xy 61.731842 -249.236609) (xy 61.743424 -249.289857)
			(xy 61.74731 -249.344212) (xy 62.462452 -249.344212) (xy 62.466338 -249.289851) (xy 62.477922 -249.236597)
			(xy 62.496968 -249.185533) (xy 62.523087 -249.1377) (xy 62.555748 -249.094072) (xy 62.594286 -249.055535)
			(xy 62.637916 -249.022877) (xy 62.68575 -248.99676) (xy 62.736815 -248.977717) (xy 62.79007 -248.966136)
			(xy 62.844431 -248.962252) (xy 62.898791 -248.966145) (xy 62.952044 -248.977734) (xy 63.003106 -248.996785)
			(xy 63.050936 -249.02291) (xy 63.073026 -249.038872) (xy 63.092038 -249.052468) (xy 63.133921 -249.0732)
			(xy 63.178889 -249.085926) (xy 63.225426 -249.090216) (xy 63.271963 -249.085926) (xy 63.316931 -249.0732)
			(xy 63.358814 -249.052468) (xy 63.377826 -249.038872) (xy 63.399932 -249.022941) (xy 63.447755 -248.996827)
			(xy 63.498807 -248.977785) (xy 63.55205 -248.966202) (xy 63.606399 -248.962315) (xy 63.660748 -248.966202)
			(xy 63.713991 -248.977784) (xy 63.765043 -248.996826) (xy 63.812866 -249.02294) (xy 63.856485 -249.055594)
			(xy 63.895013 -249.094123) (xy 63.927666 -249.137743) (xy 63.953778 -249.185567) (xy 63.972819 -249.23662)
			(xy 63.984399 -249.289863) (xy 63.988285 -249.344212) (xy 64.366461 -249.344212) (xy 64.370348 -249.289853)
			(xy 64.381931 -249.236601) (xy 64.400975 -249.18554) (xy 64.427093 -249.137708) (xy 64.459752 -249.094081)
			(xy 64.498288 -249.055546) (xy 64.541916 -249.022888) (xy 64.589748 -248.996771) (xy 64.64081 -248.977728)
			(xy 64.694063 -248.966146) (xy 64.748422 -248.962261) (xy 64.80278 -248.966153) (xy 64.856031 -248.977741)
			(xy 64.907091 -248.996789) (xy 64.95492 -249.022911) (xy 64.97701 -249.038872) (xy 64.996022 -249.052468)
			(xy 65.037905 -249.0732) (xy 65.082873 -249.085926) (xy 65.12941 -249.090216) (xy 65.175947 -249.085926)
			(xy 65.220915 -249.0732) (xy 65.262798 -249.052468) (xy 65.28181 -249.038872) (xy 65.303917 -249.02294)
			(xy 65.35174 -248.996823) (xy 65.402794 -248.977779) (xy 65.456038 -248.966194) (xy 65.51039 -248.962305)
			(xy 65.564741 -248.966191) (xy 65.617986 -248.977773) (xy 65.669041 -248.996815) (xy 65.716866 -249.022929)
			(xy 65.760488 -249.055583) (xy 65.799018 -249.094114) (xy 65.831672 -249.137735) (xy 65.857786 -249.185561)
			(xy 65.876827 -249.236615) (xy 65.888409 -249.289861) (xy 65.892295 -249.344212) (xy 65.888405 -249.398563)
			(xy 65.876821 -249.451808) (xy 65.857776 -249.502861) (xy 65.831659 -249.550685) (xy 65.799002 -249.594304)
			(xy 65.760469 -249.632832) (xy 65.716846 -249.665484) (xy 65.669019 -249.691595) (xy 65.617963 -249.710634)
			(xy 65.564717 -249.722212) (xy 65.510366 -249.726095) (xy 65.456015 -249.722202) (xy 65.402771 -249.710614)
			(xy 65.351718 -249.691567) (xy 65.303896 -249.665447) (xy 65.28181 -249.649488) (xy 65.262798 -249.635892)
			(xy 65.220915 -249.61516) (xy 65.175947 -249.602434) (xy 65.12941 -249.598144) (xy 65.082873 -249.602434)
			(xy 65.037905 -249.61516) (xy 64.996022 -249.635892) (xy 64.97701 -249.649488) (xy 64.95494 -249.665476)
			(xy 64.907113 -249.691601) (xy 64.856054 -249.710653) (xy 64.802804 -249.722244) (xy 64.748446 -249.726139)
			(xy 64.694087 -249.722257) (xy 64.640833 -249.710678) (xy 64.58977 -249.691639) (xy 64.541937 -249.665525)
			(xy 64.498306 -249.63287) (xy 64.459768 -249.594337) (xy 64.427106 -249.550712) (xy 64.400985 -249.502882)
			(xy 64.381938 -249.451822) (xy 64.370351 -249.39857) (xy 64.366461 -249.344212) (xy 63.988285 -249.344212)
			(xy 63.984396 -249.398561) (xy 63.972812 -249.451803) (xy 63.953768 -249.502855) (xy 63.927653 -249.550677)
			(xy 63.894998 -249.594295) (xy 63.856467 -249.632822) (xy 63.812845 -249.665473) (xy 63.765021 -249.691584)
			(xy 63.713967 -249.710622) (xy 63.660724 -249.722201) (xy 63.606375 -249.726085) (xy 63.552026 -249.722194)
			(xy 63.498784 -249.710608) (xy 63.447733 -249.691563) (xy 63.399912 -249.665446) (xy 63.377826 -249.649488)
			(xy 63.358814 -249.635892) (xy 63.316931 -249.61516) (xy 63.271963 -249.602434) (xy 63.225426 -249.598144)
			(xy 63.178889 -249.602434) (xy 63.133921 -249.61516) (xy 63.092038 -249.635892) (xy 63.073026 -249.649488)
			(xy 63.050956 -249.665477) (xy 63.003127 -249.691605) (xy 62.952067 -249.710659) (xy 62.898815 -249.722252)
			(xy 62.844455 -249.726148) (xy 62.790094 -249.722268) (xy 62.736838 -249.71069) (xy 62.685772 -249.69165)
			(xy 62.637936 -249.665536) (xy 62.594304 -249.63288) (xy 62.555763 -249.594347) (xy 62.5231 -249.55072)
			(xy 62.496978 -249.502889) (xy 62.477929 -249.451826) (xy 62.466342 -249.398573) (xy 62.462452 -249.344212)
			(xy 61.74731 -249.344212) (xy 61.743421 -249.398567) (xy 61.731835 -249.451815) (xy 61.712788 -249.502871)
			(xy 61.686669 -249.550698) (xy 61.654009 -249.59432) (xy 61.615474 -249.63285) (xy 61.571846 -249.665502)
			(xy 61.524016 -249.691614) (xy 61.472956 -249.710652) (xy 61.419706 -249.722229) (xy 61.365351 -249.72611)
			(xy 61.310997 -249.722215) (xy 61.25775 -249.710624) (xy 61.206695 -249.691573) (xy 61.158871 -249.665449)
			(xy 61.136784 -249.649488) (xy 61.117772 -249.635892) (xy 61.075889 -249.61516) (xy 61.030921 -249.602434)
			(xy 60.984384 -249.598144) (xy 60.937847 -249.602434) (xy 60.892879 -249.61516) (xy 60.850996 -249.635892)
			(xy 60.831984 -249.649488) (xy 60.809915 -249.665474) (xy 60.762089 -249.691594) (xy 60.711033 -249.710643)
			(xy 60.657786 -249.722231) (xy 60.603431 -249.726123) (xy 60.549076 -249.72224) (xy 60.495826 -249.71066)
			(xy 60.444767 -249.69162) (xy 60.396937 -249.665507) (xy 60.353311 -249.632853) (xy 60.314775 -249.594322)
			(xy 60.282116 -249.550699) (xy 60.255998 -249.502872) (xy 60.236952 -249.451815) (xy 60.225366 -249.398567)
			(xy 60.221477 -249.344212) (xy 59.860617 -249.344212) (xy 59.856728 -249.398568) (xy 59.845141 -249.451818)
			(xy 59.826094 -249.502876) (xy 59.799974 -249.550704) (xy 59.767313 -249.594327) (xy 59.728775 -249.632857)
			(xy 59.685146 -249.665511) (xy 59.637314 -249.691622) (xy 59.586252 -249.71066) (xy 59.533001 -249.722237)
			(xy 59.478644 -249.726117) (xy 59.424288 -249.722221) (xy 59.37104 -249.710629) (xy 59.319984 -249.691576)
			(xy 59.272159 -249.66545) (xy 59.250072 -249.649488) (xy 59.23106 -249.635892) (xy 59.189177 -249.61516)
			(xy 59.144209 -249.602434) (xy 59.097672 -249.598144) (xy 59.051135 -249.602434) (xy 59.006167 -249.61516)
			(xy 58.964284 -249.635892) (xy 58.945272 -249.649488) (xy 58.923203 -249.665473) (xy 58.875378 -249.691591)
			(xy 58.824323 -249.710638) (xy 58.771077 -249.722225) (xy 58.716724 -249.726116) (xy 58.662371 -249.722232)
			(xy 58.609123 -249.710652) (xy 58.558065 -249.691611) (xy 58.510237 -249.665499) (xy 58.466612 -249.632845)
			(xy 58.428079 -249.594315) (xy 58.395421 -249.550693) (xy 58.369304 -249.502867) (xy 58.350259 -249.451812)
			(xy 58.338673 -249.398565) (xy 58.334784 -249.344212) (xy 47.405036 -249.344212) (xy 47.405036 -249.789442)
			(xy 47.404534 -249.821403) (xy 47.396523 -249.884821) (xy 47.380626 -249.946735) (xy 47.357094 -250.006168)
			(xy 47.3263 -250.062183) (xy 47.288727 -250.113898) (xy 47.24497 -250.160495) (xy 47.195717 -250.20124)
			(xy 47.141746 -250.235491) (xy 47.083907 -250.262708) (xy 47.023114 -250.282461) (xy 46.960324 -250.294439)
			(xy 46.896528 -250.298453) (xy 46.832732 -250.294439) (xy 46.769942 -250.282461) (xy 46.709149 -250.262708)
			(xy 46.65131 -250.235491) (xy 46.597339 -250.20124) (xy 46.548086 -250.160495) (xy 46.504329 -250.113898)
			(xy 46.466756 -250.062183) (xy 46.435962 -250.006168) (xy 46.41243 -249.946735) (xy 46.396533 -249.884821)
			(xy 46.388522 -249.821403) (xy 46.38802 -249.789442) (xy 46.38802 -249.441208) (xy 46.387593 -249.418296)
			(xy 46.379396 -249.373212) (xy 46.363247 -249.330328) (xy 46.339671 -249.291035) (xy 46.309431 -249.256607)
			(xy 46.273508 -249.228158) (xy 46.233066 -249.206612) (xy 46.189416 -249.192667) (xy 46.143973 -249.186775)
			(xy 46.121066 -249.187462) (xy 46.096428 -249.188224) (xy 44.941998 -249.188224) (xy 44.797218 -249.333004)
			(xy 44.774485 -249.355006) (xy 44.724293 -249.393519) (xy 44.669504 -249.425152) (xy 44.611054 -249.449363)
			(xy 44.549945 -249.465737) (xy 44.487221 -249.473995) (xy 44.423955 -249.473995) (xy 44.361231 -249.465737)
			(xy 44.300122 -249.449363) (xy 44.241672 -249.425152) (xy 44.186883 -249.393519) (xy 44.136691 -249.355006)
			(xy 44.091956 -249.310271) (xy 44.053443 -249.260079) (xy 44.02181 -249.20529) (xy 43.997599 -249.14684)
			(xy 43.981225 -249.085731) (xy 43.972967 -249.023007) (xy 28.942538 -249.023007) (xy 28.942538 -251.480965)
			(xy 44.155847 -251.480965) (xy 44.155847 -251.417699) (xy 44.164105 -251.354975) (xy 44.180479 -251.293866)
			(xy 44.20469 -251.235416) (xy 44.236323 -251.180627) (xy 44.274836 -251.130435) (xy 44.319571 -251.0857)
			(xy 44.369763 -251.047187) (xy 44.424552 -251.015554) (xy 44.483002 -250.991343) (xy 44.544111 -250.974969)
			(xy 44.606835 -250.966711) (xy 44.670101 -250.966711) (xy 44.732825 -250.974969) (xy 44.793934 -250.991343)
			(xy 44.852384 -251.015554) (xy 44.907173 -251.047187) (xy 44.957365 -251.0857) (xy 44.980098 -251.107702)
			(xy 45.09262 -251.220224) (xy 46.036738 -251.220224) (xy 46.065032 -251.220639) (xy 46.121232 -251.227257)
			(xy 46.152406 -251.234699) (xy 58.334802 -251.234699) (xy 58.338689 -251.180348) (xy 58.350272 -251.127104)
			(xy 58.369315 -251.07605) (xy 58.39543 -251.028226) (xy 58.428085 -250.984605) (xy 58.466616 -250.946076)
			(xy 58.510238 -250.913422) (xy 58.558063 -250.887309) (xy 58.609118 -250.868268) (xy 58.662362 -250.856687)
			(xy 58.716713 -250.852802) (xy 58.771064 -250.856691) (xy 58.824308 -250.868276) (xy 58.875361 -250.88732)
			(xy 58.923185 -250.913436) (xy 58.945272 -250.929394) (xy 58.964284 -250.94299) (xy 59.006167 -250.963722)
			(xy 59.051135 -250.976448) (xy 59.097672 -250.980738) (xy 59.144209 -250.976448) (xy 59.189177 -250.963722)
			(xy 59.23106 -250.94299) (xy 59.250072 -250.929394) (xy 59.272159 -250.913429) (xy 59.319987 -250.887304)
			(xy 59.371045 -250.868251) (xy 59.424296 -250.85666) (xy 59.478655 -250.852765) (xy 59.533014 -250.856647)
			(xy 59.586268 -250.868226) (xy 59.637331 -250.887266) (xy 59.685165 -250.91338) (xy 59.728795 -250.946036)
			(xy 59.767333 -250.98457) (xy 59.799995 -251.028196) (xy 59.826115 -251.076027) (xy 59.845161 -251.127088)
			(xy 59.856747 -251.18034) (xy 59.860635 -251.234699) (xy 60.221495 -251.234699) (xy 60.225382 -251.180346)
			(xy 60.236966 -251.1271) (xy 60.256009 -251.076045) (xy 60.282125 -251.02822) (xy 60.314782 -250.984598)
			(xy 60.353314 -250.946068) (xy 60.396938 -250.913414) (xy 60.444764 -250.8873) (xy 60.495821 -250.86826)
			(xy 60.549067 -250.856679) (xy 60.60342 -250.852795) (xy 60.657772 -250.856685) (xy 60.711018 -250.868271)
			(xy 60.762072 -250.887317) (xy 60.809896 -250.913435) (xy 60.831984 -250.929394) (xy 60.850996 -250.94299)
			(xy 60.892879 -250.963722) (xy 60.937847 -250.976448) (xy 60.984384 -250.980738) (xy 61.030921 -250.976448)
			(xy 61.075889 -250.963722) (xy 61.117772 -250.94299) (xy 61.136784 -250.929394) (xy 61.158871 -250.91343)
			(xy 61.206697 -250.887306) (xy 61.257755 -250.868256) (xy 61.311005 -250.856666) (xy 61.365362 -250.852772)
			(xy 61.419719 -250.856655) (xy 61.472971 -250.868234) (xy 61.524033 -250.887275) (xy 61.571865 -250.913389)
			(xy 61.615493 -250.946044) (xy 61.65403 -250.984577) (xy 61.68669 -251.028202) (xy 61.712809 -251.076031)
			(xy 61.731855 -251.127091) (xy 61.74344 -251.180341) (xy 61.747328 -251.234699) (xy 62.462469 -251.234699)
			(xy 62.466358 -251.180341) (xy 62.477943 -251.127089) (xy 62.496989 -251.076029) (xy 62.523109 -251.028199)
			(xy 62.55577 -250.984573) (xy 62.594307 -250.94604) (xy 62.637937 -250.913384) (xy 62.68577 -250.88727)
			(xy 62.736833 -250.86823) (xy 62.790085 -250.856651) (xy 62.844444 -250.852769) (xy 62.898802 -250.856664)
			(xy 62.952052 -250.868255) (xy 63.00311 -250.887307) (xy 63.050937 -250.913432) (xy 63.073026 -250.929394)
			(xy 63.092038 -250.94299) (xy 63.133921 -250.963722) (xy 63.178889 -250.976448) (xy 63.225426 -250.980738)
			(xy 63.271963 -250.976448) (xy 63.316931 -250.963722) (xy 63.358814 -250.94299) (xy 63.377826 -250.929394)
			(xy 63.399912 -250.913434) (xy 63.447736 -250.887317) (xy 63.498789 -250.868272) (xy 63.552034 -250.856687)
			(xy 63.606386 -250.852797) (xy 63.660737 -250.856683) (xy 63.713983 -250.868264) (xy 63.765038 -250.887305)
			(xy 63.812864 -250.913418) (xy 63.856487 -250.946072) (xy 63.895018 -250.984602) (xy 63.927674 -251.028223)
			(xy 63.953789 -251.076048) (xy 63.972832 -251.127102) (xy 63.984415 -251.180347) (xy 63.988303 -251.234699)
			(xy 64.366479 -251.234699) (xy 64.370367 -251.180343) (xy 64.381952 -251.127093) (xy 64.400997 -251.076035)
			(xy 64.427115 -251.028207) (xy 64.459774 -250.984582) (xy 64.49831 -250.946051) (xy 64.541937 -250.913395)
			(xy 64.589768 -250.887282) (xy 64.640828 -250.868241) (xy 64.694079 -250.856662) (xy 64.748435 -250.852779)
			(xy 64.802791 -250.856672) (xy 64.856039 -250.868261) (xy 64.907096 -250.887311) (xy 64.954922 -250.913433)
			(xy 64.97701 -250.929394) (xy 64.996022 -250.94299) (xy 65.037905 -250.963722) (xy 65.082873 -250.976448)
			(xy 65.12941 -250.980738) (xy 65.175947 -250.976448) (xy 65.220915 -250.963722) (xy 65.262798 -250.94299)
			(xy 65.28181 -250.929394) (xy 65.303896 -250.913432) (xy 65.351721 -250.887313) (xy 65.402776 -250.868266)
			(xy 65.456023 -250.856679) (xy 65.510376 -250.852788) (xy 65.56473 -250.856672) (xy 65.617978 -250.868253)
			(xy 65.669036 -250.887293) (xy 65.716864 -250.913407) (xy 65.760489 -250.946061) (xy 65.799022 -250.984592)
			(xy 65.83168 -251.028215) (xy 65.857796 -251.076041) (xy 65.876841 -251.127098) (xy 65.888424 -251.180345)
			(xy 65.892312 -251.234699) (xy 65.888425 -251.289053) (xy 65.876841 -251.3423) (xy 65.857797 -251.393356)
			(xy 65.831681 -251.441183) (xy 65.799024 -251.484806) (xy 65.760491 -251.523337) (xy 65.716866 -251.555992)
			(xy 65.669038 -251.582106) (xy 65.617981 -251.601147) (xy 65.564733 -251.612728) (xy 65.510379 -251.616612)
			(xy 65.456025 -251.612722) (xy 65.402779 -251.601135) (xy 65.351723 -251.582088) (xy 65.303898 -251.555969)
			(xy 65.28181 -251.54001) (xy 65.262798 -251.526414) (xy 65.220915 -251.505682) (xy 65.175947 -251.492956)
			(xy 65.12941 -251.488666) (xy 65.082873 -251.492956) (xy 65.037905 -251.505682) (xy 64.996022 -251.526414)
			(xy 64.97701 -251.54001) (xy 64.95492 -251.555968) (xy 64.907094 -251.58209) (xy 64.856037 -251.60114)
			(xy 64.802788 -251.612728) (xy 64.748433 -251.616621) (xy 64.694076 -251.612738) (xy 64.640826 -251.601158)
			(xy 64.589766 -251.582117) (xy 64.541935 -251.556003) (xy 64.498308 -251.523348) (xy 64.459773 -251.484816)
			(xy 64.427114 -251.441191) (xy 64.400996 -251.393363) (xy 64.381951 -251.342304) (xy 64.370367 -251.289055)
			(xy 64.366479 -251.234699) (xy 63.988303 -251.234699) (xy 63.984415 -251.28905) (xy 63.972832 -251.342296)
			(xy 63.95379 -251.39335) (xy 63.927675 -251.441175) (xy 63.89502 -251.484797) (xy 63.856488 -251.523327)
			(xy 63.812866 -251.555981) (xy 63.76504 -251.582094) (xy 63.713985 -251.601136) (xy 63.66074 -251.612717)
			(xy 63.606388 -251.616603) (xy 63.552036 -251.612713) (xy 63.498792 -251.601129) (xy 63.447738 -251.582084)
			(xy 63.399914 -251.555968) (xy 63.377826 -251.54001) (xy 63.358814 -251.526414) (xy 63.316931 -251.505682)
			(xy 63.271963 -251.492956) (xy 63.225426 -251.488666) (xy 63.178889 -251.492956) (xy 63.133921 -251.505682)
			(xy 63.092038 -251.526414) (xy 63.073026 -251.54001) (xy 63.050935 -251.555969) (xy 63.003108 -251.582094)
			(xy 62.95205 -251.601146) (xy 62.898799 -251.612737) (xy 62.844442 -251.616631) (xy 62.790083 -251.612748)
			(xy 62.73683 -251.601169) (xy 62.685768 -251.582129) (xy 62.637935 -251.556014) (xy 62.594305 -251.523358)
			(xy 62.555768 -251.484825) (xy 62.523107 -251.441199) (xy 62.496988 -251.393369) (xy 62.477942 -251.342309)
			(xy 62.466357 -251.289057) (xy 62.462469 -251.234699) (xy 61.747328 -251.234699) (xy 61.74344 -251.289056)
			(xy 61.731855 -251.342307) (xy 61.71281 -251.393367) (xy 61.686691 -251.441196) (xy 61.654031 -251.484821)
			(xy 61.615495 -251.523354) (xy 61.571867 -251.55601) (xy 61.524035 -251.582124) (xy 61.472973 -251.601165)
			(xy 61.419722 -251.612745) (xy 61.365364 -251.616628) (xy 61.311007 -251.612735) (xy 61.257758 -251.601145)
			(xy 61.2067 -251.582095) (xy 61.158873 -251.555971) (xy 61.136784 -251.54001) (xy 61.117772 -251.526414)
			(xy 61.075889 -251.505682) (xy 61.030921 -251.492956) (xy 60.984384 -251.488666) (xy 60.937847 -251.492956)
			(xy 60.892879 -251.505682) (xy 60.850996 -251.526414) (xy 60.831984 -251.54001) (xy 60.809894 -251.555966)
			(xy 60.76207 -251.582084) (xy 60.711015 -251.60113) (xy 60.65777 -251.612715) (xy 60.603418 -251.616605)
			(xy 60.549065 -251.61272) (xy 60.495819 -251.60114) (xy 60.444762 -251.582099) (xy 60.396936 -251.555985)
			(xy 60.353312 -251.523331) (xy 60.31478 -251.4848) (xy 60.282124 -251.441178) (xy 60.256008 -251.393353)
			(xy 60.236965 -251.342297) (xy 60.225382 -251.289051) (xy 60.221495 -251.234699) (xy 59.860635 -251.234699)
			(xy 59.856747 -251.289058) (xy 59.845162 -251.34231) (xy 59.826116 -251.393371) (xy 59.799996 -251.441202)
			(xy 59.767335 -251.484828) (xy 59.728797 -251.523362) (xy 59.685167 -251.556019) (xy 59.637333 -251.582133)
			(xy 59.58627 -251.601174) (xy 59.533017 -251.612753) (xy 59.478657 -251.616635) (xy 59.424299 -251.612741)
			(xy 59.371048 -251.60115) (xy 59.319989 -251.582097) (xy 59.272161 -251.555972) (xy 59.250072 -251.54001)
			(xy 59.23106 -251.526414) (xy 59.189177 -251.505682) (xy 59.144209 -251.492956) (xy 59.097672 -251.488666)
			(xy 59.051135 -251.492956) (xy 59.006167 -251.505682) (xy 58.964284 -251.526414) (xy 58.945272 -251.54001)
			(xy 58.923183 -251.555965) (xy 58.875359 -251.582081) (xy 58.824306 -251.601125) (xy 58.771062 -251.612709)
			(xy 58.716711 -251.616598) (xy 58.66236 -251.612712) (xy 58.609115 -251.601131) (xy 58.558061 -251.58209)
			(xy 58.510236 -251.555977) (xy 58.466614 -251.523323) (xy 58.428083 -251.484793) (xy 58.395429 -251.441172)
			(xy 58.369314 -251.393348) (xy 58.350272 -251.342294) (xy 58.338689 -251.28905) (xy 58.334802 -251.234699)
			(xy 46.152406 -251.234699) (xy 46.176274 -251.240397) (xy 46.229403 -251.259879) (xy 46.279891 -251.285437)
			(xy 46.303692 -251.300742) (xy 46.335442 -251.321824) (xy 46.392592 -251.321824) (xy 46.392592 -251.376942)
			(xy 46.412488 -251.399236) (xy 46.447133 -251.447925) (xy 46.475506 -251.500516) (xy 46.497173 -251.556207)
			(xy 46.511803 -251.614145) (xy 46.519173 -251.673445) (xy 46.51917 -251.733202) (xy 46.511795 -251.792502)
			(xy 46.497159 -251.850438) (xy 46.475486 -251.906127) (xy 46.447108 -251.958715) (xy 46.412459 -252.007401)
			(xy 46.392592 -252.029722) (xy 46.392592 -252.08484) (xy 46.335442 -252.08484) (xy 46.303692 -252.105922)
			(xy 46.279905 -252.12125) (xy 46.229415 -252.146811) (xy 46.176283 -252.166293) (xy 46.121238 -252.179429)
			(xy 46.065034 -252.186039) (xy 46.036738 -252.18644) (xy 44.692316 -252.18644) (xy 44.296838 -251.790962)
			(xy 44.274836 -251.768229) (xy 44.236323 -251.718037) (xy 44.20469 -251.663248) (xy 44.180479 -251.604798)
			(xy 44.164105 -251.543689) (xy 44.155847 -251.480965) (xy 28.942538 -251.480965) (xy 28.942538 -253.40564)
			(xy 44.081192 -253.40564) (xy 44.081192 -253.399544) (xy 44.08164 -253.367918) (xy 44.089852 -253.305201)
			(xy 44.106182 -253.244094) (xy 44.13035 -253.185641) (xy 44.161941 -253.130844) (xy 44.200416 -253.08064)
			(xy 44.222416 -253.057914) (xy 44.637706 -252.642624) (xy 46.025562 -252.642624) (xy 46.05383 -252.643034)
			(xy 46.109974 -252.649691) (xy 46.164959 -252.662847) (xy 46.218035 -252.682324) (xy 46.268479 -252.707856)
			(xy 46.292262 -252.723142) (xy 46.324266 -252.744224) (xy 46.48708 -252.744224) (xy 46.520862 -252.718824)
			(xy 46.547336 -252.699626) (xy 46.604271 -252.667455) (xy 46.664862 -252.64285) (xy 46.728108 -252.626217)
			(xy 46.792964 -252.617832) (xy 46.85836 -252.617832) (xy 46.923216 -252.626217) (xy 46.986462 -252.64285)
			(xy 47.047053 -252.667455) (xy 47.103988 -252.699626) (xy 47.130462 -252.718824) (xy 47.164244 -252.744224)
			(xy 47.18177 -252.744224) (xy 47.18177 -252.76302) (xy 47.205403 -252.787006) (xy 47.246797 -252.840118)
			(xy 47.280816 -252.89823) (xy 47.306864 -252.960325) (xy 47.324486 -253.025315) (xy 47.333372 -253.092063)
			(xy 47.333916 -253.125732) (xy 47.333916 -253.275772) (xy 58.334837 -253.275772) (xy 58.338728 -253.221427)
			(xy 58.350314 -253.168188) (xy 58.369358 -253.11714) (xy 58.395474 -253.069322) (xy 58.428129 -253.025708)
			(xy 58.466659 -252.987185) (xy 58.510279 -252.954537) (xy 58.558102 -252.92843) (xy 58.609153 -252.909395)
			(xy 58.662393 -252.897818) (xy 58.71674 -252.893937) (xy 58.771085 -252.89783) (xy 58.824323 -252.909417)
			(xy 58.875371 -252.928463) (xy 58.923188 -252.95458) (xy 58.945272 -252.970538) (xy 58.964284 -252.984134)
			(xy 59.006167 -253.004866) (xy 59.051135 -253.017592) (xy 59.097672 -253.021882) (xy 59.144209 -253.017592)
			(xy 59.189177 -253.004866) (xy 59.23106 -252.984134) (xy 59.250072 -252.970538) (xy 59.272118 -252.954514)
			(xy 59.319948 -252.928382) (xy 59.37101 -252.909325) (xy 59.424265 -252.897729) (xy 59.478628 -252.89383)
			(xy 59.532993 -252.897708) (xy 59.586252 -252.909284) (xy 59.637322 -252.928323) (xy 59.685162 -252.954436)
			(xy 59.728798 -252.987092) (xy 59.767343 -253.025627) (xy 59.80001 -253.069255) (xy 59.826136 -253.117088)
			(xy 59.845188 -253.168152) (xy 59.856778 -253.221409) (xy 59.86067 -253.275772) (xy 60.22153 -253.275772)
			(xy 60.225421 -253.221425) (xy 60.237007 -253.168185) (xy 60.256052 -253.117136) (xy 60.282169 -253.069316)
			(xy 60.314826 -253.025701) (xy 60.353357 -252.987177) (xy 60.396979 -252.954529) (xy 60.444803 -252.928422)
			(xy 60.495856 -252.909386) (xy 60.549099 -252.89781) (xy 60.603447 -252.89393) (xy 60.657794 -252.897824)
			(xy 60.711033 -252.909412) (xy 60.762082 -252.92846) (xy 60.8099 -252.954579) (xy 60.831984 -252.970538)
			(xy 60.850996 -252.984134) (xy 60.892879 -253.004866) (xy 60.937847 -253.017592) (xy 60.984384 -253.021882)
			(xy 61.030921 -253.017592) (xy 61.075889 -253.004866) (xy 61.117772 -252.984134) (xy 61.136784 -252.970538)
			(xy 61.158829 -252.954515) (xy 61.206659 -252.928385) (xy 61.25772 -252.909329) (xy 61.310974 -252.897735)
			(xy 61.365335 -252.893837) (xy 61.419698 -252.897716) (xy 61.472956 -252.909293) (xy 61.524023 -252.928332)
			(xy 61.571862 -252.954445) (xy 61.615496 -252.9871) (xy 61.654039 -253.025634) (xy 61.686705 -253.069261)
			(xy 61.71283 -253.117093) (xy 61.731881 -253.168156) (xy 61.743471 -253.22141) (xy 61.747363 -253.275772)
			(xy 62.462505 -253.275772) (xy 62.466396 -253.221419) (xy 62.477984 -253.168174) (xy 62.497032 -253.117119)
			(xy 62.523153 -253.069295) (xy 62.555814 -253.025676) (xy 62.59435 -252.987149) (xy 62.637978 -252.9545)
			(xy 62.685808 -252.928391) (xy 62.736868 -252.909357) (xy 62.790117 -252.897782) (xy 62.84447 -252.893905)
			(xy 62.898823 -252.897802) (xy 62.952067 -252.909396) (xy 63.00312 -252.92845) (xy 63.050941 -252.954576)
			(xy 63.073026 -252.970538) (xy 63.092038 -252.984134) (xy 63.133921 -253.004866) (xy 63.178889 -253.017592)
			(xy 63.225426 -253.021882) (xy 63.271963 -253.017592) (xy 63.316931 -253.004866) (xy 63.358814 -252.984134)
			(xy 63.377826 -252.970538) (xy 63.39987 -252.954518) (xy 63.447697 -252.928396) (xy 63.498754 -252.909346)
			(xy 63.552003 -252.897756) (xy 63.606359 -252.893862) (xy 63.660716 -252.897744) (xy 63.713967 -252.909323)
			(xy 63.765029 -252.928362) (xy 63.812861 -252.954474) (xy 63.85649 -252.987128) (xy 63.895027 -253.025659)
			(xy 63.927689 -253.069282) (xy 63.95381 -253.117109) (xy 63.972858 -253.168167) (xy 63.984446 -253.221416)
			(xy 63.988338 -253.275772) (xy 64.366514 -253.275772) (xy 64.370406 -253.221422) (xy 64.381993 -253.168178)
			(xy 64.40104 -253.117125) (xy 64.427159 -253.069303) (xy 64.459818 -253.025686) (xy 64.498353 -252.98716)
			(xy 64.541978 -252.954511) (xy 64.589806 -252.928403) (xy 64.640863 -252.909368) (xy 64.69411 -252.897793)
			(xy 64.748461 -252.893914) (xy 64.802812 -252.897811) (xy 64.856054 -252.909402) (xy 64.907105 -252.928454)
			(xy 64.954925 -252.954577) (xy 64.97701 -252.970538) (xy 64.996022 -252.984134) (xy 65.037905 -253.004866)
			(xy 65.082873 -253.017592) (xy 65.12941 -253.021882) (xy 65.175947 -253.017592) (xy 65.220915 -253.004866)
			(xy 65.262798 -252.984134) (xy 65.28181 -252.970538) (xy 65.303855 -252.954517) (xy 65.351682 -252.928392)
			(xy 65.402741 -252.909339) (xy 65.455992 -252.897748) (xy 65.51035 -252.893853) (xy 65.564709 -252.897734)
			(xy 65.617963 -252.909311) (xy 65.669027 -252.92835) (xy 65.716861 -252.954463) (xy 65.760492 -252.987117)
			(xy 65.799032 -253.025649) (xy 65.831695 -253.069274) (xy 65.857818 -253.117103) (xy 65.876867 -253.168163)
			(xy 65.888455 -253.221414) (xy 65.892347 -253.275772) (xy 65.888463 -253.330131) (xy 65.876882 -253.383384)
			(xy 65.85784 -253.434447) (xy 65.831725 -253.48228) (xy 65.799068 -253.525909) (xy 65.760534 -253.564446)
			(xy 65.716908 -253.597107) (xy 65.669077 -253.623227) (xy 65.618016 -253.642273) (xy 65.564764 -253.653859)
			(xy 65.510405 -253.657747) (xy 65.456046 -253.65386) (xy 65.402794 -253.642276) (xy 65.351733 -253.623231)
			(xy 65.303901 -253.597113) (xy 65.28181 -253.581154) (xy 65.262798 -253.567558) (xy 65.220915 -253.546826)
			(xy 65.175947 -253.5341) (xy 65.12941 -253.52981) (xy 65.082873 -253.5341) (xy 65.037905 -253.546826)
			(xy 64.996022 -253.567558) (xy 64.97701 -253.581154) (xy 64.954878 -253.597053) (xy 64.907055 -253.623169)
			(xy 64.856001 -253.642213) (xy 64.802757 -253.653797) (xy 64.748406 -253.657686) (xy 64.694055 -253.653799)
			(xy 64.64081 -253.642217) (xy 64.589756 -253.623174) (xy 64.541932 -253.597059) (xy 64.498311 -253.564404)
			(xy 64.459782 -253.525873) (xy 64.427129 -253.48225) (xy 64.401017 -253.434424) (xy 64.381977 -253.383369)
			(xy 64.370398 -253.330124) (xy 64.366514 -253.275772) (xy 63.988338 -253.275772) (xy 63.984454 -253.330129)
			(xy 63.972874 -253.38338) (xy 63.953833 -253.434441) (xy 63.927719 -253.482272) (xy 63.895063 -253.5259)
			(xy 63.856531 -253.564436) (xy 63.812907 -253.597096) (xy 63.765079 -253.623215) (xy 63.71402 -253.642262)
			(xy 63.660771 -253.653848) (xy 63.606414 -253.657738) (xy 63.552058 -253.653852) (xy 63.498807 -253.64227)
			(xy 63.447747 -253.623227) (xy 63.399917 -253.597112) (xy 63.377826 -253.581154) (xy 63.358814 -253.567558)
			(xy 63.316931 -253.546826) (xy 63.271963 -253.5341) (xy 63.225426 -253.52981) (xy 63.178889 -253.5341)
			(xy 63.133921 -253.546826) (xy 63.092038 -253.567558) (xy 63.073026 -253.581154) (xy 63.050894 -253.597054)
			(xy 63.00307 -253.623173) (xy 62.952014 -253.642219) (xy 62.898768 -253.653805) (xy 62.844415 -253.657695)
			(xy 62.790062 -253.65381) (xy 62.736815 -253.642228) (xy 62.685758 -253.623186) (xy 62.637932 -253.597071)
			(xy 62.594309 -253.564414) (xy 62.555777 -253.525882) (xy 62.523123 -253.482258) (xy 62.497009 -253.434431)
			(xy 62.477969 -253.383373) (xy 62.466388 -253.330126) (xy 62.462505 -253.275772) (xy 61.747363 -253.275772)
			(xy 61.743479 -253.330135) (xy 61.731897 -253.383391) (xy 61.712853 -253.434457) (xy 61.686735 -253.482293)
			(xy 61.654075 -253.525924) (xy 61.615538 -253.564464) (xy 61.571908 -253.597126) (xy 61.524074 -253.623245)
			(xy 61.473009 -253.642292) (xy 61.419753 -253.653876) (xy 61.36539 -253.657763) (xy 61.311028 -253.653873)
			(xy 61.257773 -253.642286) (xy 61.206709 -253.623238) (xy 61.158876 -253.597115) (xy 61.136784 -253.581154)
			(xy 61.117772 -253.567558) (xy 61.075889 -253.546826) (xy 61.030921 -253.5341) (xy 60.984384 -253.52981)
			(xy 60.937847 -253.5341) (xy 60.892879 -253.546826) (xy 60.850996 -253.567558) (xy 60.831984 -253.581154)
			(xy 60.809853 -253.597051) (xy 60.762031 -253.623163) (xy 60.71098 -253.642203) (xy 60.657739 -253.653784)
			(xy 60.603391 -253.65767) (xy 60.549044 -253.653782) (xy 60.495803 -253.642198) (xy 60.444753 -253.623156)
			(xy 60.396932 -253.597041) (xy 60.353315 -253.564387) (xy 60.314789 -253.525857) (xy 60.282139 -253.482237)
			(xy 60.256029 -253.434414) (xy 60.236992 -253.383362) (xy 60.225413 -253.33012) (xy 60.22153 -253.275772)
			(xy 59.86067 -253.275772) (xy 59.856786 -253.330137) (xy 59.845203 -253.383395) (xy 59.826159 -253.434462)
			(xy 59.80004 -253.482299) (xy 59.767379 -253.525931) (xy 59.72884 -253.564471) (xy 59.685208 -253.597134)
			(xy 59.637372 -253.623254) (xy 59.586305 -253.6423) (xy 59.533048 -253.653884) (xy 59.478684 -253.65777)
			(xy 59.42432 -253.653879) (xy 59.371063 -253.642291) (xy 59.319998 -253.62324) (xy 59.272164 -253.597116)
			(xy 59.250072 -253.581154) (xy 59.23106 -253.567558) (xy 59.189177 -253.546826) (xy 59.144209 -253.5341)
			(xy 59.097672 -253.52981) (xy 59.051135 -253.5341) (xy 59.006167 -253.546826) (xy 58.964284 -253.567558)
			(xy 58.945272 -253.581154) (xy 58.923141 -253.59705) (xy 58.875321 -253.62316) (xy 58.82427 -253.642199)
			(xy 58.771031 -253.653778) (xy 58.716685 -253.657663) (xy 58.662339 -253.653774) (xy 58.6091 -253.64219)
			(xy 58.558051 -253.623147) (xy 58.510233 -253.597033) (xy 58.466617 -253.564379) (xy 58.428093 -253.52585)
			(xy 58.395444 -253.482231) (xy 58.369335 -253.434409) (xy 58.350298 -253.383359) (xy 58.33872 -253.330119)
			(xy 58.334837 -253.275772) (xy 47.333916 -253.275772) (xy 47.333916 -254.395224) (xy 47.333415 -254.427169)
			(xy 47.325407 -254.490555) (xy 47.309518 -254.552438) (xy 47.285999 -254.611842) (xy 47.255219 -254.667829)
			(xy 47.217666 -254.719518) (xy 47.17393 -254.766092) (xy 47.124702 -254.806817) (xy 47.070757 -254.841051)
			(xy 47.012948 -254.868254) (xy 46.952185 -254.887997) (xy 46.889426 -254.899969) (xy 46.825662 -254.903981)
			(xy 46.761898 -254.899969) (xy 46.699139 -254.887997) (xy 46.638376 -254.868254) (xy 46.580567 -254.841051)
			(xy 46.526622 -254.806817) (xy 46.477394 -254.766092) (xy 46.433658 -254.719518) (xy 46.396105 -254.667829)
			(xy 46.365325 -254.611842) (xy 46.341806 -254.552438) (xy 46.325917 -254.490555) (xy 46.317909 -254.427169)
			(xy 46.317408 -254.395224) (xy 46.317408 -253.861824) (xy 46.316991 -253.838897) (xy 46.308785 -253.793782)
			(xy 46.292618 -253.750873) (xy 46.269013 -253.711561) (xy 46.238738 -253.677122) (xy 46.202775 -253.648674)
			(xy 46.162291 -253.627141) (xy 46.118601 -253.613222) (xy 46.073121 -253.607367) (xy 46.0502 -253.608078)
			(xy 46.025562 -253.60884) (xy 45.03801 -253.60884) (xy 44.948348 -253.698248) (xy 44.943776 -253.70409)
			(xy 44.923888 -253.728482) (xy 44.878894 -253.772486) (xy 44.828565 -253.810271) (xy 44.773754 -253.841198)
			(xy 44.715389 -253.864743) (xy 44.654461 -253.880506) (xy 44.592 -253.88822) (xy 44.529068 -253.887755)
			(xy 44.466728 -253.879118) (xy 44.406039 -253.862456) (xy 44.348029 -253.838051) (xy 44.293681 -253.806317)
			(xy 44.243916 -253.767792) (xy 44.199577 -253.723128) (xy 44.161417 -253.673083) (xy 44.130081 -253.618504)
			(xy 44.106101 -253.560317) (xy 44.089883 -253.499508) (xy 44.081702 -253.437107) (xy 44.081192 -253.40564)
			(xy 28.942538 -253.40564) (xy 28.942538 -255.185717) (xy 58.334778 -255.185717) (xy 58.338663 -255.131362)
			(xy 58.350244 -255.078114) (xy 58.369286 -255.027056) (xy 58.3954 -254.979228) (xy 58.428055 -254.935603)
			(xy 58.466586 -254.897069) (xy 58.51021 -254.864412) (xy 58.558037 -254.838295) (xy 58.609093 -254.81925)
			(xy 58.662341 -254.807666) (xy 58.716695 -254.803778) (xy 58.77105 -254.807665) (xy 58.824298 -254.819248)
			(xy 58.875355 -254.838291) (xy 58.923182 -254.864406) (xy 58.945272 -254.880364) (xy 58.964284 -254.89396)
			(xy 59.006167 -254.914692) (xy 59.051135 -254.927418) (xy 59.097672 -254.931708) (xy 59.144209 -254.927418)
			(xy 59.189177 -254.914692) (xy 59.23106 -254.89396) (xy 59.250072 -254.880364) (xy 59.272187 -254.864439)
			(xy 59.320013 -254.838318) (xy 59.37107 -254.819269) (xy 59.424318 -254.807681) (xy 59.478673 -254.803789)
			(xy 59.533029 -254.807673) (xy 59.586278 -254.819254) (xy 59.637338 -254.838295) (xy 59.685167 -254.86441)
			(xy 59.728793 -254.897066) (xy 59.767327 -254.935599) (xy 59.799984 -254.979224) (xy 59.8261 -255.027053)
			(xy 59.845143 -255.078112) (xy 59.856725 -255.131361) (xy 59.860611 -255.185717) (xy 60.221471 -255.185717)
			(xy 60.225356 -255.131361) (xy 60.236938 -255.078111) (xy 60.25598 -255.027051) (xy 60.282095 -254.979222)
			(xy 60.314752 -254.935596) (xy 60.353285 -254.897061) (xy 60.396909 -254.864403) (xy 60.444738 -254.838286)
			(xy 60.495797 -254.819242) (xy 60.549046 -254.807658) (xy 60.603402 -254.803771) (xy 60.657758 -254.807659)
			(xy 60.711007 -254.819243) (xy 60.762066 -254.838288) (xy 60.809894 -254.864405) (xy 60.831984 -254.880364)
			(xy 60.850996 -254.89396) (xy 60.892879 -254.914692) (xy 60.937847 -254.927418) (xy 60.984384 -254.931708)
			(xy 61.030921 -254.927418) (xy 61.075889 -254.914692) (xy 61.117772 -254.89396) (xy 61.136784 -254.880364)
			(xy 61.158899 -254.86444) (xy 61.206724 -254.838321) (xy 61.257779 -254.819274) (xy 61.311026 -254.807687)
			(xy 61.36538 -254.803796) (xy 61.419734 -254.807681) (xy 61.472982 -254.819262) (xy 61.524039 -254.838304)
			(xy 61.571867 -254.864418) (xy 61.615491 -254.897074) (xy 61.654024 -254.935606) (xy 61.68668 -254.97923)
			(xy 61.712795 -255.027058) (xy 61.731837 -255.078115) (xy 61.743418 -255.131363) (xy 61.747304 -255.185717)
			(xy 62.462445 -255.185717) (xy 62.466331 -255.131355) (xy 62.477915 -255.0781) (xy 62.49696 -255.027035)
			(xy 62.523079 -254.979201) (xy 62.55574 -254.935571) (xy 62.594278 -254.897034) (xy 62.637909 -254.864374)
			(xy 62.685743 -254.838256) (xy 62.736808 -254.819212) (xy 62.790064 -254.80763) (xy 62.844426 -254.803745)
			(xy 62.898787 -254.807637) (xy 62.952041 -254.819227) (xy 63.003104 -254.838278) (xy 63.050935 -254.864402)
			(xy 63.073026 -254.880364) (xy 63.092038 -254.89396) (xy 63.133921 -254.914692) (xy 63.178889 -254.927418)
			(xy 63.225426 -254.931708) (xy 63.271963 -254.927418) (xy 63.316931 -254.914692) (xy 63.358814 -254.89396)
			(xy 63.377826 -254.880364) (xy 63.39994 -254.864444) (xy 63.447762 -254.838331) (xy 63.498813 -254.81929)
			(xy 63.552055 -254.807708) (xy 63.606404 -254.803821) (xy 63.660752 -254.807709) (xy 63.713993 -254.819292)
			(xy 63.765045 -254.838334) (xy 63.812866 -254.864448) (xy 63.856484 -254.897102) (xy 63.895012 -254.935631)
			(xy 63.927663 -254.979251) (xy 63.953774 -255.027074) (xy 63.972814 -255.078126) (xy 63.984394 -255.131368)
			(xy 63.988279 -255.185717) (xy 64.366455 -255.185717) (xy 64.370341 -255.131357) (xy 64.381924 -255.078104)
			(xy 64.400968 -255.027041) (xy 64.427085 -254.979209) (xy 64.459744 -254.93558) (xy 64.49828 -254.897044)
			(xy 64.541909 -254.864385) (xy 64.589741 -254.838267) (xy 64.640804 -254.819223) (xy 64.694057 -254.807641)
			(xy 64.748417 -254.803755) (xy 64.802776 -254.807646) (xy 64.856028 -254.819233) (xy 64.907089 -254.838282)
			(xy 64.95492 -254.864403) (xy 64.97701 -254.880364) (xy 64.996022 -254.89396) (xy 65.037905 -254.914692)
			(xy 65.082873 -254.927418) (xy 65.12941 -254.931708) (xy 65.175947 -254.927418) (xy 65.220915 -254.914692)
			(xy 65.262798 -254.89396) (xy 65.28181 -254.880364) (xy 65.303924 -254.864443) (xy 65.351747 -254.838327)
			(xy 65.4028 -254.819284) (xy 65.456044 -254.8077) (xy 65.510394 -254.803812) (xy 65.564745 -254.807698)
			(xy 65.617989 -254.819281) (xy 65.669043 -254.838323) (xy 65.716866 -254.864437) (xy 65.760487 -254.897091)
			(xy 65.799016 -254.935621) (xy 65.831669 -254.979243) (xy 65.857782 -255.027068) (xy 65.876823 -255.078122)
			(xy 65.888403 -255.131366) (xy 65.892288 -255.185717) (xy 65.888398 -255.240067) (xy 65.876813 -255.29331)
			(xy 65.857768 -255.344363) (xy 65.831651 -255.392185) (xy 65.798994 -255.435804) (xy 65.760462 -255.474331)
			(xy 65.716838 -255.506981) (xy 65.669012 -255.533091) (xy 65.617957 -255.552129) (xy 65.564712 -255.563706)
			(xy 65.510361 -255.567588) (xy 65.456011 -255.563695) (xy 65.402768 -255.552107) (xy 65.351717 -255.533059)
			(xy 65.303896 -255.506939) (xy 65.28181 -255.49098) (xy 65.262798 -255.477384) (xy 65.220915 -255.456652)
			(xy 65.175947 -255.443926) (xy 65.12941 -255.439636) (xy 65.082873 -255.443926) (xy 65.037905 -255.456652)
			(xy 64.996022 -255.477384) (xy 64.97701 -255.49098) (xy 64.954948 -255.506979) (xy 64.90712 -255.533105)
			(xy 64.856061 -255.552158) (xy 64.802809 -255.56375) (xy 64.748451 -255.567645) (xy 64.694091 -255.563764)
			(xy 64.640836 -255.552186) (xy 64.589772 -255.533146) (xy 64.541937 -255.507033) (xy 64.498306 -255.474378)
			(xy 64.459766 -255.435845) (xy 64.427103 -255.392219) (xy 64.400981 -255.344389) (xy 64.381933 -255.293328)
			(xy 64.370346 -255.240076) (xy 64.366455 -255.185717) (xy 63.988279 -255.185717) (xy 63.984389 -255.240065)
			(xy 63.972804 -255.293306) (xy 63.95376 -255.344357) (xy 63.927645 -255.392177) (xy 63.89499 -255.435795)
			(xy 63.856459 -255.47432) (xy 63.812838 -255.50697) (xy 63.765014 -255.53308) (xy 63.713961 -255.552118)
			(xy 63.660718 -255.563696) (xy 63.60637 -255.567579) (xy 63.552022 -255.563687) (xy 63.498781 -255.552101)
			(xy 63.447731 -255.533055) (xy 63.399912 -255.506938) (xy 63.377826 -255.49098) (xy 63.358814 -255.477384)
			(xy 63.316931 -255.456652) (xy 63.271963 -255.443926) (xy 63.225426 -255.439636) (xy 63.178889 -255.443926)
			(xy 63.133921 -255.456652) (xy 63.092038 -255.477384) (xy 63.073026 -255.49098) (xy 63.050963 -255.50698)
			(xy 63.003135 -255.533108) (xy 62.952074 -255.552164) (xy 62.898821 -255.563758) (xy 62.84446 -255.567655)
			(xy 62.790097 -255.563775) (xy 62.736841 -255.552197) (xy 62.685774 -255.533158) (xy 62.637937 -255.507044)
			(xy 62.594303 -255.474388) (xy 62.555762 -255.435854) (xy 62.523097 -255.392227) (xy 62.496974 -255.344396)
			(xy 62.477924 -255.293333) (xy 62.466336 -255.240078) (xy 62.462445 -255.185717) (xy 61.747304 -255.185717)
			(xy 61.743414 -255.240071) (xy 61.731827 -255.293317) (xy 61.712781 -255.344373) (xy 61.686661 -255.392198)
			(xy 61.654001 -255.435819) (xy 61.615466 -255.474348) (xy 61.571839 -255.507) (xy 61.524009 -255.53311)
			(xy 61.472949 -255.552147) (xy 61.419701 -255.563724) (xy 61.365346 -255.567604) (xy 61.310993 -255.563708)
			(xy 61.257747 -255.552117) (xy 61.206693 -255.533065) (xy 61.158871 -255.506941) (xy 61.136784 -255.49098)
			(xy 61.117772 -255.477384) (xy 61.075889 -255.456652) (xy 61.030921 -255.443926) (xy 60.984384 -255.439636)
			(xy 60.937847 -255.443926) (xy 60.892879 -255.456652) (xy 60.850996 -255.477384) (xy 60.831984 -255.49098)
			(xy 60.809922 -255.506976) (xy 60.762096 -255.533098) (xy 60.71104 -255.552147) (xy 60.657791 -255.563737)
			(xy 60.603436 -255.567629) (xy 60.549079 -255.563747) (xy 60.495829 -255.552168) (xy 60.444769 -255.533128)
			(xy 60.396938 -255.507015) (xy 60.35331 -255.474361) (xy 60.314774 -255.43583) (xy 60.282113 -255.392207)
			(xy 60.255994 -255.344379) (xy 60.236947 -255.293321) (xy 60.225361 -255.240073) (xy 60.221471 -255.185717)
			(xy 59.860611 -255.185717) (xy 59.856721 -255.240072) (xy 59.845134 -255.293321) (xy 59.826086 -255.344378)
			(xy 59.799966 -255.392204) (xy 59.767305 -255.435826) (xy 59.728768 -255.474356) (xy 59.685139 -255.507008)
			(xy 59.637307 -255.533119) (xy 59.586246 -255.552156) (xy 59.532995 -255.563732) (xy 59.478639 -255.567611)
			(xy 59.424284 -255.563714) (xy 59.371037 -255.552121) (xy 59.319982 -255.533068) (xy 59.272159 -255.506942)
			(xy 59.250072 -255.49098) (xy 59.23106 -255.477384) (xy 59.189177 -255.456652) (xy 59.144209 -255.443926)
			(xy 59.097672 -255.439636) (xy 59.051135 -255.443926) (xy 59.006167 -255.456652) (xy 58.964284 -255.477384)
			(xy 58.945272 -255.49098) (xy 58.923211 -255.506975) (xy 58.875386 -255.533095) (xy 58.82433 -255.552143)
			(xy 58.771083 -255.56373) (xy 58.716729 -255.567622) (xy 58.662374 -255.563739) (xy 58.609126 -255.552159)
			(xy 58.558067 -255.533119) (xy 58.510238 -255.507007) (xy 58.466612 -255.474353) (xy 58.428077 -255.435823)
			(xy 58.395418 -255.392201) (xy 58.3693 -255.344374) (xy 58.350254 -255.293318) (xy 58.338668 -255.240071)
			(xy 58.334778 -255.185717) (xy 28.942538 -255.185717) (xy 28.942538 -256.249053) (xy 44.144671 -256.249053)
			(xy 44.144671 -256.185787) (xy 44.152929 -256.123063) (xy 44.169303 -256.061954) (xy 44.193514 -256.003504)
			(xy 44.225147 -255.948715) (xy 44.26366 -255.898523) (xy 44.308395 -255.853788) (xy 44.358587 -255.815275)
			(xy 44.413376 -255.783642) (xy 44.471826 -255.759431) (xy 44.532935 -255.743057) (xy 44.595659 -255.734799)
			(xy 44.658925 -255.734799) (xy 44.721649 -255.743057) (xy 44.782758 -255.759431) (xy 44.841208 -255.783642)
			(xy 44.895997 -255.815275) (xy 44.946189 -255.853788) (xy 44.968922 -255.87579) (xy 45.039788 -255.94691)
			(xy 45.051929 -255.958364) (xy 45.080799 -255.975089) (xy 45.113021 -255.983748) (xy 45.129704 -255.984248)
			(xy 45.96511 -255.984248) (xy 45.993398 -255.984627) (xy 46.049594 -255.991179) (xy 46.104636 -256.004264)
			(xy 46.157768 -256.023701) (xy 46.208261 -256.049222) (xy 46.232064 -256.064512) (xy 46.263814 -256.085848)
			(xy 46.320964 -256.085848) (xy 46.320964 -256.140712) (xy 46.340832 -256.163031) (xy 46.375479 -256.211716)
			(xy 46.403855 -256.264303) (xy 46.425525 -256.31999) (xy 46.440158 -256.377926) (xy 46.447531 -256.437224)
			(xy 46.447531 -256.496979) (xy 46.440158 -256.556277) (xy 46.425524 -256.614212) (xy 46.403854 -256.669899)
			(xy 46.375478 -256.722487) (xy 46.34083 -256.771171) (xy 46.320964 -256.793492) (xy 46.320964 -256.848356)
			(xy 46.263814 -256.848356) (xy 46.232064 -256.869692) (xy 46.208261 -256.884979) (xy 46.157757 -256.91047)
			(xy 46.104623 -256.929895) (xy 46.049586 -256.942986) (xy 45.993397 -256.949565) (xy 45.96511 -256.949956)
			(xy 44.676822 -256.949956) (xy 44.285662 -256.55905) (xy 44.26366 -256.536317) (xy 44.225147 -256.486125)
			(xy 44.193514 -256.431336) (xy 44.169303 -256.372886) (xy 44.152929 -256.311777) (xy 44.144671 -256.249053)
			(xy 28.942538 -256.249053) (xy 28.942538 -258.170817) (xy 44.087521 -258.170817) (xy 44.087521 -258.107551)
			(xy 44.095779 -258.044827) (xy 44.112153 -257.983718) (xy 44.136364 -257.925268) (xy 44.167997 -257.870479)
			(xy 44.20651 -257.820287) (xy 44.228512 -257.797554) (xy 44.619672 -257.406648) (xy 45.965872 -257.406648)
			(xy 45.994135 -257.407036) (xy 46.050277 -257.413607) (xy 46.105266 -257.426699) (xy 46.158346 -257.44613)
			(xy 46.208791 -257.471635) (xy 46.232572 -257.486912) (xy 46.264576 -257.507994) (xy 46.42739 -257.507994)
			(xy 46.461172 -257.482594) (xy 46.487646 -257.463396) (xy 46.544581 -257.431225) (xy 46.605172 -257.40662)
			(xy 46.668418 -257.389987) (xy 46.733274 -257.381602) (xy 46.79867 -257.381602) (xy 46.863526 -257.389987)
			(xy 46.926772 -257.40662) (xy 46.987363 -257.431225) (xy 47.044298 -257.463396) (xy 47.070772 -257.482594)
			(xy 47.104554 -257.507994) (xy 47.12208 -257.507994) (xy 47.12208 -257.52679) (xy 47.145757 -257.550746)
			(xy 47.187193 -257.60385) (xy 47.221253 -257.661961) (xy 47.247341 -257.72406) (xy 47.265 -257.789061)
			(xy 47.27392 -257.855824) (xy 47.27448 -257.889502) (xy 47.27448 -258.594352) (xy 47.274992 -258.61752)
			(xy 47.283401 -258.663088) (xy 47.29993 -258.706376) (xy 47.324032 -258.745952) (xy 47.354909 -258.780502)
			(xy 47.391537 -258.808884) (xy 47.432702 -258.830156) (xy 47.477042 -258.843614) (xy 47.523086 -258.848811)
			(xy 47.56931 -258.845576) (xy 47.614182 -258.834016) (xy 47.635414 -258.82473) (xy 47.664867 -258.811555)
			(xy 47.726349 -258.791978) (xy 47.789813 -258.780338) (xy 47.854241 -258.776822) (xy 47.918596 -258.781487)
			(xy 47.981843 -258.794258) (xy 48.042966 -258.814929) (xy 48.100981 -258.843168) (xy 48.154958 -258.878521)
			(xy 48.204027 -258.92042) (xy 48.2474 -258.968191) (xy 48.284379 -259.021066) (xy 48.299583 -259.050028)
			(xy 70.896988 -259.050028) (xy 70.896988 -258.105148) (xy 70.897568 -258.072647) (xy 70.905872 -258.008177)
			(xy 70.922325 -257.945292) (xy 70.946658 -257.885016) (xy 70.978475 -257.828333) (xy 71.017257 -257.776167)
			(xy 71.062371 -257.72937) (xy 71.113082 -257.688704) (xy 71.168562 -257.654832) (xy 71.227906 -257.628308)
			(xy 71.290147 -257.609564) (xy 71.354269 -257.598905) (xy 71.419227 -257.596505) (xy 71.483961 -257.602404)
			(xy 71.547415 -257.616505) (xy 71.608555 -257.638578) (xy 71.666383 -257.668263) (xy 71.719956 -257.705077)
			(xy 71.7684 -257.748418) (xy 71.790052 -257.772662) (xy 71.804661 -257.788881) (xy 71.838417 -257.816549)
			(xy 71.876403 -257.838045) (xy 71.917502 -257.852736) (xy 71.960507 -257.860192) (xy 72.004153 -257.860192)
			(xy 72.047158 -257.852736) (xy 72.088257 -257.838045) (xy 72.126243 -257.816549) (xy 72.159999 -257.788881)
			(xy 72.174608 -257.772662) (xy 72.196685 -257.748028) (xy 72.246049 -257.703999) (xy 72.300709 -257.666747)
			(xy 72.359739 -257.636901) (xy 72.422143 -257.614966) (xy 72.486865 -257.601312) (xy 72.552812 -257.596171)
			(xy 72.618868 -257.599629) (xy 72.683918 -257.611627) (xy 72.74686 -257.631964) (xy 72.806633 -257.660295)
			(xy 72.862225 -257.696141) (xy 72.912696 -257.738896) (xy 72.935338 -257.76301) (xy 72.951549 -257.780038)
			(xy 72.989064 -257.808368) (xy 73.031146 -257.829322) (xy 73.076361 -257.842187) (xy 73.123171 -257.846525)
			(xy 73.169981 -257.842187) (xy 73.215196 -257.829322) (xy 73.257278 -257.808368) (xy 73.294793 -257.780038)
			(xy 73.311004 -257.76301) (xy 73.333494 -257.73896) (xy 73.383725 -257.696382) (xy 73.439031 -257.660643)
			(xy 73.498488 -257.632342) (xy 73.5611 -257.611953) (xy 73.62582 -257.599815) (xy 73.691566 -257.596133)
			(xy 73.757236 -257.600968) (xy 73.821734 -257.614239) (xy 73.883979 -257.635724) (xy 73.94293 -257.665063)
			(xy 73.9976 -257.701767) (xy 74.047076 -257.74522) (xy 74.069194 -257.769614) (xy 74.083776 -257.78555)
			(xy 74.117365 -257.812703) (xy 74.155062 -257.833784) (xy 74.195783 -257.848184) (xy 74.238352 -257.85549)
			(xy 74.281544 -257.85549) (xy 74.324113 -257.848184) (xy 74.364834 -257.833784) (xy 74.402531 -257.812703)
			(xy 74.43612 -257.78555) (xy 74.450702 -257.769614) (xy 74.472533 -257.74568) (xy 74.521135 -257.702852)
			(xy 74.574783 -257.666546) (xy 74.632609 -257.637349) (xy 74.693675 -257.615734) (xy 74.756993 -257.602052)
			(xy 74.821536 -257.596525) (xy 74.886258 -257.599241) (xy 74.95011 -257.610158) (xy 75.012059 -257.629097)
			(xy 75.071099 -257.655753) (xy 75.126275 -257.689693) (xy 75.176693 -257.730367) (xy 75.221534 -257.777116)
			(xy 75.260074 -257.829183) (xy 75.291687 -257.885725) (xy 75.315862 -257.945824) (xy 75.332206 -258.008507)
			(xy 75.340454 -258.072759) (xy 75.340972 -258.105148) (xy 75.340972 -259.050028) (xy 75.340498 -259.082755)
			(xy 75.332099 -259.147669) (xy 75.315443 -259.210969) (xy 75.290806 -259.27161) (xy 75.258594 -259.328589)
			(xy 75.239372 -259.355082) (xy 75.213972 -259.388864) (xy 75.213972 -259.406136) (xy 75.198732 -259.406136)
			(xy 75.162918 -259.436362) (xy 75.137741 -259.457215) (xy 75.083009 -259.492966) (xy 75.024144 -259.521405)
			(xy 74.962119 -259.54206) (xy 74.897957 -259.554591) (xy 74.832718 -259.558791) (xy 74.767479 -259.554591)
			(xy 74.703317 -259.54206) (xy 74.641292 -259.521405) (xy 74.582427 -259.492966) (xy 74.527695 -259.457215)
			(xy 74.502518 -259.436362) (xy 74.466704 -259.406136) (xy 74.451464 -259.406136) (xy 74.451464 -259.388864)
			(xy 74.426064 -259.355082) (xy 74.411371 -259.334954) (xy 74.385545 -259.292332) (xy 74.374502 -259.269992)
			(xy 74.367181 -259.255898) (xy 74.346779 -259.231571) (xy 74.321004 -259.213033) (xy 74.291451 -259.20143)
			(xy 74.259948 -259.197481) (xy 74.228445 -259.20143) (xy 74.198892 -259.213033) (xy 74.173117 -259.231571)
			(xy 74.152715 -259.255898) (xy 74.145394 -259.269992) (xy 74.134361 -259.292337) (xy 74.108535 -259.334961)
			(xy 74.093832 -259.355082) (xy 74.068432 -259.388864) (xy 74.068432 -259.406136) (xy 74.053192 -259.406136)
			(xy 74.017378 -259.436362) (xy 73.992201 -259.457215) (xy 73.937469 -259.492966) (xy 73.878604 -259.521405)
			(xy 73.816579 -259.54206) (xy 73.752417 -259.554591) (xy 73.687178 -259.558791) (xy 73.621939 -259.554591)
			(xy 73.557777 -259.54206) (xy 73.495752 -259.521405) (xy 73.436887 -259.492966) (xy 73.382155 -259.457215)
			(xy 73.356978 -259.436362) (xy 73.321164 -259.406136) (xy 73.305924 -259.406136) (xy 73.305924 -259.388864)
			(xy 73.280524 -259.355082) (xy 73.268088 -259.338191) (xy 73.245706 -259.302715) (xy 73.23582 -259.284216)
			(xy 73.228348 -259.270704) (xy 73.207993 -259.247498) (xy 73.182651 -259.229873) (xy 73.153812 -259.218866)
			(xy 73.123171 -259.215123) (xy 73.09253 -259.218866) (xy 73.063691 -259.229873) (xy 73.038349 -259.247498)
			(xy 73.017994 -259.270704) (xy 73.010522 -259.284216) (xy 73.00065 -259.302723) (xy 72.978268 -259.338201)
			(xy 72.965818 -259.355082) (xy 72.940672 -259.388864) (xy 72.940672 -259.406136) (xy 72.925178 -259.406136)
			(xy 72.889364 -259.436362) (xy 72.864187 -259.457215) (xy 72.809455 -259.492966) (xy 72.75059 -259.521405)
			(xy 72.688565 -259.54206) (xy 72.624403 -259.554591) (xy 72.559164 -259.558791) (xy 72.493925 -259.554591)
			(xy 72.429763 -259.54206) (xy 72.367738 -259.521405) (xy 72.308873 -259.492966) (xy 72.254141 -259.457215)
			(xy 72.228964 -259.436362) (xy 72.19315 -259.406136) (xy 72.177656 -259.406136) (xy 72.177656 -259.388864)
			(xy 72.15251 -259.355082) (xy 72.1367 -259.333409) (xy 72.109208 -259.287341) (xy 72.097646 -259.263134)
			(xy 72.090467 -259.248732) (xy 72.070087 -259.223839) (xy 72.04413 -259.204835) (xy 72.014244 -259.192927)
			(xy 71.98233 -259.188871) (xy 71.950416 -259.192927) (xy 71.92053 -259.204835) (xy 71.894573 -259.223839)
			(xy 71.874193 -259.248732) (xy 71.867014 -259.263134) (xy 71.855464 -259.287347) (xy 71.827971 -259.333417)
			(xy 71.81215 -259.355082) (xy 71.787004 -259.388864) (xy 71.787004 -259.406136) (xy 71.77151 -259.406136)
			(xy 71.735696 -259.436362) (xy 71.710519 -259.457215) (xy 71.655787 -259.492966) (xy 71.596922 -259.521405)
			(xy 71.534897 -259.54206) (xy 71.470735 -259.554591) (xy 71.405496 -259.558791) (xy 71.340257 -259.554591)
			(xy 71.276095 -259.54206) (xy 71.21407 -259.521405) (xy 71.155205 -259.492966) (xy 71.100473 -259.457215)
			(xy 71.075296 -259.436362) (xy 71.039482 -259.406136) (xy 71.023988 -259.406136) (xy 71.023988 -259.388864)
			(xy 70.998842 -259.355082) (xy 70.979582 -259.328607) (xy 70.947321 -259.271636) (xy 70.922638 -259.210996)
			(xy 70.905943 -259.147689) (xy 70.897511 -259.082763) (xy 70.896988 -259.050028) (xy 48.299583 -259.050028)
			(xy 48.314371 -259.078196) (xy 48.336893 -259.138661) (xy 48.351582 -259.20149) (xy 48.358204 -259.265673)
			(xy 48.356651 -259.330178) (xy 48.346948 -259.393968) (xy 48.329251 -259.456017) (xy 48.303845 -259.515328)
			(xy 48.271139 -259.570948) (xy 48.231657 -259.621982) (xy 48.2092 -259.64515) (xy 46.990508 -260.864096)
			(xy 46.311566 -260.864096) (xy 46.278864 -260.863588) (xy 46.214001 -260.855191) (xy 46.150752 -260.83854)
			(xy 46.090162 -260.81391) (xy 46.033233 -260.78171) (xy 46.006766 -260.762496) (xy 45.972984 -260.737096)
			(xy 45.81017 -260.737096) (xy 45.778166 -260.758178) (xy 45.75439 -260.773476) (xy 45.703953 -260.799028)
			(xy 45.650876 -260.81851) (xy 45.595886 -260.831655) (xy 45.539736 -260.838283) (xy 45.511466 -260.838696)
			(xy 44.738036 -260.838696) (xy 44.336208 -260.436868) (xy 44.314206 -260.414135) (xy 44.275693 -260.363943)
			(xy 44.24406 -260.309154) (xy 44.219849 -260.250704) (xy 44.203475 -260.189595) (xy 44.195217 -260.126871)
			(xy 44.195217 -260.063605) (xy 44.203475 -260.000881) (xy 44.219849 -259.939772) (xy 44.24406 -259.881322)
			(xy 44.275693 -259.826533) (xy 44.314206 -259.776341) (xy 44.358941 -259.731606) (xy 44.409133 -259.693093)
			(xy 44.463922 -259.66146) (xy 44.522372 -259.637249) (xy 44.583481 -259.620875) (xy 44.646205 -259.612617)
			(xy 44.709471 -259.612617) (xy 44.772195 -259.620875) (xy 44.833304 -259.637249) (xy 44.891754 -259.66146)
			(xy 44.946543 -259.693093) (xy 44.996735 -259.731606) (xy 45.019468 -259.753608) (xy 45.13834 -259.87248)
			(xy 45.511466 -259.87248) (xy 45.539733 -259.872928) (xy 45.595876 -259.879574) (xy 45.650861 -259.892722)
			(xy 45.703938 -259.912191) (xy 45.754382 -259.937716) (xy 45.778166 -259.952998) (xy 45.81017 -259.97408)
			(xy 45.972984 -259.97408) (xy 46.006766 -259.94868) (xy 46.03324 -259.929478) (xy 46.090177 -259.897301)
			(xy 46.150766 -259.872681) (xy 46.21401 -259.856025) (xy 46.278866 -259.847606) (xy 46.311566 -259.84708)
			(xy 46.569376 -259.84708) (xy 46.641004 -259.775706) (xy 46.656585 -259.759491) (xy 46.682298 -259.722602)
			(xy 46.701117 -259.681764) (xy 46.712454 -259.63825) (xy 46.715955 -259.593421) (xy 46.711511 -259.548675)
			(xy 46.69926 -259.50541) (xy 46.679585 -259.464976) (xy 46.653101 -259.428637) (xy 46.620634 -259.397527)
			(xy 46.583198 -259.372618) (xy 46.562772 -259.36321) (xy 46.532922 -259.349669) (xy 46.476693 -259.315981)
			(xy 46.425261 -259.275345) (xy 46.379479 -259.228435) (xy 46.340107 -259.176029) (xy 46.307797 -259.118997)
			(xy 46.283087 -259.058285) (xy 46.266385 -258.9949) (xy 46.25797 -258.929894) (xy 46.257464 -258.89712)
			(xy 46.257464 -258.625594) (xy 46.257004 -258.602684) (xy 46.248806 -258.557605) (xy 46.232659 -258.514725)
			(xy 46.209085 -258.475435) (xy 46.17885 -258.441009) (xy 46.142932 -258.41256) (xy 46.102496 -258.391012)
			(xy 46.058852 -258.377063) (xy 46.013415 -258.371165) (xy 45.99051 -258.371848) (xy 45.965872 -258.372356)
			(xy 45.072554 -258.372356) (xy 45.055874 -258.372887) (xy 45.023654 -258.381539) (xy 44.994774 -258.39824)
			(xy 44.982638 -258.409694) (xy 44.911772 -258.480814) (xy 44.889039 -258.502816) (xy 44.838847 -258.541329)
			(xy 44.784058 -258.572962) (xy 44.725608 -258.597173) (xy 44.664499 -258.613547) (xy 44.601775 -258.621805)
			(xy 44.538509 -258.621805) (xy 44.475785 -258.613547) (xy 44.414676 -258.597173) (xy 44.356226 -258.572962)
			(xy 44.301437 -258.541329) (xy 44.251245 -258.502816) (xy 44.20651 -258.458081) (xy 44.167997 -258.407889)
			(xy 44.136364 -258.3531) (xy 44.112153 -258.29465) (xy 44.095779 -258.233541) (xy 44.087521 -258.170817)
			(xy 28.942538 -258.170817) (xy 28.942538 -260.328156) (xy 30.714579 -262.100197) (xy 44.081171 -262.100197)
			(xy 44.081171 -262.036931) (xy 44.089429 -261.974207) (xy 44.105803 -261.913098) (xy 44.130014 -261.854648)
			(xy 44.161647 -261.799859) (xy 44.20016 -261.749667) (xy 44.222162 -261.726934) (xy 44.654216 -261.29488)
			(xy 45.510958 -261.29488) (xy 45.539253 -261.295276) (xy 45.595454 -261.301897) (xy 45.650496 -261.315041)
			(xy 45.703625 -261.334527) (xy 45.754112 -261.36009) (xy 45.777912 -261.375398) (xy 45.809662 -261.39648)
			(xy 45.866812 -261.39648) (xy 45.866812 -261.440168) (xy 52.335176 -261.440168) (xy 53.987192 -261.440168)
			(xy 53.987192 -263.092184) (xy 52.335176 -263.092184) (xy 52.335176 -261.440168) (xy 45.866812 -261.440168)
			(xy 45.866812 -261.451598) (xy 45.886668 -261.473928) (xy 45.921319 -261.52261) (xy 45.949698 -261.575195)
			(xy 45.971372 -261.630881) (xy 45.986008 -261.688816) (xy 45.993383 -261.748114) (xy 45.993384 -261.807869)
			(xy 45.986011 -261.867167) (xy 45.971377 -261.925102) (xy 45.949706 -261.980789) (xy 45.921329 -262.033375)
			(xy 45.886679 -262.082058) (xy 45.866812 -262.104378) (xy 45.866812 -262.159496) (xy 45.809662 -262.159496)
			(xy 45.777912 -262.180578) (xy 45.754116 -262.195892) (xy 45.703629 -262.221457) (xy 45.6505 -262.240942)
			(xy 45.595456 -262.254081) (xy 45.539253 -262.260694) (xy 45.510958 -262.261096) (xy 45.05452 -262.261096)
			(xy 45.008885 -262.306731) (xy 48.835554 -262.306731) (xy 48.835554 -262.225621) (xy 48.843504 -262.144902)
			(xy 48.859327 -262.065351) (xy 48.882872 -261.987735) (xy 48.913911 -261.912799) (xy 48.952146 -261.841267)
			(xy 48.997208 -261.773827) (xy 49.048663 -261.711128) (xy 49.106016 -261.653775) (xy 49.168715 -261.60232)
			(xy 49.236155 -261.557258) (xy 49.307687 -261.519023) (xy 49.382623 -261.487984) (xy 49.460239 -261.464439)
			(xy 49.53979 -261.448616) (xy 49.620509 -261.440666) (xy 49.701619 -261.440666) (xy 49.782338 -261.448616)
			(xy 49.861889 -261.464439) (xy 49.939505 -261.487984) (xy 50.014441 -261.519023) (xy 50.085973 -261.557258)
			(xy 50.153413 -261.60232) (xy 50.216112 -261.653775) (xy 50.273465 -261.711128) (xy 50.32492 -261.773827)
			(xy 50.369982 -261.841267) (xy 50.408217 -261.912799) (xy 50.439256 -261.987735) (xy 50.462801 -262.065351)
			(xy 50.478624 -262.144902) (xy 50.486574 -262.225621) (xy 50.487072 -262.266176) (xy 50.486574 -262.306731)
			(xy 50.478624 -262.38745) (xy 50.462801 -262.467001) (xy 50.439256 -262.544617) (xy 50.408217 -262.619553)
			(xy 50.369982 -262.691085) (xy 50.32492 -262.758525) (xy 50.273465 -262.821224) (xy 50.216112 -262.878577)
			(xy 50.153413 -262.930032) (xy 50.085973 -262.975094) (xy 50.014441 -263.013329) (xy 49.939505 -263.044368)
			(xy 49.861889 -263.067913) (xy 49.782338 -263.083736) (xy 49.701619 -263.091686) (xy 49.620509 -263.091686)
			(xy 49.53979 -263.083736) (xy 49.460239 -263.067913) (xy 49.382623 -263.044368) (xy 49.307687 -263.013329)
			(xy 49.236155 -262.975094) (xy 49.168715 -262.930032) (xy 49.106016 -262.878577) (xy 49.048663 -262.821224)
			(xy 48.997208 -262.758525) (xy 48.952146 -262.691085) (xy 48.913911 -262.619553) (xy 48.882872 -262.544617)
			(xy 48.859327 -262.467001) (xy 48.843504 -262.38745) (xy 48.835554 -262.306731) (xy 45.008885 -262.306731)
			(xy 44.905422 -262.410194) (xy 44.882689 -262.432196) (xy 44.832497 -262.470709) (xy 44.777708 -262.502342)
			(xy 44.719258 -262.526553) (xy 44.658149 -262.542927) (xy 44.595425 -262.551185) (xy 44.532159 -262.551185)
			(xy 44.469435 -262.542927) (xy 44.408326 -262.526553) (xy 44.349876 -262.502342) (xy 44.295087 -262.470709)
			(xy 44.244895 -262.432196) (xy 44.20016 -262.387461) (xy 44.161647 -262.337269) (xy 44.130014 -262.28248)
			(xy 44.105803 -262.22403) (xy 44.089429 -262.162921) (xy 44.081171 -262.100197) (xy 30.714579 -262.100197)
			(xy 35.035998 -266.421616) (xy 84.87994 -266.421616) (xy 84.884011 -266.365994) (xy 84.896137 -266.311557)
			(xy 84.91606 -266.259466) (xy 84.943356 -266.210831) (xy 84.977442 -266.166688) (xy 85.017591 -266.127979)
			(xy 85.062949 -266.095528) (xy 85.112549 -266.070027) (xy 85.165333 -266.05202) (xy 85.220176 -266.04189)
			(xy 85.27591 -266.039853) (xy 85.331347 -266.045953) (xy 85.385304 -266.060059) (xy 85.436633 -266.081871)
			(xy 85.484239 -266.110925) (xy 85.527107 -266.1466) (xy 85.532282 -266.152376) (xy 87.394794 -266.152376)
			(xy 87.398865 -266.096754) (xy 87.410991 -266.042317) (xy 87.430914 -265.990226) (xy 87.45821 -265.941591)
			(xy 87.492296 -265.897448) (xy 87.532445 -265.858739) (xy 87.577803 -265.826288) (xy 87.627403 -265.800787)
			(xy 87.680187 -265.78278) (xy 87.73503 -265.77265) (xy 87.790764 -265.770613) (xy 87.846201 -265.776713)
			(xy 87.900158 -265.790819) (xy 87.951487 -265.812631) (xy 87.999093 -265.841685) (xy 88.041961 -265.87736)
			(xy 88.079178 -265.918897) (xy 88.109951 -265.96541) (xy 88.133623 -266.015907) (xy 88.149691 -266.069314)
			(xy 88.157811 -266.12449) (xy 88.15832 -266.152376) (xy 88.157811 -266.180262) (xy 88.149691 -266.235438)
			(xy 88.133623 -266.288845) (xy 88.109951 -266.339342) (xy 88.079178 -266.385855) (xy 88.041961 -266.427392)
			(xy 87.999093 -266.463067) (xy 87.951487 -266.492121) (xy 87.900158 -266.513933) (xy 87.846201 -266.528039)
			(xy 87.790764 -266.534139) (xy 87.73503 -266.532102) (xy 87.680187 -266.521972) (xy 87.627403 -266.503965)
			(xy 87.577803 -266.478464) (xy 87.532445 -266.446013) (xy 87.492296 -266.407304) (xy 87.45821 -266.363161)
			(xy 87.430914 -266.314526) (xy 87.410991 -266.262435) (xy 87.398865 -266.207998) (xy 87.394794 -266.152376)
			(xy 85.532282 -266.152376) (xy 85.564324 -266.188137) (xy 85.595097 -266.23465) (xy 85.618769 -266.285147)
			(xy 85.634837 -266.338554) (xy 85.642957 -266.39373) (xy 85.643466 -266.421616) (xy 85.642957 -266.449502)
			(xy 85.634837 -266.504678) (xy 85.618769 -266.558085) (xy 85.595097 -266.608582) (xy 85.564324 -266.655095)
			(xy 85.527107 -266.696632) (xy 85.484239 -266.732307) (xy 85.436633 -266.761361) (xy 85.385304 -266.783173)
			(xy 85.331347 -266.797279) (xy 85.27591 -266.803379) (xy 85.220176 -266.801342) (xy 85.165333 -266.791212)
			(xy 85.112549 -266.773205) (xy 85.062949 -266.747704) (xy 85.017591 -266.715253) (xy 84.977442 -266.676544)
			(xy 84.943356 -266.632401) (xy 84.91606 -266.583766) (xy 84.896137 -266.531675) (xy 84.884011 -266.477238)
			(xy 84.87994 -266.421616) (xy 35.035998 -266.421616) (xy 36.14293 -267.528548) (xy 78.276194 -267.528548)
			(xy 78.280265 -267.472926) (xy 78.292391 -267.418489) (xy 78.312314 -267.366398) (xy 78.33961 -267.317763)
			(xy 78.373696 -267.27362) (xy 78.413845 -267.234911) (xy 78.459203 -267.20246) (xy 78.508803 -267.176959)
			(xy 78.561587 -267.158952) (xy 78.61643 -267.148822) (xy 78.672164 -267.146785) (xy 78.727601 -267.152885)
			(xy 78.781558 -267.166991) (xy 78.832887 -267.188803) (xy 78.880493 -267.217857) (xy 78.923361 -267.253532)
			(xy 78.960578 -267.295069) (xy 78.991351 -267.341582) (xy 79.015023 -267.392079) (xy 79.031091 -267.445486)
			(xy 79.03539 -267.4747) (xy 80.28635 -267.4747) (xy 80.290421 -267.419078) (xy 80.302547 -267.364641)
			(xy 80.32247 -267.31255) (xy 80.349766 -267.263915) (xy 80.383852 -267.219772) (xy 80.424001 -267.181063)
			(xy 80.469359 -267.148612) (xy 80.518959 -267.123111) (xy 80.571743 -267.105104) (xy 80.626586 -267.094974)
			(xy 80.68232 -267.092937) (xy 80.737757 -267.099037) (xy 80.791714 -267.113143) (xy 80.843043 -267.134955)
			(xy 80.873666 -267.153644) (xy 81.976466 -267.153644) (xy 81.980537 -267.098022) (xy 81.992663 -267.043585)
			(xy 82.012586 -266.991494) (xy 82.039882 -266.942859) (xy 82.073968 -266.898716) (xy 82.114117 -266.860007)
			(xy 82.159475 -266.827556) (xy 82.209075 -266.802055) (xy 82.261859 -266.784048) (xy 82.316702 -266.773918)
			(xy 82.372436 -266.771881) (xy 82.427873 -266.777981) (xy 82.48183 -266.792087) (xy 82.533159 -266.813899)
			(xy 82.580765 -266.842953) (xy 82.623633 -266.878628) (xy 82.66085 -266.920165) (xy 82.691623 -266.966678)
			(xy 82.715295 -267.017175) (xy 82.731363 -267.070582) (xy 82.739483 -267.125758) (xy 82.739992 -267.153644)
			(xy 82.739483 -267.18153) (xy 82.731363 -267.236706) (xy 82.715295 -267.290113) (xy 82.691623 -267.34061)
			(xy 82.66085 -267.387123) (xy 82.623633 -267.42866) (xy 82.580765 -267.464335) (xy 82.533159 -267.493389)
			(xy 82.48183 -267.515201) (xy 82.427873 -267.529307) (xy 82.372436 -267.535407) (xy 82.316702 -267.53337)
			(xy 82.261859 -267.52324) (xy 82.209075 -267.505233) (xy 82.159475 -267.479732) (xy 82.114117 -267.447281)
			(xy 82.073968 -267.408572) (xy 82.039882 -267.364429) (xy 82.012586 -267.315794) (xy 81.992663 -267.263703)
			(xy 81.980537 -267.209266) (xy 81.976466 -267.153644) (xy 80.873666 -267.153644) (xy 80.890649 -267.164009)
			(xy 80.933517 -267.199684) (xy 80.970734 -267.241221) (xy 81.001507 -267.287734) (xy 81.025179 -267.338231)
			(xy 81.041247 -267.391638) (xy 81.049367 -267.446814) (xy 81.049876 -267.4747) (xy 81.049367 -267.502586)
			(xy 81.041247 -267.557762) (xy 81.025179 -267.611169) (xy 81.001507 -267.661666) (xy 80.970734 -267.708179)
			(xy 80.933517 -267.749716) (xy 80.890649 -267.785391) (xy 80.843043 -267.814445) (xy 80.791714 -267.836257)
			(xy 80.737757 -267.850363) (xy 80.68232 -267.856463) (xy 80.626586 -267.854426) (xy 80.571743 -267.844296)
			(xy 80.518959 -267.826289) (xy 80.469359 -267.800788) (xy 80.424001 -267.768337) (xy 80.383852 -267.729628)
			(xy 80.349766 -267.685485) (xy 80.32247 -267.63685) (xy 80.302547 -267.584759) (xy 80.290421 -267.530322)
			(xy 80.28635 -267.4747) (xy 79.03539 -267.4747) (xy 79.039211 -267.500662) (xy 79.03972 -267.528548)
			(xy 79.039211 -267.556434) (xy 79.031091 -267.61161) (xy 79.015023 -267.665017) (xy 78.991351 -267.715514)
			(xy 78.960578 -267.762027) (xy 78.923361 -267.803564) (xy 78.880493 -267.839239) (xy 78.832887 -267.868293)
			(xy 78.781558 -267.890105) (xy 78.727601 -267.904211) (xy 78.672164 -267.910311) (xy 78.61643 -267.908274)
			(xy 78.561587 -267.898144) (xy 78.508803 -267.880137) (xy 78.459203 -267.854636) (xy 78.413845 -267.822185)
			(xy 78.373696 -267.783476) (xy 78.33961 -267.739333) (xy 78.312314 -267.690698) (xy 78.292391 -267.638607)
			(xy 78.280265 -267.58417) (xy 78.276194 -267.528548) (xy 36.14293 -267.528548) (xy 36.596828 -267.982446)
			(xy 36.596828 -273.61007) (xy 39.818564 -273.61007) (xy 39.819058 -273.552661) (xy 39.826902 -273.438113)
			(xy 39.842544 -273.324366) (xy 39.865911 -273.211952) (xy 39.896896 -273.101394) (xy 39.935352 -272.993209)
			(xy 39.981101 -272.8879) (xy 40.03393 -272.785958) (xy 40.093592 -272.687859) (xy 40.159809 -272.59406)
			(xy 40.232272 -272.504998) (xy 40.310645 -272.421089) (xy 40.39456 -272.342723) (xy 40.483627 -272.270266)
			(xy 40.577431 -272.204056) (xy 40.675535 -272.144402) (xy 40.777481 -272.091581) (xy 40.882793 -272.045839)
			(xy 40.990981 -272.007391) (xy 41.101541 -271.976415) (xy 41.213957 -271.953056) (xy 41.327705 -271.937423)
			(xy 41.442254 -271.929588) (xy 41.557072 -271.929588) (xy 41.671621 -271.937423) (xy 41.785369 -271.953056)
			(xy 41.897785 -271.976415) (xy 42.008345 -272.007391) (xy 42.116533 -272.045839) (xy 42.221845 -272.091581)
			(xy 42.323791 -272.144402) (xy 42.421895 -272.204056) (xy 42.501239 -272.26006) (xy 43.327577 -272.26006)
			(xy 43.331612 -272.184356) (xy 43.343671 -272.109511) (xy 43.363617 -272.03637) (xy 43.391224 -271.965765)
			(xy 43.42618 -271.898494) (xy 43.468088 -271.835319) (xy 43.516474 -271.776957) (xy 43.57079 -271.724069)
			(xy 43.630419 -271.677254) (xy 43.694687 -271.637042) (xy 43.762864 -271.60389) (xy 43.83418 -271.578172)
			(xy 43.907825 -271.56018) (xy 43.982965 -271.550118) (xy 44.058749 -271.548099) (xy 44.134319 -271.554148)
			(xy 44.208817 -271.568195) (xy 44.2814 -271.590081) (xy 44.351246 -271.619558) (xy 44.417563 -271.656293)
			(xy 44.479599 -271.699868) (xy 44.536652 -271.74979) (xy 44.588076 -271.805494) (xy 44.633287 -271.866349)
			(xy 44.671774 -271.931664) (xy 44.7031 -272.0007) (xy 44.72691 -272.072675) (xy 44.742935 -272.146773)
			(xy 44.750994 -272.222154) (xy 44.751498 -272.26006) (xy 45.867577 -272.26006) (xy 45.871612 -272.184356)
			(xy 45.883671 -272.109511) (xy 45.903617 -272.03637) (xy 45.931224 -271.965765) (xy 45.96618 -271.898494)
			(xy 46.008088 -271.835319) (xy 46.056474 -271.776957) (xy 46.11079 -271.724069) (xy 46.170419 -271.677254)
			(xy 46.234687 -271.637042) (xy 46.302864 -271.60389) (xy 46.37418 -271.578172) (xy 46.447825 -271.56018)
			(xy 46.522965 -271.550118) (xy 46.598749 -271.548099) (xy 46.674319 -271.554148) (xy 46.748817 -271.568195)
			(xy 46.8214 -271.590081) (xy 46.891246 -271.619558) (xy 46.957563 -271.656293) (xy 47.019599 -271.699868)
			(xy 47.076652 -271.74979) (xy 47.128076 -271.805494) (xy 47.173287 -271.866349) (xy 47.211774 -271.931664)
			(xy 47.2431 -272.0007) (xy 47.26691 -272.072675) (xy 47.282935 -272.146773) (xy 47.290994 -272.222154)
			(xy 47.291498 -272.26006) (xy 48.407577 -272.26006) (xy 48.411612 -272.184356) (xy 48.423671 -272.109511)
			(xy 48.443617 -272.03637) (xy 48.471224 -271.965765) (xy 48.50618 -271.898494) (xy 48.548088 -271.835319)
			(xy 48.596474 -271.776957) (xy 48.65079 -271.724069) (xy 48.710419 -271.677254) (xy 48.774687 -271.637042)
			(xy 48.842864 -271.60389) (xy 48.91418 -271.578172) (xy 48.987825 -271.56018) (xy 49.062965 -271.550118)
			(xy 49.138749 -271.548099) (xy 49.214319 -271.554148) (xy 49.288817 -271.568195) (xy 49.3614 -271.590081)
			(xy 49.431246 -271.619558) (xy 49.497563 -271.656293) (xy 49.559599 -271.699868) (xy 49.616652 -271.74979)
			(xy 49.668076 -271.805494) (xy 49.713287 -271.866349) (xy 49.751774 -271.931664) (xy 49.7831 -272.0007)
			(xy 49.80691 -272.072675) (xy 49.822935 -272.146773) (xy 49.830994 -272.222154) (xy 49.831498 -272.26006)
			(xy 50.947577 -272.26006) (xy 50.951612 -272.184356) (xy 50.963671 -272.109511) (xy 50.983617 -272.03637)
			(xy 51.011224 -271.965765) (xy 51.04618 -271.898494) (xy 51.088088 -271.835319) (xy 51.136474 -271.776957)
			(xy 51.19079 -271.724069) (xy 51.250419 -271.677254) (xy 51.314687 -271.637042) (xy 51.382864 -271.60389)
			(xy 51.45418 -271.578172) (xy 51.527825 -271.56018) (xy 51.602965 -271.550118) (xy 51.678749 -271.548099)
			(xy 51.754319 -271.554148) (xy 51.828817 -271.568195) (xy 51.9014 -271.590081) (xy 51.971246 -271.619558)
			(xy 52.037563 -271.656293) (xy 52.099599 -271.699868) (xy 52.156652 -271.74979) (xy 52.208076 -271.805494)
			(xy 52.253287 -271.866349) (xy 52.291774 -271.931664) (xy 52.3231 -272.0007) (xy 52.34691 -272.072675)
			(xy 52.362935 -272.146773) (xy 52.370994 -272.222154) (xy 52.371498 -272.26006) (xy 53.487577 -272.26006)
			(xy 53.491612 -272.184356) (xy 53.503671 -272.109511) (xy 53.523617 -272.03637) (xy 53.551224 -271.965765)
			(xy 53.58618 -271.898494) (xy 53.628088 -271.835319) (xy 53.676474 -271.776957) (xy 53.73079 -271.724069)
			(xy 53.790419 -271.677254) (xy 53.854687 -271.637042) (xy 53.922864 -271.60389) (xy 53.99418 -271.578172)
			(xy 54.067825 -271.56018) (xy 54.142965 -271.550118) (xy 54.218749 -271.548099) (xy 54.294319 -271.554148)
			(xy 54.368817 -271.568195) (xy 54.4414 -271.590081) (xy 54.511246 -271.619558) (xy 54.577563 -271.656293)
			(xy 54.639599 -271.699868) (xy 54.696652 -271.74979) (xy 54.748076 -271.805494) (xy 54.793287 -271.866349)
			(xy 54.831774 -271.931664) (xy 54.8631 -272.0007) (xy 54.88691 -272.072675) (xy 54.902935 -272.146773)
			(xy 54.910994 -272.222154) (xy 54.911498 -272.26006) (xy 56.027577 -272.26006) (xy 56.031612 -272.184356)
			(xy 56.043671 -272.109511) (xy 56.063617 -272.03637) (xy 56.091224 -271.965765) (xy 56.12618 -271.898494)
			(xy 56.168088 -271.835319) (xy 56.216474 -271.776957) (xy 56.27079 -271.724069) (xy 56.330419 -271.677254)
			(xy 56.394687 -271.637042) (xy 56.462864 -271.60389) (xy 56.53418 -271.578172) (xy 56.607825 -271.56018)
			(xy 56.682965 -271.550118) (xy 56.758749 -271.548099) (xy 56.834319 -271.554148) (xy 56.908817 -271.568195)
			(xy 56.9814 -271.590081) (xy 57.051246 -271.619558) (xy 57.117563 -271.656293) (xy 57.179599 -271.699868)
			(xy 57.236652 -271.74979) (xy 57.288076 -271.805494) (xy 57.333287 -271.866349) (xy 57.371774 -271.931664)
			(xy 57.4031 -272.0007) (xy 57.42691 -272.072675) (xy 57.442935 -272.146773) (xy 57.450994 -272.222154)
			(xy 57.451498 -272.26006) (xy 58.567577 -272.26006) (xy 58.571612 -272.184356) (xy 58.583671 -272.109511)
			(xy 58.603617 -272.03637) (xy 58.631224 -271.965765) (xy 58.66618 -271.898494) (xy 58.708088 -271.835319)
			(xy 58.756474 -271.776957) (xy 58.81079 -271.724069) (xy 58.870419 -271.677254) (xy 58.934687 -271.637042)
			(xy 59.002864 -271.60389) (xy 59.07418 -271.578172) (xy 59.147825 -271.56018) (xy 59.222965 -271.550118)
			(xy 59.298749 -271.548099) (xy 59.374319 -271.554148) (xy 59.448817 -271.568195) (xy 59.5214 -271.590081)
			(xy 59.591246 -271.619558) (xy 59.657563 -271.656293) (xy 59.719599 -271.699868) (xy 59.776652 -271.74979)
			(xy 59.828076 -271.805494) (xy 59.873287 -271.866349) (xy 59.911774 -271.931664) (xy 59.9431 -272.0007)
			(xy 59.96691 -272.072675) (xy 59.982935 -272.146773) (xy 59.990994 -272.222154) (xy 59.991498 -272.26006)
			(xy 61.107577 -272.26006) (xy 61.111612 -272.184356) (xy 61.123671 -272.109511) (xy 61.143617 -272.03637)
			(xy 61.171224 -271.965765) (xy 61.20618 -271.898494) (xy 61.248088 -271.835319) (xy 61.296474 -271.776957)
			(xy 61.35079 -271.724069) (xy 61.410419 -271.677254) (xy 61.474687 -271.637042) (xy 61.542864 -271.60389)
			(xy 61.61418 -271.578172) (xy 61.687825 -271.56018) (xy 61.762965 -271.550118) (xy 61.838749 -271.548099)
			(xy 61.914319 -271.554148) (xy 61.988817 -271.568195) (xy 62.0614 -271.590081) (xy 62.131246 -271.619558)
			(xy 62.197563 -271.656293) (xy 62.259599 -271.699868) (xy 62.265544 -271.70507) (xy 86.197697 -271.70507)
			(xy 86.201732 -271.629366) (xy 86.213791 -271.554521) (xy 86.233737 -271.48138) (xy 86.261344 -271.410775)
			(xy 86.2963 -271.343504) (xy 86.338208 -271.280329) (xy 86.386594 -271.221967) (xy 86.44091 -271.169079)
			(xy 86.500539 -271.122264) (xy 86.564807 -271.082052) (xy 86.632984 -271.0489) (xy 86.7043 -271.023182)
			(xy 86.777945 -271.00519) (xy 86.853085 -270.995128) (xy 86.928869 -270.993109) (xy 87.004439 -270.999158)
			(xy 87.078937 -271.013205) (xy 87.15152 -271.035091) (xy 87.221366 -271.064568) (xy 87.287683 -271.101303)
			(xy 87.349719 -271.144878) (xy 87.406772 -271.1948) (xy 87.458196 -271.250504) (xy 87.503407 -271.311359)
			(xy 87.541894 -271.376674) (xy 87.57322 -271.44571) (xy 87.59703 -271.517685) (xy 87.613055 -271.591783)
			(xy 87.621114 -271.667164) (xy 87.621618 -271.70507) (xy 88.737697 -271.70507) (xy 88.741732 -271.629366)
			(xy 88.753791 -271.554521) (xy 88.773737 -271.48138) (xy 88.801344 -271.410775) (xy 88.8363 -271.343504)
			(xy 88.878208 -271.280329) (xy 88.926594 -271.221967) (xy 88.98091 -271.169079) (xy 89.040539 -271.122264)
			(xy 89.104807 -271.082052) (xy 89.172984 -271.0489) (xy 89.2443 -271.023182) (xy 89.317945 -271.00519)
			(xy 89.393085 -270.995128) (xy 89.468869 -270.993109) (xy 89.544439 -270.999158) (xy 89.618937 -271.013205)
			(xy 89.69152 -271.035091) (xy 89.761366 -271.064568) (xy 89.827683 -271.101303) (xy 89.889719 -271.144878)
			(xy 89.946772 -271.1948) (xy 89.998196 -271.250504) (xy 90.043407 -271.311359) (xy 90.081894 -271.376674)
			(xy 90.11322 -271.44571) (xy 90.13703 -271.517685) (xy 90.153055 -271.591783) (xy 90.161114 -271.667164)
			(xy 90.161618 -271.70507) (xy 91.277697 -271.70507) (xy 91.281732 -271.629366) (xy 91.293791 -271.554521)
			(xy 91.313737 -271.48138) (xy 91.341344 -271.410775) (xy 91.3763 -271.343504) (xy 91.418208 -271.280329)
			(xy 91.466594 -271.221967) (xy 91.52091 -271.169079) (xy 91.580539 -271.122264) (xy 91.644807 -271.082052)
			(xy 91.712984 -271.0489) (xy 91.7843 -271.023182) (xy 91.857945 -271.00519) (xy 91.933085 -270.995128)
			(xy 92.008869 -270.993109) (xy 92.084439 -270.999158) (xy 92.158937 -271.013205) (xy 92.23152 -271.035091)
			(xy 92.301366 -271.064568) (xy 92.367683 -271.101303) (xy 92.429719 -271.144878) (xy 92.486772 -271.1948)
			(xy 92.538196 -271.250504) (xy 92.583407 -271.311359) (xy 92.621894 -271.376674) (xy 92.65322 -271.44571)
			(xy 92.67703 -271.517685) (xy 92.693055 -271.591783) (xy 92.701114 -271.667164) (xy 92.701618 -271.70507)
			(xy 92.701114 -271.742976) (xy 92.693055 -271.818357) (xy 92.67703 -271.892455) (xy 92.65322 -271.96443)
			(xy 92.621894 -272.033466) (xy 92.583407 -272.098781) (xy 92.538196 -272.159636) (xy 92.486772 -272.21534)
			(xy 92.429719 -272.265262) (xy 92.367683 -272.308837) (xy 92.301366 -272.345572) (xy 92.23152 -272.375049)
			(xy 92.158937 -272.396935) (xy 92.084439 -272.410982) (xy 92.008869 -272.417031) (xy 91.933085 -272.415012)
			(xy 91.857945 -272.40495) (xy 91.7843 -272.386958) (xy 91.712984 -272.36124) (xy 91.644807 -272.328088)
			(xy 91.580539 -272.287876) (xy 91.52091 -272.241061) (xy 91.466594 -272.188173) (xy 91.418208 -272.129811)
			(xy 91.3763 -272.066636) (xy 91.341344 -271.999365) (xy 91.313737 -271.92876) (xy 91.293791 -271.855619)
			(xy 91.281732 -271.780774) (xy 91.277697 -271.70507) (xy 90.161618 -271.70507) (xy 90.161114 -271.742976)
			(xy 90.153055 -271.818357) (xy 90.13703 -271.892455) (xy 90.11322 -271.96443) (xy 90.081894 -272.033466)
			(xy 90.043407 -272.098781) (xy 89.998196 -272.159636) (xy 89.946772 -272.21534) (xy 89.889719 -272.265262)
			(xy 89.827683 -272.308837) (xy 89.761366 -272.345572) (xy 89.69152 -272.375049) (xy 89.618937 -272.396935)
			(xy 89.544439 -272.410982) (xy 89.468869 -272.417031) (xy 89.393085 -272.415012) (xy 89.317945 -272.40495)
			(xy 89.2443 -272.386958) (xy 89.172984 -272.36124) (xy 89.104807 -272.328088) (xy 89.040539 -272.287876)
			(xy 88.98091 -272.241061) (xy 88.926594 -272.188173) (xy 88.878208 -272.129811) (xy 88.8363 -272.066636)
			(xy 88.801344 -271.999365) (xy 88.773737 -271.92876) (xy 88.753791 -271.855619) (xy 88.741732 -271.780774)
			(xy 88.737697 -271.70507) (xy 87.621618 -271.70507) (xy 87.621114 -271.742976) (xy 87.613055 -271.818357)
			(xy 87.59703 -271.892455) (xy 87.57322 -271.96443) (xy 87.541894 -272.033466) (xy 87.503407 -272.098781)
			(xy 87.458196 -272.159636) (xy 87.406772 -272.21534) (xy 87.349719 -272.265262) (xy 87.287683 -272.308837)
			(xy 87.221366 -272.345572) (xy 87.15152 -272.375049) (xy 87.078937 -272.396935) (xy 87.004439 -272.410982)
			(xy 86.928869 -272.417031) (xy 86.853085 -272.415012) (xy 86.777945 -272.40495) (xy 86.7043 -272.386958)
			(xy 86.632984 -272.36124) (xy 86.564807 -272.328088) (xy 86.500539 -272.287876) (xy 86.44091 -272.241061)
			(xy 86.386594 -272.188173) (xy 86.338208 -272.129811) (xy 86.2963 -272.066636) (xy 86.261344 -271.999365)
			(xy 86.233737 -271.92876) (xy 86.213791 -271.855619) (xy 86.201732 -271.780774) (xy 86.197697 -271.70507)
			(xy 62.265544 -271.70507) (xy 62.316652 -271.74979) (xy 62.368076 -271.805494) (xy 62.413287 -271.866349)
			(xy 62.451774 -271.931664) (xy 62.4831 -272.0007) (xy 62.50691 -272.072675) (xy 62.522935 -272.146773)
			(xy 62.530994 -272.222154) (xy 62.531498 -272.26006) (xy 62.530994 -272.297966) (xy 62.522935 -272.373347)
			(xy 62.50691 -272.447445) (xy 62.4831 -272.51942) (xy 62.451774 -272.588456) (xy 62.413287 -272.653771)
			(xy 62.368076 -272.714626) (xy 62.316652 -272.77033) (xy 62.259599 -272.820252) (xy 62.197563 -272.863827)
			(xy 62.131246 -272.900562) (xy 62.0614 -272.930039) (xy 61.988817 -272.951925) (xy 61.914319 -272.965972)
			(xy 61.838749 -272.972021) (xy 61.762965 -272.970002) (xy 61.687825 -272.95994) (xy 61.61418 -272.941948)
			(xy 61.542864 -272.91623) (xy 61.474687 -272.883078) (xy 61.410419 -272.842866) (xy 61.35079 -272.796051)
			(xy 61.296474 -272.743163) (xy 61.248088 -272.684801) (xy 61.20618 -272.621626) (xy 61.171224 -272.554355)
			(xy 61.143617 -272.48375) (xy 61.123671 -272.410609) (xy 61.111612 -272.335764) (xy 61.107577 -272.26006)
			(xy 59.991498 -272.26006) (xy 59.990994 -272.297966) (xy 59.982935 -272.373347) (xy 59.96691 -272.447445)
			(xy 59.9431 -272.51942) (xy 59.911774 -272.588456) (xy 59.873287 -272.653771) (xy 59.828076 -272.714626)
			(xy 59.776652 -272.77033) (xy 59.719599 -272.820252) (xy 59.657563 -272.863827) (xy 59.591246 -272.900562)
			(xy 59.5214 -272.930039) (xy 59.448817 -272.951925) (xy 59.374319 -272.965972) (xy 59.298749 -272.972021)
			(xy 59.222965 -272.970002) (xy 59.147825 -272.95994) (xy 59.07418 -272.941948) (xy 59.002864 -272.91623)
			(xy 58.934687 -272.883078) (xy 58.870419 -272.842866) (xy 58.81079 -272.796051) (xy 58.756474 -272.743163)
			(xy 58.708088 -272.684801) (xy 58.66618 -272.621626) (xy 58.631224 -272.554355) (xy 58.603617 -272.48375)
			(xy 58.583671 -272.410609) (xy 58.571612 -272.335764) (xy 58.567577 -272.26006) (xy 57.451498 -272.26006)
			(xy 57.450994 -272.297966) (xy 57.442935 -272.373347) (xy 57.42691 -272.447445) (xy 57.4031 -272.51942)
			(xy 57.371774 -272.588456) (xy 57.333287 -272.653771) (xy 57.288076 -272.714626) (xy 57.236652 -272.77033)
			(xy 57.179599 -272.820252) (xy 57.117563 -272.863827) (xy 57.051246 -272.900562) (xy 56.9814 -272.930039)
			(xy 56.908817 -272.951925) (xy 56.834319 -272.965972) (xy 56.758749 -272.972021) (xy 56.682965 -272.970002)
			(xy 56.607825 -272.95994) (xy 56.53418 -272.941948) (xy 56.462864 -272.91623) (xy 56.394687 -272.883078)
			(xy 56.330419 -272.842866) (xy 56.27079 -272.796051) (xy 56.216474 -272.743163) (xy 56.168088 -272.684801)
			(xy 56.12618 -272.621626) (xy 56.091224 -272.554355) (xy 56.063617 -272.48375) (xy 56.043671 -272.410609)
			(xy 56.031612 -272.335764) (xy 56.027577 -272.26006) (xy 54.911498 -272.26006) (xy 54.910994 -272.297966)
			(xy 54.902935 -272.373347) (xy 54.88691 -272.447445) (xy 54.8631 -272.51942) (xy 54.831774 -272.588456)
			(xy 54.793287 -272.653771) (xy 54.748076 -272.714626) (xy 54.696652 -272.77033) (xy 54.639599 -272.820252)
			(xy 54.577563 -272.863827) (xy 54.511246 -272.900562) (xy 54.4414 -272.930039) (xy 54.368817 -272.951925)
			(xy 54.294319 -272.965972) (xy 54.218749 -272.972021) (xy 54.142965 -272.970002) (xy 54.067825 -272.95994)
			(xy 53.99418 -272.941948) (xy 53.922864 -272.91623) (xy 53.854687 -272.883078) (xy 53.790419 -272.842866)
			(xy 53.73079 -272.796051) (xy 53.676474 -272.743163) (xy 53.628088 -272.684801) (xy 53.58618 -272.621626)
			(xy 53.551224 -272.554355) (xy 53.523617 -272.48375) (xy 53.503671 -272.410609) (xy 53.491612 -272.335764)
			(xy 53.487577 -272.26006) (xy 52.371498 -272.26006) (xy 52.370994 -272.297966) (xy 52.362935 -272.373347)
			(xy 52.34691 -272.447445) (xy 52.3231 -272.51942) (xy 52.291774 -272.588456) (xy 52.253287 -272.653771)
			(xy 52.208076 -272.714626) (xy 52.156652 -272.77033) (xy 52.099599 -272.820252) (xy 52.037563 -272.863827)
			(xy 51.971246 -272.900562) (xy 51.9014 -272.930039) (xy 51.828817 -272.951925) (xy 51.754319 -272.965972)
			(xy 51.678749 -272.972021) (xy 51.602965 -272.970002) (xy 51.527825 -272.95994) (xy 51.45418 -272.941948)
			(xy 51.382864 -272.91623) (xy 51.314687 -272.883078) (xy 51.250419 -272.842866) (xy 51.19079 -272.796051)
			(xy 51.136474 -272.743163) (xy 51.088088 -272.684801) (xy 51.04618 -272.621626) (xy 51.011224 -272.554355)
			(xy 50.983617 -272.48375) (xy 50.963671 -272.410609) (xy 50.951612 -272.335764) (xy 50.947577 -272.26006)
			(xy 49.831498 -272.26006) (xy 49.830994 -272.297966) (xy 49.822935 -272.373347) (xy 49.80691 -272.447445)
			(xy 49.7831 -272.51942) (xy 49.751774 -272.588456) (xy 49.713287 -272.653771) (xy 49.668076 -272.714626)
			(xy 49.616652 -272.77033) (xy 49.559599 -272.820252) (xy 49.497563 -272.863827) (xy 49.431246 -272.900562)
			(xy 49.3614 -272.930039) (xy 49.288817 -272.951925) (xy 49.214319 -272.965972) (xy 49.138749 -272.972021)
			(xy 49.062965 -272.970002) (xy 48.987825 -272.95994) (xy 48.91418 -272.941948) (xy 48.842864 -272.91623)
			(xy 48.774687 -272.883078) (xy 48.710419 -272.842866) (xy 48.65079 -272.796051) (xy 48.596474 -272.743163)
			(xy 48.548088 -272.684801) (xy 48.50618 -272.621626) (xy 48.471224 -272.554355) (xy 48.443617 -272.48375)
			(xy 48.423671 -272.410609) (xy 48.411612 -272.335764) (xy 48.407577 -272.26006) (xy 47.291498 -272.26006)
			(xy 47.290994 -272.297966) (xy 47.282935 -272.373347) (xy 47.26691 -272.447445) (xy 47.2431 -272.51942)
			(xy 47.211774 -272.588456) (xy 47.173287 -272.653771) (xy 47.128076 -272.714626) (xy 47.076652 -272.77033)
			(xy 47.019599 -272.820252) (xy 46.957563 -272.863827) (xy 46.891246 -272.900562) (xy 46.8214 -272.930039)
			(xy 46.748817 -272.951925) (xy 46.674319 -272.965972) (xy 46.598749 -272.972021) (xy 46.522965 -272.970002)
			(xy 46.447825 -272.95994) (xy 46.37418 -272.941948) (xy 46.302864 -272.91623) (xy 46.234687 -272.883078)
			(xy 46.170419 -272.842866) (xy 46.11079 -272.796051) (xy 46.056474 -272.743163) (xy 46.008088 -272.684801)
			(xy 45.96618 -272.621626) (xy 45.931224 -272.554355) (xy 45.903617 -272.48375) (xy 45.883671 -272.410609)
			(xy 45.871612 -272.335764) (xy 45.867577 -272.26006) (xy 44.751498 -272.26006) (xy 44.750994 -272.297966)
			(xy 44.742935 -272.373347) (xy 44.72691 -272.447445) (xy 44.7031 -272.51942) (xy 44.671774 -272.588456)
			(xy 44.633287 -272.653771) (xy 44.588076 -272.714626) (xy 44.536652 -272.77033) (xy 44.479599 -272.820252)
			(xy 44.417563 -272.863827) (xy 44.351246 -272.900562) (xy 44.2814 -272.930039) (xy 44.208817 -272.951925)
			(xy 44.134319 -272.965972) (xy 44.058749 -272.972021) (xy 43.982965 -272.970002) (xy 43.907825 -272.95994)
			(xy 43.83418 -272.941948) (xy 43.762864 -272.91623) (xy 43.694687 -272.883078) (xy 43.630419 -272.842866)
			(xy 43.57079 -272.796051) (xy 43.516474 -272.743163) (xy 43.468088 -272.684801) (xy 43.42618 -272.621626)
			(xy 43.391224 -272.554355) (xy 43.363617 -272.48375) (xy 43.343671 -272.410609) (xy 43.331612 -272.335764)
			(xy 43.327577 -272.26006) (xy 42.501239 -272.26006) (xy 42.515699 -272.270266) (xy 42.604766 -272.342723)
			(xy 42.688681 -272.421089) (xy 42.767054 -272.504998) (xy 42.839517 -272.59406) (xy 42.905734 -272.687859)
			(xy 42.965396 -272.785958) (xy 43.018225 -272.8879) (xy 43.056094 -272.97507) (xy 84.927697 -272.97507)
			(xy 84.931732 -272.899366) (xy 84.943791 -272.824521) (xy 84.963737 -272.75138) (xy 84.991344 -272.680775)
			(xy 85.0263 -272.613504) (xy 85.068208 -272.550329) (xy 85.116594 -272.491967) (xy 85.17091 -272.439079)
			(xy 85.230539 -272.392264) (xy 85.294807 -272.352052) (xy 85.362984 -272.3189) (xy 85.4343 -272.293182)
			(xy 85.507945 -272.27519) (xy 85.583085 -272.265128) (xy 85.658869 -272.263109) (xy 85.734439 -272.269158)
			(xy 85.808937 -272.283205) (xy 85.88152 -272.305091) (xy 85.951366 -272.334568) (xy 86.017683 -272.371303)
			(xy 86.079719 -272.414878) (xy 86.136772 -272.4648) (xy 86.188196 -272.520504) (xy 86.233407 -272.581359)
			(xy 86.271894 -272.646674) (xy 86.30322 -272.71571) (xy 86.32703 -272.787685) (xy 86.343055 -272.861783)
			(xy 86.351114 -272.937164) (xy 86.351618 -272.97507) (xy 87.467697 -272.97507) (xy 87.471732 -272.899366)
			(xy 87.483791 -272.824521) (xy 87.503737 -272.75138) (xy 87.531344 -272.680775) (xy 87.5663 -272.613504)
			(xy 87.608208 -272.550329) (xy 87.656594 -272.491967) (xy 87.71091 -272.439079) (xy 87.770539 -272.392264)
			(xy 87.834807 -272.352052) (xy 87.902984 -272.3189) (xy 87.9743 -272.293182) (xy 88.047945 -272.27519)
			(xy 88.123085 -272.265128) (xy 88.198869 -272.263109) (xy 88.274439 -272.269158) (xy 88.348937 -272.283205)
			(xy 88.42152 -272.305091) (xy 88.491366 -272.334568) (xy 88.557683 -272.371303) (xy 88.619719 -272.414878)
			(xy 88.676772 -272.4648) (xy 88.728196 -272.520504) (xy 88.773407 -272.581359) (xy 88.811894 -272.646674)
			(xy 88.84322 -272.71571) (xy 88.86703 -272.787685) (xy 88.883055 -272.861783) (xy 88.891114 -272.937164)
			(xy 88.891618 -272.97507) (xy 90.007697 -272.97507) (xy 90.011732 -272.899366) (xy 90.023791 -272.824521)
			(xy 90.043737 -272.75138) (xy 90.071344 -272.680775) (xy 90.1063 -272.613504) (xy 90.148208 -272.550329)
			(xy 90.196594 -272.491967) (xy 90.25091 -272.439079) (xy 90.310539 -272.392264) (xy 90.374807 -272.352052)
			(xy 90.442984 -272.3189) (xy 90.5143 -272.293182) (xy 90.587945 -272.27519) (xy 90.663085 -272.265128)
			(xy 90.738869 -272.263109) (xy 90.814439 -272.269158) (xy 90.888937 -272.283205) (xy 90.96152 -272.305091)
			(xy 91.031366 -272.334568) (xy 91.097683 -272.371303) (xy 91.159719 -272.414878) (xy 91.216772 -272.4648)
			(xy 91.268196 -272.520504) (xy 91.313407 -272.581359) (xy 91.351894 -272.646674) (xy 91.38322 -272.71571)
			(xy 91.40703 -272.787685) (xy 91.423055 -272.861783) (xy 91.431114 -272.937164) (xy 91.431618 -272.97507)
			(xy 91.431114 -273.012976) (xy 91.423055 -273.088357) (xy 91.40703 -273.162455) (xy 91.38322 -273.23443)
			(xy 91.351894 -273.303466) (xy 91.313407 -273.368781) (xy 91.268196 -273.429636) (xy 91.216772 -273.48534)
			(xy 91.159719 -273.535262) (xy 91.097683 -273.578837) (xy 91.031366 -273.615572) (xy 90.96152 -273.645049)
			(xy 90.888937 -273.666935) (xy 90.814439 -273.680982) (xy 90.738869 -273.687031) (xy 90.663085 -273.685012)
			(xy 90.587945 -273.67495) (xy 90.5143 -273.656958) (xy 90.442984 -273.63124) (xy 90.374807 -273.598088)
			(xy 90.310539 -273.557876) (xy 90.25091 -273.511061) (xy 90.196594 -273.458173) (xy 90.148208 -273.399811)
			(xy 90.1063 -273.336636) (xy 90.071344 -273.269365) (xy 90.043737 -273.19876) (xy 90.023791 -273.125619)
			(xy 90.011732 -273.050774) (xy 90.007697 -272.97507) (xy 88.891618 -272.97507) (xy 88.891114 -273.012976)
			(xy 88.883055 -273.088357) (xy 88.86703 -273.162455) (xy 88.84322 -273.23443) (xy 88.811894 -273.303466)
			(xy 88.773407 -273.368781) (xy 88.728196 -273.429636) (xy 88.676772 -273.48534) (xy 88.619719 -273.535262)
			(xy 88.557683 -273.578837) (xy 88.491366 -273.615572) (xy 88.42152 -273.645049) (xy 88.348937 -273.666935)
			(xy 88.274439 -273.680982) (xy 88.198869 -273.687031) (xy 88.123085 -273.685012) (xy 88.047945 -273.67495)
			(xy 87.9743 -273.656958) (xy 87.902984 -273.63124) (xy 87.834807 -273.598088) (xy 87.770539 -273.557876)
			(xy 87.71091 -273.511061) (xy 87.656594 -273.458173) (xy 87.608208 -273.399811) (xy 87.5663 -273.336636)
			(xy 87.531344 -273.269365) (xy 87.503737 -273.19876) (xy 87.483791 -273.125619) (xy 87.471732 -273.050774)
			(xy 87.467697 -272.97507) (xy 86.351618 -272.97507) (xy 86.351114 -273.012976) (xy 86.343055 -273.088357)
			(xy 86.32703 -273.162455) (xy 86.30322 -273.23443) (xy 86.271894 -273.303466) (xy 86.233407 -273.368781)
			(xy 86.188196 -273.429636) (xy 86.136772 -273.48534) (xy 86.079719 -273.535262) (xy 86.017683 -273.578837)
			(xy 85.951366 -273.615572) (xy 85.88152 -273.645049) (xy 85.808937 -273.666935) (xy 85.734439 -273.680982)
			(xy 85.658869 -273.687031) (xy 85.583085 -273.685012) (xy 85.507945 -273.67495) (xy 85.4343 -273.656958)
			(xy 85.362984 -273.63124) (xy 85.294807 -273.598088) (xy 85.230539 -273.557876) (xy 85.17091 -273.511061)
			(xy 85.116594 -273.458173) (xy 85.068208 -273.399811) (xy 85.0263 -273.336636) (xy 84.991344 -273.269365)
			(xy 84.963737 -273.19876) (xy 84.943791 -273.125619) (xy 84.931732 -273.050774) (xy 84.927697 -272.97507)
			(xy 43.056094 -272.97507) (xy 43.063974 -272.993209) (xy 43.10243 -273.101394) (xy 43.133415 -273.211952)
			(xy 43.156782 -273.324366) (xy 43.172424 -273.438113) (xy 43.180268 -273.552661) (xy 43.180762 -273.61007)
			(xy 43.180576 -273.643253) (xy 43.177909 -273.709567) (xy 43.175428 -273.742658) (xy 43.170272 -273.800942)
			(xy 43.152948 -273.916671) (xy 43.127616 -274.030914) (xy 43.094401 -274.143119) (xy 43.056327 -274.24507)
			(xy 86.197697 -274.24507) (xy 86.201732 -274.169366) (xy 86.213791 -274.094521) (xy 86.233737 -274.02138)
			(xy 86.261344 -273.950775) (xy 86.2963 -273.883504) (xy 86.338208 -273.820329) (xy 86.386594 -273.761967)
			(xy 86.44091 -273.709079) (xy 86.500539 -273.662264) (xy 86.564807 -273.622052) (xy 86.632984 -273.5889)
			(xy 86.7043 -273.563182) (xy 86.777945 -273.54519) (xy 86.853085 -273.535128) (xy 86.928869 -273.533109)
			(xy 87.004439 -273.539158) (xy 87.078937 -273.553205) (xy 87.15152 -273.575091) (xy 87.221366 -273.604568)
			(xy 87.287683 -273.641303) (xy 87.349719 -273.684878) (xy 87.406772 -273.7348) (xy 87.458196 -273.790504)
			(xy 87.503407 -273.851359) (xy 87.541894 -273.916674) (xy 87.57322 -273.98571) (xy 87.59703 -274.057685)
			(xy 87.613055 -274.131783) (xy 87.621114 -274.207164) (xy 87.621618 -274.24507) (xy 88.737697 -274.24507)
			(xy 88.741732 -274.169366) (xy 88.753791 -274.094521) (xy 88.773737 -274.02138) (xy 88.801344 -273.950775)
			(xy 88.8363 -273.883504) (xy 88.878208 -273.820329) (xy 88.926594 -273.761967) (xy 88.98091 -273.709079)
			(xy 89.040539 -273.662264) (xy 89.104807 -273.622052) (xy 89.172984 -273.5889) (xy 89.2443 -273.563182)
			(xy 89.317945 -273.54519) (xy 89.393085 -273.535128) (xy 89.468869 -273.533109) (xy 89.544439 -273.539158)
			(xy 89.618937 -273.553205) (xy 89.69152 -273.575091) (xy 89.761366 -273.604568) (xy 89.827683 -273.641303)
			(xy 89.889719 -273.684878) (xy 89.946772 -273.7348) (xy 89.998196 -273.790504) (xy 90.043407 -273.851359)
			(xy 90.081894 -273.916674) (xy 90.11322 -273.98571) (xy 90.13703 -274.057685) (xy 90.153055 -274.131783)
			(xy 90.161114 -274.207164) (xy 90.161618 -274.24507) (xy 91.277697 -274.24507) (xy 91.281732 -274.169366)
			(xy 91.293791 -274.094521) (xy 91.313737 -274.02138) (xy 91.341344 -273.950775) (xy 91.3763 -273.883504)
			(xy 91.418208 -273.820329) (xy 91.466594 -273.761967) (xy 91.52091 -273.709079) (xy 91.580539 -273.662264)
			(xy 91.644807 -273.622052) (xy 91.712984 -273.5889) (xy 91.7843 -273.563182) (xy 91.857945 -273.54519)
			(xy 91.933085 -273.535128) (xy 92.008869 -273.533109) (xy 92.084439 -273.539158) (xy 92.158937 -273.553205)
			(xy 92.23152 -273.575091) (xy 92.301366 -273.604568) (xy 92.367683 -273.641303) (xy 92.429719 -273.684878)
			(xy 92.486772 -273.7348) (xy 92.538196 -273.790504) (xy 92.583407 -273.851359) (xy 92.621894 -273.916674)
			(xy 92.65322 -273.98571) (xy 92.67703 -274.057685) (xy 92.693055 -274.131783) (xy 92.701114 -274.207164)
			(xy 92.701618 -274.24507) (xy 92.701114 -274.282976) (xy 92.693055 -274.358357) (xy 92.67703 -274.432455)
			(xy 92.65322 -274.50443) (xy 92.621894 -274.573466) (xy 92.583407 -274.638781) (xy 92.538196 -274.699636)
			(xy 92.486772 -274.75534) (xy 92.429719 -274.805262) (xy 92.367683 -274.848837) (xy 92.301366 -274.885572)
			(xy 92.23152 -274.915049) (xy 92.158937 -274.936935) (xy 92.084439 -274.950982) (xy 92.008869 -274.957031)
			(xy 91.933085 -274.955012) (xy 91.857945 -274.94495) (xy 91.7843 -274.926958) (xy 91.712984 -274.90124)
			(xy 91.644807 -274.868088) (xy 91.580539 -274.827876) (xy 91.52091 -274.781061) (xy 91.466594 -274.728173)
			(xy 91.418208 -274.669811) (xy 91.3763 -274.606636) (xy 91.341344 -274.539365) (xy 91.313737 -274.46876)
			(xy 91.293791 -274.395619) (xy 91.281732 -274.320774) (xy 91.277697 -274.24507) (xy 90.161618 -274.24507)
			(xy 90.161114 -274.282976) (xy 90.153055 -274.358357) (xy 90.13703 -274.432455) (xy 90.11322 -274.50443)
			(xy 90.081894 -274.573466) (xy 90.043407 -274.638781) (xy 89.998196 -274.699636) (xy 89.946772 -274.75534)
			(xy 89.889719 -274.805262) (xy 89.827683 -274.848837) (xy 89.761366 -274.885572) (xy 89.69152 -274.915049)
			(xy 89.618937 -274.936935) (xy 89.544439 -274.950982) (xy 89.468869 -274.957031) (xy 89.393085 -274.955012)
			(xy 89.317945 -274.94495) (xy 89.2443 -274.926958) (xy 89.172984 -274.90124) (xy 89.104807 -274.868088)
			(xy 89.040539 -274.827876) (xy 88.98091 -274.781061) (xy 88.926594 -274.728173) (xy 88.878208 -274.669811)
			(xy 88.8363 -274.606636) (xy 88.801344 -274.539365) (xy 88.773737 -274.46876) (xy 88.753791 -274.395619)
			(xy 88.741732 -274.320774) (xy 88.737697 -274.24507) (xy 87.621618 -274.24507) (xy 87.621114 -274.282976)
			(xy 87.613055 -274.358357) (xy 87.59703 -274.432455) (xy 87.57322 -274.50443) (xy 87.541894 -274.573466)
			(xy 87.503407 -274.638781) (xy 87.458196 -274.699636) (xy 87.406772 -274.75534) (xy 87.349719 -274.805262)
			(xy 87.287683 -274.848837) (xy 87.221366 -274.885572) (xy 87.15152 -274.915049) (xy 87.078937 -274.936935)
			(xy 87.004439 -274.950982) (xy 86.928869 -274.957031) (xy 86.853085 -274.955012) (xy 86.777945 -274.94495)
			(xy 86.7043 -274.926958) (xy 86.632984 -274.90124) (xy 86.564807 -274.868088) (xy 86.500539 -274.827876)
			(xy 86.44091 -274.781061) (xy 86.386594 -274.728173) (xy 86.338208 -274.669811) (xy 86.2963 -274.606636)
			(xy 86.261344 -274.539365) (xy 86.233737 -274.46876) (xy 86.213791 -274.395619) (xy 86.201732 -274.320774)
			(xy 86.197697 -274.24507) (xy 43.056327 -274.24507) (xy 43.055094 -274.248372) (xy 43.328336 -274.248372)
			(xy 44.751244 -274.248372) (xy 44.751244 -274.96008) (xy 45.867577 -274.96008) (xy 45.871612 -274.884376)
			(xy 45.883671 -274.809531) (xy 45.903617 -274.73639) (xy 45.931224 -274.665785) (xy 45.96618 -274.598514)
			(xy 46.008088 -274.535339) (xy 46.056474 -274.476977) (xy 46.11079 -274.424089) (xy 46.170419 -274.377274)
			(xy 46.234687 -274.337062) (xy 46.302864 -274.30391) (xy 46.37418 -274.278192) (xy 46.447825 -274.2602)
			(xy 46.522965 -274.250138) (xy 46.598749 -274.248119) (xy 46.674319 -274.254168) (xy 46.748817 -274.268215)
			(xy 46.8214 -274.290101) (xy 46.891246 -274.319578) (xy 46.957563 -274.356313) (xy 47.019599 -274.399888)
			(xy 47.076652 -274.44981) (xy 47.128076 -274.505514) (xy 47.173287 -274.566369) (xy 47.211774 -274.631684)
			(xy 47.2431 -274.70072) (xy 47.26691 -274.772695) (xy 47.282935 -274.846793) (xy 47.290994 -274.922174)
			(xy 47.291498 -274.96008) (xy 48.407577 -274.96008) (xy 48.411612 -274.884376) (xy 48.423671 -274.809531)
			(xy 48.443617 -274.73639) (xy 48.471224 -274.665785) (xy 48.50618 -274.598514) (xy 48.548088 -274.535339)
			(xy 48.596474 -274.476977) (xy 48.65079 -274.424089) (xy 48.710419 -274.377274) (xy 48.774687 -274.337062)
			(xy 48.842864 -274.30391) (xy 48.91418 -274.278192) (xy 48.987825 -274.2602) (xy 49.062965 -274.250138)
			(xy 49.138749 -274.248119) (xy 49.214319 -274.254168) (xy 49.288817 -274.268215) (xy 49.3614 -274.290101)
			(xy 49.431246 -274.319578) (xy 49.497563 -274.356313) (xy 49.559599 -274.399888) (xy 49.616652 -274.44981)
			(xy 49.668076 -274.505514) (xy 49.713287 -274.566369) (xy 49.751774 -274.631684) (xy 49.7831 -274.70072)
			(xy 49.80691 -274.772695) (xy 49.822935 -274.846793) (xy 49.830994 -274.922174) (xy 49.831498 -274.96008)
			(xy 50.947577 -274.96008) (xy 50.951612 -274.884376) (xy 50.963671 -274.809531) (xy 50.983617 -274.73639)
			(xy 51.011224 -274.665785) (xy 51.04618 -274.598514) (xy 51.088088 -274.535339) (xy 51.136474 -274.476977)
			(xy 51.19079 -274.424089) (xy 51.250419 -274.377274) (xy 51.314687 -274.337062) (xy 51.382864 -274.30391)
			(xy 51.45418 -274.278192) (xy 51.527825 -274.2602) (xy 51.602965 -274.250138) (xy 51.678749 -274.248119)
			(xy 51.754319 -274.254168) (xy 51.828817 -274.268215) (xy 51.9014 -274.290101) (xy 51.971246 -274.319578)
			(xy 52.037563 -274.356313) (xy 52.099599 -274.399888) (xy 52.156652 -274.44981) (xy 52.208076 -274.505514)
			(xy 52.253287 -274.566369) (xy 52.291774 -274.631684) (xy 52.3231 -274.70072) (xy 52.34691 -274.772695)
			(xy 52.362935 -274.846793) (xy 52.370994 -274.922174) (xy 52.371498 -274.96008) (xy 53.487577 -274.96008)
			(xy 53.491612 -274.884376) (xy 53.503671 -274.809531) (xy 53.523617 -274.73639) (xy 53.551224 -274.665785)
			(xy 53.58618 -274.598514) (xy 53.628088 -274.535339) (xy 53.676474 -274.476977) (xy 53.73079 -274.424089)
			(xy 53.790419 -274.377274) (xy 53.854687 -274.337062) (xy 53.922864 -274.30391) (xy 53.99418 -274.278192)
			(xy 54.067825 -274.2602) (xy 54.142965 -274.250138) (xy 54.218749 -274.248119) (xy 54.294319 -274.254168)
			(xy 54.368817 -274.268215) (xy 54.4414 -274.290101) (xy 54.511246 -274.319578) (xy 54.577563 -274.356313)
			(xy 54.639599 -274.399888) (xy 54.696652 -274.44981) (xy 54.748076 -274.505514) (xy 54.793287 -274.566369)
			(xy 54.831774 -274.631684) (xy 54.8631 -274.70072) (xy 54.88691 -274.772695) (xy 54.902935 -274.846793)
			(xy 54.910994 -274.922174) (xy 54.911498 -274.96008) (xy 56.027577 -274.96008) (xy 56.031612 -274.884376)
			(xy 56.043671 -274.809531) (xy 56.063617 -274.73639) (xy 56.091224 -274.665785) (xy 56.12618 -274.598514)
			(xy 56.168088 -274.535339) (xy 56.216474 -274.476977) (xy 56.27079 -274.424089) (xy 56.330419 -274.377274)
			(xy 56.394687 -274.337062) (xy 56.462864 -274.30391) (xy 56.53418 -274.278192) (xy 56.607825 -274.2602)
			(xy 56.682965 -274.250138) (xy 56.758749 -274.248119) (xy 56.834319 -274.254168) (xy 56.908817 -274.268215)
			(xy 56.9814 -274.290101) (xy 57.051246 -274.319578) (xy 57.117563 -274.356313) (xy 57.179599 -274.399888)
			(xy 57.236652 -274.44981) (xy 57.288076 -274.505514) (xy 57.333287 -274.566369) (xy 57.371774 -274.631684)
			(xy 57.4031 -274.70072) (xy 57.42691 -274.772695) (xy 57.442935 -274.846793) (xy 57.450994 -274.922174)
			(xy 57.451498 -274.96008) (xy 58.567577 -274.96008) (xy 58.571612 -274.884376) (xy 58.583671 -274.809531)
			(xy 58.603617 -274.73639) (xy 58.631224 -274.665785) (xy 58.66618 -274.598514) (xy 58.708088 -274.535339)
			(xy 58.756474 -274.476977) (xy 58.81079 -274.424089) (xy 58.870419 -274.377274) (xy 58.934687 -274.337062)
			(xy 59.002864 -274.30391) (xy 59.07418 -274.278192) (xy 59.147825 -274.2602) (xy 59.222965 -274.250138)
			(xy 59.298749 -274.248119) (xy 59.374319 -274.254168) (xy 59.448817 -274.268215) (xy 59.5214 -274.290101)
			(xy 59.591246 -274.319578) (xy 59.657563 -274.356313) (xy 59.719599 -274.399888) (xy 59.776652 -274.44981)
			(xy 59.828076 -274.505514) (xy 59.873287 -274.566369) (xy 59.911774 -274.631684) (xy 59.9431 -274.70072)
			(xy 59.96691 -274.772695) (xy 59.982935 -274.846793) (xy 59.990994 -274.922174) (xy 59.991498 -274.96008)
			(xy 61.107577 -274.96008) (xy 61.111612 -274.884376) (xy 61.123671 -274.809531) (xy 61.143617 -274.73639)
			(xy 61.171224 -274.665785) (xy 61.20618 -274.598514) (xy 61.248088 -274.535339) (xy 61.296474 -274.476977)
			(xy 61.35079 -274.424089) (xy 61.410419 -274.377274) (xy 61.474687 -274.337062) (xy 61.542864 -274.30391)
			(xy 61.61418 -274.278192) (xy 61.687825 -274.2602) (xy 61.762965 -274.250138) (xy 61.838749 -274.248119)
			(xy 61.914319 -274.254168) (xy 61.988817 -274.268215) (xy 62.0614 -274.290101) (xy 62.131246 -274.319578)
			(xy 62.197563 -274.356313) (xy 62.259599 -274.399888) (xy 62.316652 -274.44981) (xy 62.368076 -274.505514)
			(xy 62.413287 -274.566369) (xy 62.451774 -274.631684) (xy 62.4831 -274.70072) (xy 62.50691 -274.772695)
			(xy 62.522935 -274.846793) (xy 62.530994 -274.922174) (xy 62.531498 -274.96008) (xy 62.530994 -274.997986)
			(xy 62.522935 -275.073367) (xy 62.50691 -275.147465) (xy 62.4831 -275.21944) (xy 62.451774 -275.288476)
			(xy 62.413287 -275.353791) (xy 62.368076 -275.414646) (xy 62.316652 -275.47035) (xy 62.265544 -275.51507)
			(xy 84.927697 -275.51507) (xy 84.931732 -275.439366) (xy 84.943791 -275.364521) (xy 84.963737 -275.29138)
			(xy 84.991344 -275.220775) (xy 85.0263 -275.153504) (xy 85.068208 -275.090329) (xy 85.116594 -275.031967)
			(xy 85.17091 -274.979079) (xy 85.230539 -274.932264) (xy 85.294807 -274.892052) (xy 85.362984 -274.8589)
			(xy 85.4343 -274.833182) (xy 85.507945 -274.81519) (xy 85.583085 -274.805128) (xy 85.658869 -274.803109)
			(xy 85.734439 -274.809158) (xy 85.808937 -274.823205) (xy 85.88152 -274.845091) (xy 85.951366 -274.874568)
			(xy 86.017683 -274.911303) (xy 86.079719 -274.954878) (xy 86.136772 -275.0048) (xy 86.188196 -275.060504)
			(xy 86.233407 -275.121359) (xy 86.271894 -275.186674) (xy 86.30322 -275.25571) (xy 86.32703 -275.327685)
			(xy 86.343055 -275.401783) (xy 86.351114 -275.477164) (xy 86.351618 -275.51507) (xy 87.467697 -275.51507)
			(xy 87.471732 -275.439366) (xy 87.483791 -275.364521) (xy 87.503737 -275.29138) (xy 87.531344 -275.220775)
			(xy 87.5663 -275.153504) (xy 87.608208 -275.090329) (xy 87.656594 -275.031967) (xy 87.71091 -274.979079)
			(xy 87.770539 -274.932264) (xy 87.834807 -274.892052) (xy 87.902984 -274.8589) (xy 87.9743 -274.833182)
			(xy 88.047945 -274.81519) (xy 88.123085 -274.805128) (xy 88.198869 -274.803109) (xy 88.274439 -274.809158)
			(xy 88.348937 -274.823205) (xy 88.42152 -274.845091) (xy 88.491366 -274.874568) (xy 88.557683 -274.911303)
			(xy 88.619719 -274.954878) (xy 88.676772 -275.0048) (xy 88.728196 -275.060504) (xy 88.773407 -275.121359)
			(xy 88.811894 -275.186674) (xy 88.84322 -275.25571) (xy 88.86703 -275.327685) (xy 88.883055 -275.401783)
			(xy 88.891114 -275.477164) (xy 88.891618 -275.51507) (xy 90.007697 -275.51507) (xy 90.011732 -275.439366)
			(xy 90.023791 -275.364521) (xy 90.043737 -275.29138) (xy 90.071344 -275.220775) (xy 90.1063 -275.153504)
			(xy 90.148208 -275.090329) (xy 90.196594 -275.031967) (xy 90.25091 -274.979079) (xy 90.310539 -274.932264)
			(xy 90.374807 -274.892052) (xy 90.442984 -274.8589) (xy 90.5143 -274.833182) (xy 90.587945 -274.81519)
			(xy 90.663085 -274.805128) (xy 90.738869 -274.803109) (xy 90.814439 -274.809158) (xy 90.888937 -274.823205)
			(xy 90.96152 -274.845091) (xy 91.031366 -274.874568) (xy 91.097683 -274.911303) (xy 91.159719 -274.954878)
			(xy 91.165664 -274.96008) (xy 93.154506 -274.96008) (xy 93.158522 -274.84381) (xy 93.170549 -274.728095)
			(xy 93.190531 -274.613485) (xy 93.218373 -274.500526) (xy 93.253942 -274.389758) (xy 93.297068 -274.281707)
			(xy 93.347545 -274.176889) (xy 93.405134 -274.075804) (xy 93.46956 -273.978932) (xy 93.540515 -273.886736)
			(xy 93.617662 -273.799655) (xy 93.700633 -273.718104) (xy 93.789033 -273.642472) (xy 93.88244 -273.573118)
			(xy 93.980409 -273.510375) (xy 94.082473 -273.454539) (xy 94.188147 -273.405878) (xy 94.296926 -273.364624)
			(xy 94.408291 -273.330973) (xy 94.521714 -273.305085) (xy 94.636651 -273.287084) (xy 94.752557 -273.277055)
			(xy 94.868879 -273.275047) (xy 94.985062 -273.281069) (xy 95.100553 -273.295092) (xy 95.214801 -273.31705)
			(xy 95.327262 -273.346837) (xy 95.4374 -273.384312) (xy 95.54469 -273.429297) (xy 95.648621 -273.481576)
			(xy 95.748697 -273.540901) (xy 95.844443 -273.606989) (xy 95.9354 -273.679525) (xy 96.021136 -273.758164)
			(xy 96.101243 -273.84253) (xy 96.175339 -273.932222) (xy 96.243069 -274.026812) (xy 96.304113 -274.12585)
			(xy 96.358178 -274.228863) (xy 96.405008 -274.33536) (xy 96.444379 -274.444835) (xy 96.476103 -274.556765)
			(xy 96.500029 -274.670617) (xy 96.516043 -274.785849) (xy 96.52407 -274.901911) (xy 96.524572 -274.96008)
			(xy 96.52407 -275.018249) (xy 96.516043 -275.134311) (xy 96.500029 -275.249543) (xy 96.476103 -275.363395)
			(xy 96.444379 -275.475325) (xy 96.405008 -275.5848) (xy 96.358178 -275.691297) (xy 96.304113 -275.79431)
			(xy 96.243069 -275.893348) (xy 96.175339 -275.987938) (xy 96.101243 -276.07763) (xy 96.021136 -276.161996)
			(xy 95.9354 -276.240635) (xy 95.844443 -276.313171) (xy 95.748697 -276.379259) (xy 95.648621 -276.438584)
			(xy 95.54469 -276.490863) (xy 95.4374 -276.535848) (xy 95.327262 -276.573323) (xy 95.214801 -276.60311)
			(xy 95.100553 -276.625068) (xy 94.985062 -276.639091) (xy 94.868879 -276.645113) (xy 94.752557 -276.643105)
			(xy 94.636651 -276.633076) (xy 94.521714 -276.615075) (xy 94.408291 -276.589187) (xy 94.296926 -276.555536)
			(xy 94.188147 -276.514282) (xy 94.082473 -276.465621) (xy 93.980409 -276.409785) (xy 93.88244 -276.347042)
			(xy 93.789033 -276.277688) (xy 93.700633 -276.202056) (xy 93.617662 -276.120505) (xy 93.540515 -276.033424)
			(xy 93.46956 -275.941228) (xy 93.405134 -275.844356) (xy 93.347545 -275.743271) (xy 93.297068 -275.638453)
			(xy 93.253942 -275.530402) (xy 93.218373 -275.419634) (xy 93.190531 -275.306675) (xy 93.170549 -275.192065)
			(xy 93.158522 -275.07635) (xy 93.154506 -274.96008) (xy 91.165664 -274.96008) (xy 91.216772 -275.0048)
			(xy 91.268196 -275.060504) (xy 91.313407 -275.121359) (xy 91.351894 -275.186674) (xy 91.38322 -275.25571)
			(xy 91.40703 -275.327685) (xy 91.423055 -275.401783) (xy 91.431114 -275.477164) (xy 91.431618 -275.51507)
			(xy 91.431114 -275.552976) (xy 91.423055 -275.628357) (xy 91.40703 -275.702455) (xy 91.38322 -275.77443)
			(xy 91.351894 -275.843466) (xy 91.313407 -275.908781) (xy 91.268196 -275.969636) (xy 91.216772 -276.02534)
			(xy 91.159719 -276.075262) (xy 91.097683 -276.118837) (xy 91.031366 -276.155572) (xy 90.96152 -276.185049)
			(xy 90.888937 -276.206935) (xy 90.814439 -276.220982) (xy 90.738869 -276.227031) (xy 90.663085 -276.225012)
			(xy 90.587945 -276.21495) (xy 90.5143 -276.196958) (xy 90.442984 -276.17124) (xy 90.374807 -276.138088)
			(xy 90.310539 -276.097876) (xy 90.25091 -276.051061) (xy 90.196594 -275.998173) (xy 90.148208 -275.939811)
			(xy 90.1063 -275.876636) (xy 90.071344 -275.809365) (xy 90.043737 -275.73876) (xy 90.023791 -275.665619)
			(xy 90.011732 -275.590774) (xy 90.007697 -275.51507) (xy 88.891618 -275.51507) (xy 88.891114 -275.552976)
			(xy 88.883055 -275.628357) (xy 88.86703 -275.702455) (xy 88.84322 -275.77443) (xy 88.811894 -275.843466)
			(xy 88.773407 -275.908781) (xy 88.728196 -275.969636) (xy 88.676772 -276.02534) (xy 88.619719 -276.075262)
			(xy 88.557683 -276.118837) (xy 88.491366 -276.155572) (xy 88.42152 -276.185049) (xy 88.348937 -276.206935)
			(xy 88.274439 -276.220982) (xy 88.198869 -276.227031) (xy 88.123085 -276.225012) (xy 88.047945 -276.21495)
			(xy 87.9743 -276.196958) (xy 87.902984 -276.17124) (xy 87.834807 -276.138088) (xy 87.770539 -276.097876)
			(xy 87.71091 -276.051061) (xy 87.656594 -275.998173) (xy 87.608208 -275.939811) (xy 87.5663 -275.876636)
			(xy 87.531344 -275.809365) (xy 87.503737 -275.73876) (xy 87.483791 -275.665619) (xy 87.471732 -275.590774)
			(xy 87.467697 -275.51507) (xy 86.351618 -275.51507) (xy 86.351114 -275.552976) (xy 86.343055 -275.628357)
			(xy 86.32703 -275.702455) (xy 86.30322 -275.77443) (xy 86.271894 -275.843466) (xy 86.233407 -275.908781)
			(xy 86.188196 -275.969636) (xy 86.136772 -276.02534) (xy 86.079719 -276.075262) (xy 86.017683 -276.118837)
			(xy 85.951366 -276.155572) (xy 85.88152 -276.185049) (xy 85.808937 -276.206935) (xy 85.734439 -276.220982)
			(xy 85.658869 -276.227031) (xy 85.583085 -276.225012) (xy 85.507945 -276.21495) (xy 85.4343 -276.196958)
			(xy 85.362984 -276.17124) (xy 85.294807 -276.138088) (xy 85.230539 -276.097876) (xy 85.17091 -276.051061)
			(xy 85.116594 -275.998173) (xy 85.068208 -275.939811) (xy 85.0263 -275.876636) (xy 84.991344 -275.809365)
			(xy 84.963737 -275.73876) (xy 84.943791 -275.665619) (xy 84.931732 -275.590774) (xy 84.927697 -275.51507)
			(xy 62.265544 -275.51507) (xy 62.259599 -275.520272) (xy 62.197563 -275.563847) (xy 62.131246 -275.600582)
			(xy 62.0614 -275.630059) (xy 61.988817 -275.651945) (xy 61.914319 -275.665992) (xy 61.838749 -275.672041)
			(xy 61.762965 -275.670022) (xy 61.687825 -275.65996) (xy 61.61418 -275.641968) (xy 61.542864 -275.61625)
			(xy 61.474687 -275.583098) (xy 61.410419 -275.542886) (xy 61.35079 -275.496071) (xy 61.296474 -275.443183)
			(xy 61.248088 -275.384821) (xy 61.20618 -275.321646) (xy 61.171224 -275.254375) (xy 61.143617 -275.18377)
			(xy 61.123671 -275.110629) (xy 61.111612 -275.035784) (xy 61.107577 -274.96008) (xy 59.991498 -274.96008)
			(xy 59.990994 -274.997986) (xy 59.982935 -275.073367) (xy 59.96691 -275.147465) (xy 59.9431 -275.21944)
			(xy 59.911774 -275.288476) (xy 59.873287 -275.353791) (xy 59.828076 -275.414646) (xy 59.776652 -275.47035)
			(xy 59.719599 -275.520272) (xy 59.657563 -275.563847) (xy 59.591246 -275.600582) (xy 59.5214 -275.630059)
			(xy 59.448817 -275.651945) (xy 59.374319 -275.665992) (xy 59.298749 -275.672041) (xy 59.222965 -275.670022)
			(xy 59.147825 -275.65996) (xy 59.07418 -275.641968) (xy 59.002864 -275.61625) (xy 58.934687 -275.583098)
			(xy 58.870419 -275.542886) (xy 58.81079 -275.496071) (xy 58.756474 -275.443183) (xy 58.708088 -275.384821)
			(xy 58.66618 -275.321646) (xy 58.631224 -275.254375) (xy 58.603617 -275.18377) (xy 58.583671 -275.110629)
			(xy 58.571612 -275.035784) (xy 58.567577 -274.96008) (xy 57.451498 -274.96008) (xy 57.450994 -274.997986)
			(xy 57.442935 -275.073367) (xy 57.42691 -275.147465) (xy 57.4031 -275.21944) (xy 57.371774 -275.288476)
			(xy 57.333287 -275.353791) (xy 57.288076 -275.414646) (xy 57.236652 -275.47035) (xy 57.179599 -275.520272)
			(xy 57.117563 -275.563847) (xy 57.051246 -275.600582) (xy 56.9814 -275.630059) (xy 56.908817 -275.651945)
			(xy 56.834319 -275.665992) (xy 56.758749 -275.672041) (xy 56.682965 -275.670022) (xy 56.607825 -275.65996)
			(xy 56.53418 -275.641968) (xy 56.462864 -275.61625) (xy 56.394687 -275.583098) (xy 56.330419 -275.542886)
			(xy 56.27079 -275.496071) (xy 56.216474 -275.443183) (xy 56.168088 -275.384821) (xy 56.12618 -275.321646)
			(xy 56.091224 -275.254375) (xy 56.063617 -275.18377) (xy 56.043671 -275.110629) (xy 56.031612 -275.035784)
			(xy 56.027577 -274.96008) (xy 54.911498 -274.96008) (xy 54.910994 -274.997986) (xy 54.902935 -275.073367)
			(xy 54.88691 -275.147465) (xy 54.8631 -275.21944) (xy 54.831774 -275.288476) (xy 54.793287 -275.353791)
			(xy 54.748076 -275.414646) (xy 54.696652 -275.47035) (xy 54.639599 -275.520272) (xy 54.577563 -275.563847)
			(xy 54.511246 -275.600582) (xy 54.4414 -275.630059) (xy 54.368817 -275.651945) (xy 54.294319 -275.665992)
			(xy 54.218749 -275.672041) (xy 54.142965 -275.670022) (xy 54.067825 -275.65996) (xy 53.99418 -275.641968)
			(xy 53.922864 -275.61625) (xy 53.854687 -275.583098) (xy 53.790419 -275.542886) (xy 53.73079 -275.496071)
			(xy 53.676474 -275.443183) (xy 53.628088 -275.384821) (xy 53.58618 -275.321646) (xy 53.551224 -275.254375)
			(xy 53.523617 -275.18377) (xy 53.503671 -275.110629) (xy 53.491612 -275.035784) (xy 53.487577 -274.96008)
			(xy 52.371498 -274.96008) (xy 52.370994 -274.997986) (xy 52.362935 -275.073367) (xy 52.34691 -275.147465)
			(xy 52.3231 -275.21944) (xy 52.291774 -275.288476) (xy 52.253287 -275.353791) (xy 52.208076 -275.414646)
			(xy 52.156652 -275.47035) (xy 52.099599 -275.520272) (xy 52.037563 -275.563847) (xy 51.971246 -275.600582)
			(xy 51.9014 -275.630059) (xy 51.828817 -275.651945) (xy 51.754319 -275.665992) (xy 51.678749 -275.672041)
			(xy 51.602965 -275.670022) (xy 51.527825 -275.65996) (xy 51.45418 -275.641968) (xy 51.382864 -275.61625)
			(xy 51.314687 -275.583098) (xy 51.250419 -275.542886) (xy 51.19079 -275.496071) (xy 51.136474 -275.443183)
			(xy 51.088088 -275.384821) (xy 51.04618 -275.321646) (xy 51.011224 -275.254375) (xy 50.983617 -275.18377)
			(xy 50.963671 -275.110629) (xy 50.951612 -275.035784) (xy 50.947577 -274.96008) (xy 49.831498 -274.96008)
			(xy 49.830994 -274.997986) (xy 49.822935 -275.073367) (xy 49.80691 -275.147465) (xy 49.7831 -275.21944)
			(xy 49.751774 -275.288476) (xy 49.713287 -275.353791) (xy 49.668076 -275.414646) (xy 49.616652 -275.47035)
			(xy 49.559599 -275.520272) (xy 49.497563 -275.563847) (xy 49.431246 -275.600582) (xy 49.3614 -275.630059)
			(xy 49.288817 -275.651945) (xy 49.214319 -275.665992) (xy 49.138749 -275.672041) (xy 49.062965 -275.670022)
			(xy 48.987825 -275.65996) (xy 48.91418 -275.641968) (xy 48.842864 -275.61625) (xy 48.774687 -275.583098)
			(xy 48.710419 -275.542886) (xy 48.65079 -275.496071) (xy 48.596474 -275.443183) (xy 48.548088 -275.384821)
			(xy 48.50618 -275.321646) (xy 48.471224 -275.254375) (xy 48.443617 -275.18377) (xy 48.423671 -275.110629)
			(xy 48.411612 -275.035784) (xy 48.407577 -274.96008) (xy 47.291498 -274.96008) (xy 47.290994 -274.997986)
			(xy 47.282935 -275.073367) (xy 47.26691 -275.147465) (xy 47.2431 -275.21944) (xy 47.211774 -275.288476)
			(xy 47.173287 -275.353791) (xy 47.128076 -275.414646) (xy 47.076652 -275.47035) (xy 47.019599 -275.520272)
			(xy 46.957563 -275.563847) (xy 46.891246 -275.600582) (xy 46.8214 -275.630059) (xy 46.748817 -275.651945)
			(xy 46.674319 -275.665992) (xy 46.598749 -275.672041) (xy 46.522965 -275.670022) (xy 46.447825 -275.65996)
			(xy 46.37418 -275.641968) (xy 46.302864 -275.61625) (xy 46.234687 -275.583098) (xy 46.170419 -275.542886)
			(xy 46.11079 -275.496071) (xy 46.056474 -275.443183) (xy 46.008088 -275.384821) (xy 45.96618 -275.321646)
			(xy 45.931224 -275.254375) (xy 45.903617 -275.18377) (xy 45.883671 -275.110629) (xy 45.871612 -275.035784)
			(xy 45.867577 -274.96008) (xy 44.751244 -274.96008) (xy 44.751244 -275.671788) (xy 43.328336 -275.671788)
			(xy 43.328336 -274.248372) (xy 43.055094 -274.248372) (xy 43.053462 -274.252742) (xy 43.004999 -274.359253)
			(xy 42.949245 -274.462135) (xy 42.886471 -274.560891) (xy 42.816981 -274.655042) (xy 42.741111 -274.744132)
			(xy 42.659229 -274.827729) (xy 42.571732 -274.90543) (xy 42.479042 -274.976857) (xy 42.381609 -275.041665)
			(xy 42.279905 -275.09954) (xy 42.174422 -275.150202) (xy 42.065671 -275.193404) (xy 41.954179 -275.228939)
			(xy 41.840485 -275.256634) (xy 41.725141 -275.276354) (xy 41.608704 -275.288005) (xy 41.491739 -275.29153)
			(xy 41.374812 -275.286912) (xy 41.258489 -275.274173) (xy 41.143334 -275.253375) (xy 41.029905 -275.224618)
			(xy 40.91875 -275.188042) (xy 40.810407 -275.143825) (xy 40.705403 -275.092179) (xy 40.604244 -275.033356)
			(xy 40.507421 -274.96764) (xy 40.415403 -274.895349) (xy 40.328636 -274.816834) (xy 40.247539 -274.732474)
			(xy 40.172506 -274.642679) (xy 40.103899 -274.547883) (xy 40.042051 -274.448544) (xy 39.987262 -274.345145)
			(xy 39.939796 -274.238186) (xy 39.899884 -274.128185) (xy 39.86772 -274.015674) (xy 39.843457 -273.901199)
			(xy 39.827215 -273.785313) (xy 39.819072 -273.668579) (xy 39.818564 -273.61007) (xy 36.596828 -273.61007)
			(xy 36.596828 -275.540724) (xy 42.182796 -281.126692) (xy 87.019128 -281.126692) (xy 87.023199 -281.07107)
			(xy 87.035325 -281.016633) (xy 87.055248 -280.964542) (xy 87.082544 -280.915907) (xy 87.11663 -280.871764)
			(xy 87.156779 -280.833055) (xy 87.202137 -280.800604) (xy 87.251737 -280.775103) (xy 87.304521 -280.757096)
			(xy 87.359364 -280.746966) (xy 87.415098 -280.744929) (xy 87.470535 -280.751029) (xy 87.524492 -280.765135)
			(xy 87.575821 -280.786947) (xy 87.623427 -280.816001) (xy 87.666295 -280.851676) (xy 87.703512 -280.893213)
			(xy 87.734285 -280.939726) (xy 87.757957 -280.990223) (xy 87.774025 -281.04363) (xy 87.782145 -281.098806)
			(xy 87.782654 -281.126692) (xy 87.782145 -281.154578) (xy 87.774025 -281.209754) (xy 87.757957 -281.263161)
			(xy 87.734285 -281.313658) (xy 87.703512 -281.360171) (xy 87.666295 -281.401708) (xy 87.623427 -281.437383)
			(xy 87.575821 -281.466437) (xy 87.524492 -281.488249) (xy 87.470535 -281.502355) (xy 87.415098 -281.508455)
			(xy 87.359364 -281.506418) (xy 87.304521 -281.496288) (xy 87.251737 -281.478281) (xy 87.202137 -281.45278)
			(xy 87.156779 -281.420329) (xy 87.11663 -281.38162) (xy 87.082544 -281.337477) (xy 87.055248 -281.288842)
			(xy 87.035325 -281.236751) (xy 87.023199 -281.182314) (xy 87.019128 -281.126692) (xy 42.182796 -281.126692)
			(xy 42.722292 -281.666188) (xy 42.722292 -281.837892) (xy 85.345268 -281.837892) (xy 85.349339 -281.78227)
			(xy 85.361465 -281.727833) (xy 85.381388 -281.675742) (xy 85.408684 -281.627107) (xy 85.44277 -281.582964)
			(xy 85.482919 -281.544255) (xy 85.528277 -281.511804) (xy 85.577877 -281.486303) (xy 85.630661 -281.468296)
			(xy 85.685504 -281.458166) (xy 85.741238 -281.456129) (xy 85.796675 -281.462229) (xy 85.850632 -281.476335)
			(xy 85.901961 -281.498147) (xy 85.949567 -281.527201) (xy 85.992435 -281.562876) (xy 86.029652 -281.604413)
			(xy 86.060425 -281.650926) (xy 86.084097 -281.701423) (xy 86.100165 -281.75483) (xy 86.108285 -281.810006)
			(xy 86.108794 -281.837892) (xy 86.108285 -281.865778) (xy 86.100165 -281.920954) (xy 86.084097 -281.974361)
			(xy 86.060425 -282.024858) (xy 86.029652 -282.071371) (xy 85.992435 -282.112908) (xy 85.949567 -282.148583)
			(xy 85.901961 -282.177637) (xy 85.850632 -282.199449) (xy 85.796675 -282.213555) (xy 85.741238 -282.219655)
			(xy 85.685504 -282.217618) (xy 85.630661 -282.207488) (xy 85.577877 -282.189481) (xy 85.528277 -282.16398)
			(xy 85.482919 -282.131529) (xy 85.44277 -282.09282) (xy 85.408684 -282.048677) (xy 85.381388 -282.000042)
			(xy 85.361465 -281.947951) (xy 85.349339 -281.893514) (xy 85.345268 -281.837892) (xy 42.722292 -281.837892)
			(xy 42.722292 -284.379416) (xy 51.251612 -284.379416) (xy 52.903628 -284.379416) (xy 52.903628 -284.75686)
			(xy 83.181188 -284.75686) (xy 83.185259 -284.701238) (xy 83.197385 -284.646801) (xy 83.217308 -284.59471)
			(xy 83.244604 -284.546075) (xy 83.27869 -284.501932) (xy 83.318839 -284.463223) (xy 83.364197 -284.430772)
			(xy 83.413797 -284.405271) (xy 83.466581 -284.387264) (xy 83.521424 -284.377134) (xy 83.577158 -284.375097)
			(xy 83.632595 -284.381197) (xy 83.686552 -284.395303) (xy 83.737881 -284.417115) (xy 83.785487 -284.446169)
			(xy 83.828355 -284.481844) (xy 83.865572 -284.523381) (xy 83.896345 -284.569894) (xy 83.920017 -284.620391)
			(xy 83.936085 -284.673798) (xy 83.944205 -284.728974) (xy 83.944714 -284.75686) (xy 83.944205 -284.784746)
			(xy 83.936085 -284.839922) (xy 83.920017 -284.893329) (xy 83.896345 -284.943826) (xy 83.865572 -284.990339)
			(xy 83.828355 -285.031876) (xy 83.785487 -285.067551) (xy 83.737881 -285.096605) (xy 83.686552 -285.118417)
			(xy 83.632595 -285.132523) (xy 83.577158 -285.138623) (xy 83.521424 -285.136586) (xy 83.466581 -285.126456)
			(xy 83.413797 -285.108449) (xy 83.364197 -285.082948) (xy 83.318839 -285.050497) (xy 83.27869 -285.011788)
			(xy 83.244604 -284.967645) (xy 83.217308 -284.91901) (xy 83.197385 -284.866919) (xy 83.185259 -284.812482)
			(xy 83.181188 -284.75686) (xy 52.903628 -284.75686) (xy 52.903628 -286.031432) (xy 51.251612 -286.031432)
			(xy 51.251612 -284.379416) (xy 42.722292 -284.379416) (xy 42.722292 -284.663388) (xy 42.139701 -285.245979)
			(xy 47.75199 -285.245979) (xy 47.75199 -285.164869) (xy 47.75994 -285.08415) (xy 47.775763 -285.004599)
			(xy 47.799308 -284.926983) (xy 47.830347 -284.852047) (xy 47.868582 -284.780515) (xy 47.913644 -284.713075)
			(xy 47.965099 -284.650376) (xy 48.022452 -284.593023) (xy 48.085151 -284.541568) (xy 48.152591 -284.496506)
			(xy 48.224123 -284.458271) (xy 48.299059 -284.427232) (xy 48.376675 -284.403687) (xy 48.456226 -284.387864)
			(xy 48.536945 -284.379914) (xy 48.618055 -284.379914) (xy 48.698774 -284.387864) (xy 48.778325 -284.403687)
			(xy 48.855941 -284.427232) (xy 48.930877 -284.458271) (xy 49.002409 -284.496506) (xy 49.069849 -284.541568)
			(xy 49.132548 -284.593023) (xy 49.189901 -284.650376) (xy 49.241356 -284.713075) (xy 49.286418 -284.780515)
			(xy 49.324653 -284.852047) (xy 49.355692 -284.926983) (xy 49.379237 -285.004599) (xy 49.39506 -285.08415)
			(xy 49.40301 -285.164869) (xy 49.403508 -285.205424) (xy 49.40301 -285.245979) (xy 49.39506 -285.326698)
			(xy 49.379237 -285.406249) (xy 49.355692 -285.483865) (xy 49.324653 -285.558801) (xy 49.286418 -285.630333)
			(xy 49.241356 -285.697773) (xy 49.189901 -285.760472) (xy 49.132548 -285.817825) (xy 49.069849 -285.86928)
			(xy 49.002409 -285.914342) (xy 48.930877 -285.952577) (xy 48.855941 -285.983616) (xy 48.778325 -286.007161)
			(xy 48.698774 -286.022984) (xy 48.618055 -286.030934) (xy 48.536945 -286.030934) (xy 48.456226 -286.022984)
			(xy 48.376675 -286.007161) (xy 48.299059 -285.983616) (xy 48.224123 -285.952577) (xy 48.152591 -285.914342)
			(xy 48.085151 -285.86928) (xy 48.022452 -285.817825) (xy 47.965099 -285.760472) (xy 47.913644 -285.697773)
			(xy 47.868582 -285.630333) (xy 47.830347 -285.558801) (xy 47.799308 -285.483865) (xy 47.775763 -285.406249)
			(xy 47.75994 -285.326698) (xy 47.75199 -285.245979) (xy 42.139701 -285.245979) (xy 40.976042 -286.409638)
			(xy 40.954113 -286.410096) (xy 40.910907 -286.41762) (xy 40.869634 -286.432452) (xy 40.831521 -286.454151)
			(xy 40.7977 -286.482072) (xy 40.769176 -286.515386) (xy 40.746797 -286.553104) (xy 40.731227 -286.594104)
			(xy 40.72293 -286.637169) (xy 40.72215 -286.681019) (xy 40.72509 -286.702754) (xy 40.729339 -286.732917)
			(xy 40.73112 -286.793806) (xy 40.728646 -286.824166) (xy 40.725232 -286.854251) (xy 40.71186 -286.913306)
			(xy 40.69122 -286.970229) (xy 40.677846 -286.997394) (xy 40.664023 -287.02342) (xy 40.630977 -287.072216)
			(xy 40.592241 -287.116629) (xy 40.548389 -287.155999) (xy 40.500073 -287.189743) (xy 40.448011 -287.217357)
			(xy 40.392976 -287.238433) (xy 40.335786 -287.252656) (xy 40.27729 -287.259817) (xy 40.247824 -287.260284)
			(xy 40.20058 -287.260284) (xy 40.178348 -287.262346) (xy 40.135059 -287.27326) (xy 40.094337 -287.291557)
			(xy 40.05743 -287.316676) (xy 40.025469 -287.347847) (xy 39.999436 -287.384115) (xy 39.980127 -287.424368)
			(xy 39.968135 -287.467371) (xy 39.963827 -287.511807) (xy 39.965122 -287.534096) (xy 39.966908 -287.562157)
			(xy 39.965022 -287.618356) (xy 39.956954 -287.674004) (xy 39.942802 -287.728425) (xy 39.933118 -287.754822)
			(xy 39.925774 -287.77513) (xy 39.917314 -287.817475) (xy 39.916132 -287.86064) (xy 39.922262 -287.903385)
			(xy 39.935528 -287.944478) (xy 39.955548 -287.982739) (xy 39.981747 -288.017065) (xy 40.013369 -288.046471)
			(xy 40.049507 -288.070109) (xy 40.089119 -288.087299) (xy 40.131067 -288.097548) (xy 40.152574 -288.0995)
			(xy 40.483028 -288.0995) (xy 40.514644 -288.100019) (xy 40.577334 -288.108276) (xy 40.638411 -288.124644)
			(xy 40.696828 -288.148844) (xy 40.708588 -288.155634) (xy 71.362824 -288.155634) (xy 71.362824 -287.210754)
			(xy 71.36352 -287.174688) (xy 71.373839 -287.103297) (xy 71.383398 -287.068514) (xy 71.388224 -287.050988)
			(xy 71.388224 -286.6771) (xy 72.35444 -286.6771) (xy 72.35444 -287.050988) (xy 72.359266 -287.068514)
			(xy 72.368805 -287.103301) (xy 72.379134 -287.17469) (xy 72.37984 -287.210754) (xy 72.37984 -287.311084)
			(xy 72.691244 -287.311084) (xy 72.691244 -286.366204) (xy 72.691736 -286.333468) (xy 72.700177 -286.268542)
			(xy 72.716882 -286.205236) (xy 72.741575 -286.144599) (xy 72.773846 -286.087632) (xy 72.793098 -286.06115)
			(xy 72.818244 -286.027368) (xy 72.818244 -286.010096) (xy 72.833738 -286.010096) (xy 72.869552 -285.97987)
			(xy 72.894729 -285.959017) (xy 72.949461 -285.923266) (xy 73.008326 -285.894827) (xy 73.070351 -285.874172)
			(xy 73.134513 -285.861641) (xy 73.199752 -285.857441) (xy 73.264991 -285.861641) (xy 73.329153 -285.874172)
			(xy 73.391178 -285.894827) (xy 73.450043 -285.923266) (xy 73.504775 -285.959017) (xy 73.529952 -285.97987)
			(xy 73.565766 -286.010096) (xy 73.58126 -286.010096) (xy 73.58126 -286.027368) (xy 73.606406 -286.06115)
			(xy 73.62109 -286.081284) (xy 73.646922 -286.123902) (xy 73.657968 -286.14624) (xy 73.665289 -286.160334)
			(xy 73.685691 -286.184661) (xy 73.711466 -286.203199) (xy 73.741019 -286.214802) (xy 73.772522 -286.218751)
			(xy 73.804025 -286.214802) (xy 73.833578 -286.203199) (xy 73.859353 -286.184661) (xy 73.879755 -286.160334)
			(xy 73.887076 -286.14624) (xy 73.898107 -286.123894) (xy 73.923934 -286.08127) (xy 73.938638 -286.06115)
			(xy 73.963784 -286.027368) (xy 73.963784 -286.010096) (xy 73.979278 -286.010096) (xy 74.015092 -285.97987)
			(xy 74.040269 -285.959017) (xy 74.095001 -285.923266) (xy 74.153866 -285.894827) (xy 74.215891 -285.874172)
			(xy 74.280053 -285.861641) (xy 74.345292 -285.857441) (xy 74.410531 -285.861641) (xy 74.474693 -285.874172)
			(xy 74.536718 -285.894827) (xy 74.595583 -285.923266) (xy 74.650315 -285.959017) (xy 74.675492 -285.97987)
			(xy 74.711306 -286.010096) (xy 74.7268 -286.010096) (xy 74.7268 -286.027368) (xy 74.751946 -286.06115)
			(xy 74.771174 -286.087647) (xy 74.776739 -286.097472) (xy 82.563714 -286.097472) (xy 82.567785 -286.04185)
			(xy 82.579911 -285.987413) (xy 82.599834 -285.935322) (xy 82.62713 -285.886687) (xy 82.661216 -285.842544)
			(xy 82.701365 -285.803835) (xy 82.746723 -285.771384) (xy 82.796323 -285.745883) (xy 82.849107 -285.727876)
			(xy 82.90395 -285.717746) (xy 82.959684 -285.715709) (xy 83.015121 -285.721809) (xy 83.069078 -285.735915)
			(xy 83.120407 -285.757727) (xy 83.168013 -285.786781) (xy 83.210881 -285.822456) (xy 83.248098 -285.863993)
			(xy 83.278871 -285.910506) (xy 83.302543 -285.961003) (xy 83.318611 -286.01441) (xy 83.326731 -286.069586)
			(xy 83.32724 -286.097472) (xy 83.326731 -286.125358) (xy 83.318611 -286.180534) (xy 83.302543 -286.233941)
			(xy 83.278871 -286.284438) (xy 83.248098 -286.330951) (xy 83.210881 -286.372488) (xy 83.168013 -286.408163)
			(xy 83.120407 -286.437217) (xy 83.069078 -286.459029) (xy 83.015121 -286.473135) (xy 82.959684 -286.479235)
			(xy 82.90395 -286.477198) (xy 82.849107 -286.467068) (xy 82.796323 -286.449061) (xy 82.746723 -286.42356)
			(xy 82.701365 -286.391109) (xy 82.661216 -286.3524) (xy 82.62713 -286.308257) (xy 82.599834 -286.259622)
			(xy 82.579911 -286.207531) (xy 82.567785 -286.153094) (xy 82.563714 -286.097472) (xy 74.776739 -286.097472)
			(xy 74.803441 -286.144612) (xy 74.82813 -286.205246) (xy 74.844833 -286.268548) (xy 74.853273 -286.33347)
			(xy 74.8538 -286.366204) (xy 74.8538 -286.71012) (xy 86.39887 -286.71012) (xy 86.402874 -286.510022)
			(xy 86.414881 -286.310244) (xy 86.434872 -286.111107) (xy 86.462814 -285.912929) (xy 86.498662 -285.716027)
			(xy 86.54236 -285.520718) (xy 86.593837 -285.327313) (xy 86.653011 -285.136123) (xy 86.719787 -284.947453)
			(xy 86.794059 -284.761606) (xy 86.875706 -284.578879) (xy 86.964599 -284.399566) (xy 87.060595 -284.223952)
			(xy 87.16354 -284.05232) (xy 87.27327 -283.884944) (xy 87.389608 -283.722093) (xy 87.512369 -283.564026)
			(xy 87.641356 -283.410998) (xy 87.776363 -283.263253) (xy 87.917172 -283.121027) (xy 88.063559 -282.98455)
			(xy 88.215289 -282.854038) (xy 88.37212 -282.729702) (xy 88.533799 -282.61174) (xy 88.700069 -282.500341)
			(xy 88.870662 -282.395684) (xy 89.045306 -282.297936) (xy 89.223722 -282.207253) (xy 89.405622 -282.123782)
			(xy 89.590717 -282.047655) (xy 89.778709 -281.978995) (xy 89.969298 -281.917911) (xy 90.162178 -281.864501)
			(xy 90.35704 -281.818852) (xy 90.553573 -281.781035) (xy 90.751462 -281.751111) (xy 90.950389 -281.729129)
			(xy 91.150037 -281.715124) (xy 91.350085 -281.709118) (xy 91.550213 -281.71112) (xy 91.750101 -281.721128)
			(xy 91.949428 -281.739125) (xy 92.147876 -281.765083) (xy 92.345126 -281.79896) (xy 92.540863 -281.840702)
			(xy 92.734773 -281.890241) (xy 92.926546 -281.947499) (xy 93.115875 -282.012384) (xy 93.302455 -282.084792)
			(xy 93.48599 -282.164608) (xy 93.666184 -282.251702) (xy 93.842749 -282.345936) (xy 94.015402 -282.447159)
			(xy 94.183867 -282.555209) (xy 94.347875 -282.669912) (xy 94.507162 -282.791086) (xy 94.661473 -282.918535)
			(xy 94.810561 -283.052056) (xy 94.954188 -283.191436) (xy 95.092124 -283.33645) (xy 95.224147 -283.486867)
			(xy 95.350046 -283.642445) (xy 95.46962 -283.802937) (xy 95.582676 -283.968083) (xy 95.689035 -284.137621)
			(xy 95.788526 -284.311279) (xy 95.880989 -284.488778) (xy 95.966276 -284.669834) (xy 96.044251 -284.854158)
			(xy 96.114788 -285.041454) (xy 96.177776 -285.231422) (xy 96.233113 -285.423758) (xy 96.28071 -285.618154)
			(xy 96.320491 -285.814299) (xy 96.352393 -286.011878) (xy 96.376364 -286.210575) (xy 96.392366 -286.410073)
			(xy 96.400373 -286.610051) (xy 96.400874 -286.71012) (xy 96.400373 -286.810189) (xy 96.392366 -287.010167)
			(xy 96.376364 -287.209665) (xy 96.352393 -287.408362) (xy 96.320491 -287.605941) (xy 96.28071 -287.802086)
			(xy 96.233113 -287.996482) (xy 96.177776 -288.188818) (xy 96.114788 -288.378786) (xy 96.044251 -288.566082)
			(xy 95.966276 -288.750406) (xy 95.880989 -288.931462) (xy 95.788526 -289.108961) (xy 95.689035 -289.282619)
			(xy 95.582676 -289.452157) (xy 95.46962 -289.617303) (xy 95.350046 -289.777795) (xy 95.224147 -289.933373)
			(xy 95.092124 -290.08379) (xy 94.954188 -290.228804) (xy 94.810561 -290.368184) (xy 94.661473 -290.501705)
			(xy 94.507162 -290.629154) (xy 94.347875 -290.750328) (xy 94.183867 -290.865031) (xy 94.015402 -290.973081)
			(xy 93.842749 -291.074304) (xy 93.666184 -291.168538) (xy 93.48599 -291.255632) (xy 93.302455 -291.335448)
			(xy 93.115875 -291.407856) (xy 92.926546 -291.472741) (xy 92.734773 -291.529999) (xy 92.540863 -291.579538)
			(xy 92.345126 -291.62128) (xy 92.147876 -291.655157) (xy 91.949428 -291.681115) (xy 91.750101 -291.699112)
			(xy 91.550213 -291.70912) (xy 91.350085 -291.711122) (xy 91.150037 -291.705116) (xy 90.950389 -291.691111)
			(xy 90.751462 -291.669129) (xy 90.553573 -291.639205) (xy 90.35704 -291.601388) (xy 90.162178 -291.555739)
			(xy 89.969298 -291.502329) (xy 89.778709 -291.441245) (xy 89.590717 -291.372585) (xy 89.405622 -291.296458)
			(xy 89.223722 -291.212987) (xy 89.045306 -291.122304) (xy 88.870662 -291.024556) (xy 88.700069 -290.919899)
			(xy 88.533799 -290.8085) (xy 88.37212 -290.690538) (xy 88.215289 -290.566202) (xy 88.063559 -290.43569)
			(xy 87.917172 -290.299213) (xy 87.776363 -290.156987) (xy 87.641356 -290.009242) (xy 87.512369 -289.856214)
			(xy 87.389608 -289.698147) (xy 87.27327 -289.535296) (xy 87.16354 -289.36792) (xy 87.060595 -289.196288)
			(xy 86.964599 -289.020674) (xy 86.875706 -288.841361) (xy 86.794059 -288.658634) (xy 86.719787 -288.472787)
			(xy 86.653011 -288.284117) (xy 86.593837 -288.092927) (xy 86.54236 -287.899522) (xy 86.498662 -287.704213)
			(xy 86.462814 -287.507311) (xy 86.434872 -287.309133) (xy 86.414881 -287.109996) (xy 86.402874 -286.910218)
			(xy 86.39887 -286.71012) (xy 74.8538 -286.71012) (xy 74.8538 -287.311084) (xy 74.853295 -287.343487)
			(xy 74.84505 -287.407768) (xy 74.828705 -287.47048) (xy 74.804525 -287.530607) (xy 74.772901 -287.587174)
			(xy 74.734346 -287.639265) (xy 74.689485 -287.686035) (xy 74.639045 -287.726726) (xy 74.583844 -287.760679)
			(xy 74.524776 -287.787343) (xy 74.462799 -287.806286) (xy 74.398918 -287.817201) (xy 74.334168 -287.819911)
			(xy 74.269598 -287.814372) (xy 74.206255 -287.800674) (xy 74.145166 -287.779039) (xy 74.087321 -287.749818)
			(xy 74.033657 -287.713484) (xy 73.985045 -287.670626) (xy 73.963276 -287.646618) (xy 73.948694 -287.630682)
			(xy 73.915105 -287.603529) (xy 73.877408 -287.582448) (xy 73.836687 -287.568048) (xy 73.794118 -287.560742)
			(xy 73.750926 -287.560742) (xy 73.708357 -287.568048) (xy 73.667636 -287.582448) (xy 73.629939 -287.603529)
			(xy 73.59635 -287.630682) (xy 73.581768 -287.646618) (xy 73.559987 -287.670618) (xy 73.51138 -287.713487)
			(xy 73.457719 -287.749833) (xy 73.399875 -287.779064) (xy 73.338784 -287.800708) (xy 73.275439 -287.814413)
			(xy 73.210866 -287.819957) (xy 73.146111 -287.817251) (xy 73.082226 -287.806337) (xy 73.020245 -287.787394)
			(xy 72.961174 -287.760728) (xy 72.90597 -287.726772) (xy 72.855529 -287.686076) (xy 72.810669 -287.639299)
			(xy 72.772116 -287.587202) (xy 72.740497 -287.530627) (xy 72.716323 -287.470494) (xy 72.699986 -287.407775)
			(xy 72.691752 -287.34349) (xy 72.691244 -287.311084) (xy 72.37984 -287.311084) (xy 72.37984 -288.155634)
			(xy 72.379338 -288.187595) (xy 72.371327 -288.251013) (xy 72.35543 -288.312927) (xy 72.331898 -288.37236)
			(xy 72.301104 -288.428375) (xy 72.263531 -288.48009) (xy 72.219774 -288.526687) (xy 72.170521 -288.567432)
			(xy 72.11655 -288.601683) (xy 72.058711 -288.6289) (xy 71.997918 -288.648653) (xy 71.935128 -288.660631)
			(xy 71.871332 -288.664645) (xy 71.807536 -288.660631) (xy 71.744746 -288.648653) (xy 71.683953 -288.6289)
			(xy 71.626114 -288.601683) (xy 71.572143 -288.567432) (xy 71.52289 -288.526687) (xy 71.479133 -288.48009)
			(xy 71.44156 -288.428375) (xy 71.410766 -288.37236) (xy 71.387234 -288.312927) (xy 71.371337 -288.251013)
			(xy 71.363326 -288.187595) (xy 71.362824 -288.155634) (xy 40.708588 -288.155634) (xy 40.751587 -288.180462)
			(xy 40.801751 -288.218957) (xy 40.846461 -288.26367) (xy 40.884953 -288.313836) (xy 40.916568 -288.368597)
			(xy 40.940765 -288.427016) (xy 40.95713 -288.488093) (xy 40.965383 -288.550784) (xy 40.965383 -288.614016)
			(xy 40.95713 -288.676707) (xy 40.940765 -288.737784) (xy 40.916568 -288.796203) (xy 40.884953 -288.850964)
			(xy 40.846461 -288.90113) (xy 40.801751 -288.945843) (xy 40.751587 -288.984338) (xy 40.696828 -289.015956)
			(xy 40.638411 -289.040156) (xy 40.577334 -289.056524) (xy 40.514644 -289.064781) (xy 40.483028 -289.065208)
			(xy 39.441882 -289.065208) (xy 39.110158 -288.733484) (xy 39.055548 -288.733484) (xy 39.055548 -288.67608)
			(xy 39.034466 -288.644076) (xy 39.018046 -288.618448) (xy 38.991078 -288.56388) (xy 38.971181 -288.506356)
			(xy 38.958669 -288.446787) (xy 38.955726 -288.416492) (xy 38.954202 -288.391346) (xy 38.954964 -288.347912)
			(xy 38.955908 -288.325828) (xy 38.951072 -288.281895) (xy 38.938707 -288.239462) (xy 38.919187 -288.199808)
			(xy 38.8931 -288.16413) (xy 38.861233 -288.133504) (xy 38.824547 -288.108853) (xy 38.78415 -288.090922)
			(xy 38.741259 -288.080252) (xy 38.719252 -288.078164) (xy 36.397184 -288.078164) (xy 36.382357 -288.078606)
			(xy 36.353505 -288.085464) (xy 36.327008 -288.098783) (xy 36.304293 -288.117848) (xy 36.295076 -288.129472)
			(xy 36.268779 -288.164147) (xy 36.21073 -288.228992) (xy 36.146937 -288.288195) (xy 36.077945 -288.34125)
			(xy 36.004346 -288.387701) (xy 35.926768 -288.427151) (xy 35.845877 -288.459263) (xy 35.762364 -288.483762)
			(xy 35.676944 -288.500438) (xy 35.590349 -288.509148) (xy 35.50332 -288.509818) (xy 35.416601 -288.502442)
			(xy 35.330934 -288.487083) (xy 35.247054 -288.463873) (xy 35.165678 -288.433011) (xy 35.087502 -288.394759)
			(xy 35.013196 -288.349447) (xy 34.943396 -288.297461) (xy 34.878699 -288.239247) (xy 34.819659 -288.175303)
			(xy 34.76678 -288.106177) (xy 34.720517 -288.032459) (xy 34.700464 -287.993836) (xy 34.681962 -287.956241)
			(xy 34.650929 -287.8784) (xy 34.638488 -287.838388) (xy 34.626296 -287.79343) (xy 34.625788 -287.791398)
			(xy 34.625534 -287.790128) (xy 34.62528 -287.789112) (xy 34.625026 -287.787842) (xy 34.620529 -287.771464)
			(xy 34.604158 -287.74172) (xy 34.580525 -287.717343) (xy 34.551303 -287.700058) (xy 34.518558 -287.691087)
			(xy 34.501582 -287.69056) (xy 31.497778 -287.69056) (xy 31.480775 -287.691092) (xy 31.447975 -287.700065)
			(xy 31.418715 -287.717393) (xy 31.39508 -287.741841) (xy 31.378751 -287.77167) (xy 31.374334 -287.788096)
			(xy 31.363737 -287.83039) (xy 31.335738 -287.912969) (xy 31.300213 -287.992601) (xy 31.257469 -288.068602)
			(xy 31.207872 -288.140319) (xy 31.151848 -288.207136) (xy 31.089878 -288.26848) (xy 31.022496 -288.323823)
			(xy 30.950279 -288.372689) (xy 30.873848 -288.41466) (xy 30.793859 -288.449375) (xy 30.711001 -288.476535)
			(xy 30.625983 -288.495907) (xy 30.539537 -288.507324) (xy 30.452406 -288.51069) (xy 30.365337 -288.505974)
			(xy 30.279078 -288.493217) (xy 30.194371 -288.472529) (xy 30.111944 -288.444088) (xy 30.032503 -288.408137)
			(xy 29.994352 -288.387028) (xy 29.9749 -288.376527) (xy 29.933268 -288.361677) (xy 29.889696 -288.354253)
			(xy 29.845495 -288.35448) (xy 29.802001 -288.362352) (xy 29.760525 -288.37763) (xy 29.722318 -288.399855)
			(xy 29.688532 -288.428354) (xy 29.660187 -288.46227) (xy 29.638137 -288.500578) (xy 29.623049 -288.542124)
			(xy 29.615376 -288.585654) (xy 29.614876 -288.607754) (xy 29.614876 -289.072066) (xy 29.61535 -289.094174)
			(xy 29.623 -289.137722) (xy 29.638074 -289.179288) (xy 29.660116 -289.217616) (xy 29.688462 -289.25155)
			(xy 29.722255 -289.280063) (xy 29.760474 -289.302294) (xy 29.801966 -289.317573) (xy 29.845475 -289.325438)
			(xy 29.88969 -289.32565) (xy 29.933273 -289.318204) (xy 29.974909 -289.303324) (xy 29.994352 -289.292792)
			(xy 30.032527 -289.271621) (xy 30.112065 -289.235636) (xy 30.194595 -289.207178) (xy 30.279409 -289.186492)
			(xy 30.365774 -289.173756) (xy 30.452948 -289.16908) (xy 30.54018 -289.172504) (xy 30.626719 -289.183999)
			(xy 30.711821 -289.203466) (xy 30.794751 -289.230737) (xy 30.874797 -289.265577) (xy 30.951269 -289.307686)
			(xy 31.023509 -289.356702) (xy 31.090895 -289.412203) (xy 31.152846 -289.473711) (xy 31.208829 -289.540696)
			(xy 31.258363 -289.612582) (xy 31.301021 -289.68875) (xy 31.336435 -289.768543) (xy 31.3643 -289.851276)
			(xy 31.384377 -289.936235) (xy 31.396494 -290.02269) (xy 31.400544 -290.109895) (xy 31.398525 -290.15336)
			(xy 34.599874 -290.15336) (xy 34.599874 -290.06646) (xy 34.607892 -289.979931) (xy 34.62386 -289.894511)
			(xy 34.647641 -289.810929) (xy 34.679033 -289.729897) (xy 34.717767 -289.652108) (xy 34.763514 -289.578224)
			(xy 34.815883 -289.508877) (xy 34.874427 -289.444657) (xy 34.938647 -289.386113) (xy 35.007994 -289.333744)
			(xy 35.081878 -289.287997) (xy 35.159667 -289.249263) (xy 35.240699 -289.217871) (xy 35.324281 -289.19409)
			(xy 35.409701 -289.178122) (xy 35.49623 -289.170104) (xy 35.58313 -289.170104) (xy 35.669659 -289.178122)
			(xy 35.755079 -289.19409) (xy 35.838661 -289.217871) (xy 35.919693 -289.249263) (xy 35.997482 -289.287997)
			(xy 36.071366 -289.333744) (xy 36.140713 -289.386113) (xy 36.204933 -289.444657) (xy 36.263477 -289.508877)
			(xy 36.315846 -289.578224) (xy 36.361593 -289.652108) (xy 36.400327 -289.729897) (xy 36.431719 -289.810929)
			(xy 36.4555 -289.894511) (xy 36.471468 -289.979931) (xy 36.479486 -290.06646) (xy 36.479988 -290.10991)
			(xy 36.479486 -290.15336) (xy 36.471468 -290.239889) (xy 36.4555 -290.325309) (xy 36.431719 -290.408891)
			(xy 36.400327 -290.489923) (xy 36.361593 -290.567712) (xy 36.315846 -290.641596) (xy 36.263477 -290.710943)
			(xy 36.204933 -290.775163) (xy 36.140713 -290.833707) (xy 36.071366 -290.886076) (xy 35.997482 -290.931823)
			(xy 35.919693 -290.970557) (xy 35.838661 -291.001949) (xy 35.755079 -291.02573) (xy 35.669659 -291.041698)
			(xy 35.58313 -291.049716) (xy 35.49623 -291.049716) (xy 35.409701 -291.041698) (xy 35.324281 -291.02573)
			(xy 35.240699 -291.001949) (xy 35.159667 -290.970557) (xy 35.081878 -290.931823) (xy 35.007994 -290.886076)
			(xy 34.938647 -290.833707) (xy 34.874427 -290.775163) (xy 34.815883 -290.710943) (xy 34.763514 -290.641596)
			(xy 34.717767 -290.567712) (xy 34.679033 -290.489923) (xy 34.647641 -290.408891) (xy 34.62386 -290.325309)
			(xy 34.607892 -290.239889) (xy 34.599874 -290.15336) (xy 31.398525 -290.15336) (xy 31.396494 -290.1971)
			(xy 31.384379 -290.283555) (xy 31.364303 -290.368514) (xy 31.336438 -290.451247) (xy 31.301025 -290.531041)
			(xy 31.258368 -290.60721) (xy 31.208835 -290.679096) (xy 31.152853 -290.746082) (xy 31.090902 -290.80759)
			(xy 31.023517 -290.863092) (xy 30.951278 -290.912109) (xy 30.874806 -290.954219) (xy 30.79476 -290.98906)
			(xy 30.71183 -291.016332) (xy 30.626729 -291.035799) (xy 30.54019 -291.047295) (xy 30.452958 -291.05072)
			(xy 30.365784 -291.046045) (xy 30.279418 -291.03331) (xy 30.194605 -291.012625) (xy 30.112074 -290.984168)
			(xy 30.032536 -290.948183) (xy 29.994352 -290.927028) (xy 29.9749 -290.916527) (xy 29.933268 -290.901677)
			(xy 29.889696 -290.894253) (xy 29.845495 -290.89448) (xy 29.802001 -290.902352) (xy 29.760525 -290.91763)
			(xy 29.722318 -290.939855) (xy 29.688532 -290.968354) (xy 29.660187 -291.00227) (xy 29.638137 -291.040578)
			(xy 29.623049 -291.082124) (xy 29.615376 -291.125654) (xy 29.614876 -291.147754) (xy 29.614876 -291.612066)
			(xy 29.61535 -291.634174) (xy 29.623 -291.677722) (xy 29.638074 -291.719288) (xy 29.660116 -291.757616)
			(xy 29.688462 -291.79155) (xy 29.722255 -291.820063) (xy 29.760474 -291.842294) (xy 29.801966 -291.857573)
			(xy 29.845475 -291.865438) (xy 29.88969 -291.86565) (xy 29.933273 -291.858204) (xy 29.974909 -291.843324)
			(xy 29.994352 -291.832792) (xy 30.032527 -291.811621) (xy 30.112065 -291.775636) (xy 30.194595 -291.747178)
			(xy 30.279409 -291.726492) (xy 30.365774 -291.713756) (xy 30.452948 -291.70908) (xy 30.54018 -291.712504)
			(xy 30.626719 -291.723999) (xy 30.711821 -291.743466) (xy 30.794751 -291.770737) (xy 30.874797 -291.805577)
			(xy 30.951269 -291.847686) (xy 31.023509 -291.896702) (xy 31.090895 -291.952203) (xy 31.152846 -292.013711)
			(xy 31.208829 -292.080696) (xy 31.258363 -292.152582) (xy 31.301021 -292.22875) (xy 31.336435 -292.308543)
			(xy 31.3643 -292.391276) (xy 31.384377 -292.476235) (xy 31.396494 -292.56269) (xy 31.400544 -292.649895)
			(xy 31.398525 -292.69336) (xy 34.599874 -292.69336) (xy 34.599874 -292.60646) (xy 34.607892 -292.519931)
			(xy 34.62386 -292.434511) (xy 34.647641 -292.350929) (xy 34.679033 -292.269897) (xy 34.717767 -292.192108)
			(xy 34.763514 -292.118224) (xy 34.815883 -292.048877) (xy 34.874427 -291.984657) (xy 34.938647 -291.926113)
			(xy 35.007994 -291.873744) (xy 35.081878 -291.827997) (xy 35.159667 -291.789263) (xy 35.240699 -291.757871)
			(xy 35.324281 -291.73409) (xy 35.409701 -291.718122) (xy 35.49623 -291.710104) (xy 35.58313 -291.710104)
			(xy 35.669659 -291.718122) (xy 35.755079 -291.73409) (xy 35.838661 -291.757871) (xy 35.919693 -291.789263)
			(xy 35.997482 -291.827997) (xy 36.071366 -291.873744) (xy 36.140713 -291.926113) (xy 36.204933 -291.984657)
			(xy 36.263477 -292.048877) (xy 36.315846 -292.118224) (xy 36.361593 -292.192108) (xy 36.400327 -292.269897)
			(xy 36.431719 -292.350929) (xy 36.4555 -292.434511) (xy 36.471468 -292.519931) (xy 36.479486 -292.60646)
			(xy 36.479988 -292.64991) (xy 36.479486 -292.69336) (xy 36.471468 -292.779889) (xy 36.4555 -292.865309)
			(xy 36.431719 -292.948891) (xy 36.400327 -293.029923) (xy 36.361593 -293.107712) (xy 36.315846 -293.181596)
			(xy 36.263477 -293.250943) (xy 36.204933 -293.315163) (xy 36.140713 -293.373707) (xy 36.071366 -293.426076)
			(xy 35.997482 -293.471823) (xy 35.919693 -293.510557) (xy 35.838661 -293.541949) (xy 35.755079 -293.56573)
			(xy 35.669659 -293.581698) (xy 35.58313 -293.589716) (xy 35.49623 -293.589716) (xy 35.409701 -293.581698)
			(xy 35.324281 -293.56573) (xy 35.240699 -293.541949) (xy 35.159667 -293.510557) (xy 35.081878 -293.471823)
			(xy 35.007994 -293.426076) (xy 34.938647 -293.373707) (xy 34.874427 -293.315163) (xy 34.815883 -293.250943)
			(xy 34.763514 -293.181596) (xy 34.717767 -293.107712) (xy 34.679033 -293.029923) (xy 34.647641 -292.948891)
			(xy 34.62386 -292.865309) (xy 34.607892 -292.779889) (xy 34.599874 -292.69336) (xy 31.398525 -292.69336)
			(xy 31.396494 -292.7371) (xy 31.384379 -292.823555) (xy 31.364303 -292.908514) (xy 31.336438 -292.991247)
			(xy 31.301025 -293.071041) (xy 31.258368 -293.14721) (xy 31.208835 -293.219096) (xy 31.152853 -293.286082)
			(xy 31.090902 -293.34759) (xy 31.023517 -293.403092) (xy 30.951278 -293.452109) (xy 30.874806 -293.494219)
			(xy 30.79476 -293.52906) (xy 30.71183 -293.556332) (xy 30.626729 -293.575799) (xy 30.54019 -293.587295)
			(xy 30.452958 -293.59072) (xy 30.365784 -293.586045) (xy 30.279418 -293.57331) (xy 30.194605 -293.552625)
			(xy 30.112074 -293.524168) (xy 30.032536 -293.488183) (xy 29.994352 -293.467028) (xy 29.9749 -293.456527)
			(xy 29.933268 -293.441677) (xy 29.889696 -293.434253) (xy 29.845495 -293.43448) (xy 29.802001 -293.442352)
			(xy 29.760525 -293.45763) (xy 29.722318 -293.479855) (xy 29.688532 -293.508354) (xy 29.660187 -293.54227)
			(xy 29.638137 -293.580578) (xy 29.623049 -293.622124) (xy 29.615376 -293.665654) (xy 29.614876 -293.687754)
			(xy 29.614876 -294.152066) (xy 29.61535 -294.174174) (xy 29.623 -294.217722) (xy 29.638074 -294.259288)
			(xy 29.660116 -294.297616) (xy 29.688462 -294.33155) (xy 29.722255 -294.360063) (xy 29.760474 -294.382294)
			(xy 29.801966 -294.397573) (xy 29.845475 -294.405438) (xy 29.88969 -294.40565) (xy 29.933273 -294.398204)
			(xy 29.974909 -294.383324) (xy 29.994352 -294.372792) (xy 30.032527 -294.351621) (xy 30.112065 -294.315636)
			(xy 30.194595 -294.287178) (xy 30.279409 -294.266492) (xy 30.365774 -294.253756) (xy 30.452948 -294.24908)
			(xy 30.54018 -294.252504) (xy 30.626719 -294.263999) (xy 30.711821 -294.283466) (xy 30.794751 -294.310737)
			(xy 30.874797 -294.345577) (xy 30.951269 -294.387686) (xy 31.023509 -294.436702) (xy 31.090895 -294.492203)
			(xy 31.152846 -294.553711) (xy 31.208829 -294.620696) (xy 31.258363 -294.692582) (xy 31.301021 -294.76875)
			(xy 31.336435 -294.848543) (xy 31.3643 -294.931276) (xy 31.384377 -295.016235) (xy 31.396494 -295.10269)
			(xy 31.400544 -295.189895) (xy 31.398525 -295.23336) (xy 34.599874 -295.23336) (xy 34.599874 -295.14646)
			(xy 34.607892 -295.059931) (xy 34.62386 -294.974511) (xy 34.647641 -294.890929) (xy 34.679033 -294.809897)
			(xy 34.717767 -294.732108) (xy 34.763514 -294.658224) (xy 34.815883 -294.588877) (xy 34.874427 -294.524657)
			(xy 34.938647 -294.466113) (xy 35.007994 -294.413744) (xy 35.081878 -294.367997) (xy 35.159667 -294.329263)
			(xy 35.240699 -294.297871) (xy 35.324281 -294.27409) (xy 35.409701 -294.258122) (xy 35.49623 -294.250104)
			(xy 35.58313 -294.250104) (xy 35.669659 -294.258122) (xy 35.755079 -294.27409) (xy 35.838661 -294.297871)
			(xy 35.919693 -294.329263) (xy 35.997482 -294.367997) (xy 36.071366 -294.413744) (xy 36.140713 -294.466113)
			(xy 36.204933 -294.524657) (xy 36.263477 -294.588877) (xy 36.315846 -294.658224) (xy 36.361593 -294.732108)
			(xy 36.400327 -294.809897) (xy 36.431719 -294.890929) (xy 36.4555 -294.974511) (xy 36.471468 -295.059931)
			(xy 36.479486 -295.14646) (xy 36.479988 -295.18991) (xy 36.479486 -295.23336) (xy 36.478201 -295.247231)
			(xy 78.899273 -295.247231) (xy 78.899273 -295.183969) (xy 78.90753 -295.121247) (xy 78.923903 -295.06014)
			(xy 78.948111 -295.001693) (xy 78.979741 -294.946905) (xy 79.018251 -294.896714) (xy 79.062982 -294.851978)
			(xy 79.11317 -294.813464) (xy 79.167955 -294.781829) (xy 79.2264 -294.757616) (xy 79.287506 -294.741238)
			(xy 79.350227 -294.732976) (xy 79.381858 -294.732456) (xy 80.532732 -294.732456) (xy 80.561 -294.732876)
			(xy 80.617144 -294.739529) (xy 80.672129 -294.752683) (xy 80.725205 -294.772158) (xy 80.775649 -294.797689)
			(xy 80.799432 -294.812974) (xy 80.831436 -294.834056) (xy 80.99425 -294.834056) (xy 81.028032 -294.808656)
			(xy 81.054514 -294.789466) (xy 81.111449 -294.757288) (xy 81.172036 -294.732666) (xy 81.235278 -294.716007)
			(xy 81.300133 -294.707584) (xy 81.332832 -294.707056) (xy 82.752184 -294.707056) (xy 82.784145 -294.707608)
			(xy 82.847562 -294.715618) (xy 82.909476 -294.731513) (xy 82.968909 -294.755042) (xy 83.024925 -294.785835)
			(xy 83.076639 -294.823407) (xy 83.123236 -294.867163) (xy 83.163982 -294.916415) (xy 83.198234 -294.970385)
			(xy 83.225451 -295.028223) (xy 83.245204 -295.089015) (xy 83.257182 -295.151805) (xy 83.261196 -295.2156)
			(xy 83.257182 -295.279395) (xy 83.245204 -295.342185) (xy 83.225451 -295.402977) (xy 83.198234 -295.460815)
			(xy 83.163982 -295.514785) (xy 83.123236 -295.564037) (xy 83.076639 -295.607793) (xy 83.024925 -295.645365)
			(xy 82.968909 -295.676158) (xy 82.909476 -295.699687) (xy 82.847562 -295.715582) (xy 82.784145 -295.723592)
			(xy 82.752184 -295.724072) (xy 81.332832 -295.724072) (xy 81.300129 -295.723587) (xy 81.235265 -295.715185)
			(xy 81.172015 -295.698529) (xy 81.111426 -295.673894) (xy 81.054498 -295.641688) (xy 81.028032 -295.622472)
			(xy 80.99425 -295.597072) (xy 80.831436 -295.597072) (xy 80.799432 -295.618154) (xy 80.775663 -295.633464)
			(xy 80.725225 -295.659015) (xy 80.672146 -295.678494) (xy 80.617154 -295.691636) (xy 80.561002 -295.698261)
			(xy 80.532732 -295.698672) (xy 79.381858 -295.698672) (xy 79.350227 -295.698224) (xy 79.287506 -295.689962)
			(xy 79.2264 -295.673584) (xy 79.167955 -295.649371) (xy 79.11317 -295.617736) (xy 79.062982 -295.579222)
			(xy 79.018251 -295.534486) (xy 78.979741 -295.484295) (xy 78.948111 -295.429507) (xy 78.923903 -295.37106)
			(xy 78.90753 -295.309953) (xy 78.899273 -295.247231) (xy 36.478201 -295.247231) (xy 36.471468 -295.319889)
			(xy 36.4555 -295.405309) (xy 36.431719 -295.488891) (xy 36.400327 -295.569923) (xy 36.361593 -295.647712)
			(xy 36.315846 -295.721596) (xy 36.263477 -295.790943) (xy 36.204933 -295.855163) (xy 36.140713 -295.913707)
			(xy 36.071366 -295.966076) (xy 35.997482 -296.011823) (xy 35.919693 -296.050557) (xy 35.838661 -296.081949)
			(xy 35.755079 -296.10573) (xy 35.669659 -296.121698) (xy 35.58313 -296.129716) (xy 35.49623 -296.129716)
			(xy 35.409701 -296.121698) (xy 35.324281 -296.10573) (xy 35.240699 -296.081949) (xy 35.159667 -296.050557)
			(xy 35.081878 -296.011823) (xy 35.007994 -295.966076) (xy 34.938647 -295.913707) (xy 34.874427 -295.855163)
			(xy 34.815883 -295.790943) (xy 34.763514 -295.721596) (xy 34.717767 -295.647712) (xy 34.679033 -295.569923)
			(xy 34.647641 -295.488891) (xy 34.62386 -295.405309) (xy 34.607892 -295.319889) (xy 34.599874 -295.23336)
			(xy 31.398525 -295.23336) (xy 31.396494 -295.2771) (xy 31.384379 -295.363555) (xy 31.364303 -295.448514)
			(xy 31.336438 -295.531247) (xy 31.301025 -295.611041) (xy 31.258368 -295.68721) (xy 31.208835 -295.759096)
			(xy 31.152853 -295.826082) (xy 31.090902 -295.88759) (xy 31.023517 -295.943092) (xy 30.951278 -295.992109)
			(xy 30.874806 -296.034219) (xy 30.79476 -296.06906) (xy 30.71183 -296.096332) (xy 30.626729 -296.115799)
			(xy 30.54019 -296.127295) (xy 30.452958 -296.13072) (xy 30.365784 -296.126045) (xy 30.279418 -296.11331)
			(xy 30.194605 -296.092625) (xy 30.112074 -296.064168) (xy 30.032536 -296.028183) (xy 29.994352 -296.007028)
			(xy 29.9749 -295.996527) (xy 29.933268 -295.981677) (xy 29.889696 -295.974253) (xy 29.845495 -295.97448)
			(xy 29.802001 -295.982352) (xy 29.760525 -295.99763) (xy 29.722318 -296.019855) (xy 29.688532 -296.048354)
			(xy 29.660187 -296.08227) (xy 29.638137 -296.120578) (xy 29.623049 -296.162124) (xy 29.615376 -296.205654)
			(xy 29.614876 -296.227754) (xy 29.614876 -296.692066) (xy 29.61535 -296.714174) (xy 29.623 -296.757722)
			(xy 29.638074 -296.799288) (xy 29.660116 -296.837616) (xy 29.688462 -296.87155) (xy 29.722255 -296.900063)
			(xy 29.760474 -296.922294) (xy 29.801966 -296.937573) (xy 29.845475 -296.945438) (xy 29.88969 -296.94565)
			(xy 29.933273 -296.938204) (xy 29.974909 -296.923324) (xy 29.994352 -296.912792) (xy 30.032527 -296.891621)
			(xy 30.112065 -296.855636) (xy 30.194595 -296.827178) (xy 30.279409 -296.806492) (xy 30.365774 -296.793756)
			(xy 30.452948 -296.78908) (xy 30.54018 -296.792504) (xy 30.626719 -296.803999) (xy 30.711821 -296.823466)
			(xy 30.794751 -296.850737) (xy 30.874797 -296.885577) (xy 30.951269 -296.927686) (xy 31.023509 -296.976702)
			(xy 31.090895 -297.032203) (xy 31.152846 -297.093711) (xy 31.208829 -297.160696) (xy 31.258363 -297.232582)
			(xy 31.301021 -297.30875) (xy 31.336435 -297.388543) (xy 31.3643 -297.471276) (xy 31.384377 -297.556235)
			(xy 31.396494 -297.64269) (xy 31.400544 -297.729895) (xy 31.398525 -297.77336) (xy 34.599874 -297.77336)
			(xy 34.599874 -297.68646) (xy 34.607892 -297.599931) (xy 34.62386 -297.514511) (xy 34.647641 -297.430929)
			(xy 34.679033 -297.349897) (xy 34.717767 -297.272108) (xy 34.763514 -297.198224) (xy 34.815883 -297.128877)
			(xy 34.874427 -297.064657) (xy 34.938647 -297.006113) (xy 35.007994 -296.953744) (xy 35.081878 -296.907997)
			(xy 35.159667 -296.869263) (xy 35.240699 -296.837871) (xy 35.324281 -296.81409) (xy 35.409701 -296.798122)
			(xy 35.49623 -296.790104) (xy 35.58313 -296.790104) (xy 35.669659 -296.798122) (xy 35.755079 -296.81409)
			(xy 35.838661 -296.837871) (xy 35.919693 -296.869263) (xy 35.997482 -296.907997) (xy 36.041741 -296.935401)
			(xy 38.511584 -296.935401) (xy 38.515472 -296.881047) (xy 38.527056 -296.827799) (xy 38.5461 -296.776741)
			(xy 38.572216 -296.728914) (xy 38.604874 -296.68529) (xy 38.643408 -296.646759) (xy 38.687034 -296.614104)
			(xy 38.734862 -296.58799) (xy 38.785921 -296.568949) (xy 38.83917 -296.557368) (xy 38.893525 -296.553484)
			(xy 38.947879 -296.557375) (xy 39.001126 -296.568963) (xy 39.052182 -296.58801) (xy 39.100008 -296.61413)
			(xy 39.122096 -296.63009) (xy 39.141108 -296.643686) (xy 39.182991 -296.664418) (xy 39.227959 -296.677144)
			(xy 39.274496 -296.681434) (xy 39.321033 -296.677144) (xy 39.366001 -296.664418) (xy 39.407884 -296.643686)
			(xy 39.426896 -296.63009) (xy 39.448986 -296.614132) (xy 39.496812 -296.588011) (xy 39.547868 -296.568963)
			(xy 39.601116 -296.557375) (xy 39.655471 -296.553483) (xy 39.709826 -296.557366) (xy 39.763076 -296.568946)
			(xy 39.814135 -296.587987) (xy 39.861965 -296.614101) (xy 39.905591 -296.646756) (xy 39.944126 -296.685288)
			(xy 39.976784 -296.728912) (xy 40.002901 -296.776739) (xy 40.021946 -296.827797) (xy 40.03353 -296.881046)
			(xy 40.037417 -296.935401) (xy 40.398277 -296.935401) (xy 40.402165 -296.881045) (xy 40.413749 -296.827795)
			(xy 40.432794 -296.776736) (xy 40.458912 -296.728908) (xy 40.491571 -296.685283) (xy 40.530106 -296.646751)
			(xy 40.573733 -296.614095) (xy 40.621564 -296.587981) (xy 40.672624 -296.56894) (xy 40.725875 -296.55736)
			(xy 40.780231 -296.553477) (xy 40.834587 -296.557369) (xy 40.887836 -296.568958) (xy 40.938893 -296.588007)
			(xy 40.986719 -296.614129) (xy 41.008808 -296.63009) (xy 41.02782 -296.643686) (xy 41.069703 -296.664418)
			(xy 41.114671 -296.677144) (xy 41.161208 -296.681434) (xy 41.207745 -296.677144) (xy 41.252713 -296.664418)
			(xy 41.294596 -296.643686) (xy 41.313608 -296.63009) (xy 41.335698 -296.614133) (xy 41.383523 -296.588014)
			(xy 41.434578 -296.568967) (xy 41.487824 -296.557381) (xy 41.542178 -296.55349) (xy 41.596532 -296.557374)
			(xy 41.649779 -296.568955) (xy 41.700837 -296.587996) (xy 41.748665 -296.614109) (xy 41.792289 -296.646764)
			(xy 41.830822 -296.685295) (xy 41.863479 -296.728918) (xy 41.889596 -296.776744) (xy 41.908639 -296.827801)
			(xy 41.920223 -296.881048) (xy 41.92411 -296.935401) (xy 41.920222 -296.989755) (xy 41.908639 -297.043002)
			(xy 41.889595 -297.094058) (xy 41.863478 -297.141884) (xy 41.830821 -297.185507) (xy 41.792287 -297.224038)
			(xy 41.748663 -297.256692) (xy 41.700835 -297.282805) (xy 41.649777 -297.301846) (xy 41.596529 -297.313426)
			(xy 41.542175 -297.31731) (xy 41.487822 -297.313419) (xy 41.434576 -297.301832) (xy 41.383521 -297.282785)
			(xy 41.335696 -297.256665) (xy 41.313608 -297.240706) (xy 41.294596 -297.22711) (xy 41.252713 -297.206378)
			(xy 41.207745 -297.193652) (xy 41.161208 -297.189362) (xy 41.114671 -297.193652) (xy 41.069703 -297.206378)
			(xy 41.02782 -297.22711) (xy 41.008808 -297.240706) (xy 40.986722 -297.256669) (xy 40.938895 -297.282792)
			(xy 40.887838 -297.301841) (xy 40.83459 -297.31343) (xy 40.780234 -297.317323) (xy 40.725877 -297.31344)
			(xy 40.672627 -297.30186) (xy 40.621566 -297.28282) (xy 40.573735 -297.256706) (xy 40.530108 -297.224051)
			(xy 40.491572 -297.185518) (xy 40.458913 -297.141894) (xy 40.432795 -297.094066) (xy 40.41375 -297.043007)
			(xy 40.402165 -296.989757) (xy 40.398277 -296.935401) (xy 40.037417 -296.935401) (xy 40.033529 -296.989756)
			(xy 40.021945 -297.043005) (xy 40.0029 -297.094063) (xy 39.976783 -297.14189) (xy 39.944124 -297.185514)
			(xy 39.905589 -297.224045) (xy 39.861963 -297.2567) (xy 39.814133 -297.282814) (xy 39.763074 -297.301854)
			(xy 39.709824 -297.313434) (xy 39.655468 -297.317317) (xy 39.601114 -297.313425) (xy 39.547866 -297.301837)
			(xy 39.49681 -297.282788) (xy 39.448984 -297.256666) (xy 39.426896 -297.240706) (xy 39.407884 -297.22711)
			(xy 39.366001 -297.206378) (xy 39.321033 -297.193652) (xy 39.274496 -297.189362) (xy 39.227959 -297.193652)
			(xy 39.182991 -297.206378) (xy 39.141108 -297.22711) (xy 39.122096 -297.240706) (xy 39.10001 -297.256668)
			(xy 39.052184 -297.282789) (xy 39.001128 -297.301837) (xy 38.947881 -297.313424) (xy 38.893527 -297.317316)
			(xy 38.839172 -297.313432) (xy 38.785923 -297.301852) (xy 38.734865 -297.282811) (xy 38.687036 -297.256697)
			(xy 38.64341 -297.224043) (xy 38.604876 -297.185511) (xy 38.572218 -297.141888) (xy 38.546101 -297.094061)
			(xy 38.527056 -297.043004) (xy 38.515472 -296.989756) (xy 38.511584 -296.935401) (xy 36.041741 -296.935401)
			(xy 36.071366 -296.953744) (xy 36.140713 -297.006113) (xy 36.204933 -297.064657) (xy 36.263477 -297.128877)
			(xy 36.315846 -297.198224) (xy 36.361593 -297.272108) (xy 36.400327 -297.349897) (xy 36.431719 -297.430929)
			(xy 36.4555 -297.514511) (xy 36.471468 -297.599931) (xy 36.479486 -297.68646) (xy 36.479988 -297.72991)
			(xy 36.479486 -297.77336) (xy 36.471468 -297.859889) (xy 36.459515 -297.923829) (xy 78.942725 -297.923829)
			(xy 78.942725 -297.860571) (xy 78.950982 -297.797853) (xy 78.967354 -297.73675) (xy 78.991562 -297.678307)
			(xy 79.023191 -297.623523) (xy 79.0617 -297.573336) (xy 79.10643 -297.528605) (xy 79.156616 -297.490095)
			(xy 79.211399 -297.458465) (xy 79.269842 -297.434257) (xy 79.330945 -297.417883) (xy 79.393663 -297.409625)
			(xy 79.425292 -297.409108) (xy 80.546956 -297.409108) (xy 80.57525 -297.409517) (xy 80.631451 -297.416136)
			(xy 80.686492 -297.429278) (xy 80.739621 -297.448762) (xy 80.790109 -297.474321) (xy 80.81391 -297.489626)
			(xy 80.84566 -297.510708) (xy 80.903064 -297.510708) (xy 80.903064 -297.565826) (xy 80.922938 -297.588137)
			(xy 80.957571 -297.636828) (xy 80.985935 -297.689418) (xy 81.007595 -297.745106) (xy 81.02222 -297.80304)
			(xy 81.029589 -297.862336) (xy 81.029588 -297.922088) (xy 81.022216 -297.981383) (xy 81.007587 -298.039316)
			(xy 80.985925 -298.095003) (xy 80.957559 -298.147592) (xy 80.922923 -298.196282) (xy 80.903064 -298.218606)
			(xy 80.903064 -298.273724) (xy 80.84566 -298.273724) (xy 80.81391 -298.294806) (xy 80.790117 -298.310125)
			(xy 80.739629 -298.335688) (xy 80.686498 -298.355172) (xy 80.631454 -298.36831) (xy 80.575251 -298.374922)
			(xy 80.546956 -298.375324) (xy 79.425292 -298.375324) (xy 79.393663 -298.374775) (xy 79.330945 -298.366517)
			(xy 79.269842 -298.350143) (xy 79.211399 -298.325935) (xy 79.156616 -298.294305) (xy 79.10643 -298.255795)
			(xy 79.0617 -298.211064) (xy 79.023191 -298.160877) (xy 78.991562 -298.106093) (xy 78.967354 -298.04765)
			(xy 78.950982 -297.986547) (xy 78.942725 -297.923829) (xy 36.459515 -297.923829) (xy 36.4555 -297.945309)
			(xy 36.431719 -298.028891) (xy 36.400327 -298.109923) (xy 36.361593 -298.187712) (xy 36.315846 -298.261596)
			(xy 36.263477 -298.330943) (xy 36.204933 -298.395163) (xy 36.140713 -298.453707) (xy 36.071366 -298.506076)
			(xy 35.997482 -298.551823) (xy 35.919693 -298.590557) (xy 35.838661 -298.621949) (xy 35.755079 -298.64573)
			(xy 35.669659 -298.661698) (xy 35.58313 -298.669716) (xy 35.49623 -298.669716) (xy 35.409701 -298.661698)
			(xy 35.324281 -298.64573) (xy 35.240699 -298.621949) (xy 35.159667 -298.590557) (xy 35.081878 -298.551823)
			(xy 35.007994 -298.506076) (xy 34.938647 -298.453707) (xy 34.874427 -298.395163) (xy 34.815883 -298.330943)
			(xy 34.763514 -298.261596) (xy 34.717767 -298.187712) (xy 34.679033 -298.109923) (xy 34.647641 -298.028891)
			(xy 34.62386 -297.945309) (xy 34.607892 -297.859889) (xy 34.599874 -297.77336) (xy 31.398525 -297.77336)
			(xy 31.396494 -297.8171) (xy 31.384379 -297.903555) (xy 31.364303 -297.988514) (xy 31.336438 -298.071247)
			(xy 31.301025 -298.151041) (xy 31.258368 -298.22721) (xy 31.208835 -298.299096) (xy 31.152853 -298.366082)
			(xy 31.090902 -298.42759) (xy 31.023517 -298.483092) (xy 30.951278 -298.532109) (xy 30.874806 -298.574219)
			(xy 30.79476 -298.60906) (xy 30.71183 -298.636332) (xy 30.626729 -298.655799) (xy 30.54019 -298.667295)
			(xy 30.452958 -298.67072) (xy 30.365784 -298.666045) (xy 30.279418 -298.65331) (xy 30.194605 -298.632625)
			(xy 30.112074 -298.604168) (xy 30.032536 -298.568183) (xy 29.994352 -298.547028) (xy 29.9749 -298.536527)
			(xy 29.933268 -298.521677) (xy 29.889696 -298.514253) (xy 29.845495 -298.51448) (xy 29.802001 -298.522352)
			(xy 29.760525 -298.53763) (xy 29.722318 -298.559855) (xy 29.688532 -298.588354) (xy 29.660187 -298.62227)
			(xy 29.638137 -298.660578) (xy 29.623049 -298.702124) (xy 29.615376 -298.745654) (xy 29.614876 -298.767754)
			(xy 29.614876 -298.768986) (xy 38.511605 -298.768986) (xy 38.515495 -298.714634) (xy 38.52708 -298.661389)
			(xy 38.546125 -298.610336) (xy 38.572242 -298.562512) (xy 38.6049 -298.518892) (xy 38.643434 -298.480364)
			(xy 38.687058 -298.447713) (xy 38.734885 -298.421602) (xy 38.785942 -298.402565) (xy 38.839188 -298.390987)
			(xy 38.89354 -298.387105) (xy 38.947891 -298.390998) (xy 39.001135 -298.402587) (xy 39.052188 -298.421636)
			(xy 39.10001 -298.447756) (xy 39.122096 -298.463716) (xy 39.141108 -298.477312) (xy 39.182991 -298.498044)
			(xy 39.227959 -298.51077) (xy 39.274496 -298.51506) (xy 39.321033 -298.51077) (xy 39.366001 -298.498044)
			(xy 39.407884 -298.477312) (xy 39.426896 -298.463716) (xy 39.448962 -298.447723) (xy 39.496789 -298.421599)
			(xy 39.547847 -298.402547) (xy 39.601098 -298.390956) (xy 39.655455 -298.387062) (xy 39.709814 -298.390943)
			(xy 39.763067 -298.402522) (xy 39.81413 -298.421562) (xy 39.861963 -298.447675) (xy 39.905593 -298.48033)
			(xy 39.944131 -298.518862) (xy 39.976793 -298.562487) (xy 40.002914 -298.610317) (xy 40.021961 -298.661376)
			(xy 40.033548 -298.714628) (xy 40.037438 -298.768986) (xy 40.398298 -298.768986) (xy 40.402188 -298.714632)
			(xy 40.413773 -298.661386) (xy 40.432819 -298.610331) (xy 40.458938 -298.562506) (xy 40.491597 -298.518885)
			(xy 40.530132 -298.480357) (xy 40.573758 -298.447705) (xy 40.621587 -298.421594) (xy 40.672645 -298.402556)
			(xy 40.725893 -298.390979) (xy 40.780247 -298.387098) (xy 40.8346 -298.390992) (xy 40.887845 -298.402583)
			(xy 40.938899 -298.421633) (xy 40.986721 -298.447755) (xy 41.008808 -298.463716) (xy 41.02782 -298.477312)
			(xy 41.069703 -298.498044) (xy 41.114671 -298.51077) (xy 41.161208 -298.51506) (xy 41.207745 -298.51077)
			(xy 41.252713 -298.498044) (xy 41.294596 -298.477312) (xy 41.313608 -298.463716) (xy 41.335673 -298.447724)
			(xy 41.3835 -298.421602) (xy 41.434557 -298.402552) (xy 41.487806 -298.390962) (xy 41.542162 -298.387069)
			(xy 41.596519 -298.390951) (xy 41.64977 -298.40253) (xy 41.700831 -298.42157) (xy 41.748663 -298.447683)
			(xy 41.792291 -298.480338) (xy 41.830828 -298.518869) (xy 41.863488 -298.562493) (xy 41.889608 -298.610321)
			(xy 41.908655 -298.66138) (xy 41.920241 -298.714629) (xy 41.924131 -298.768986) (xy 42.639273 -298.768986)
			(xy 42.643163 -298.714627) (xy 42.65475 -298.661375) (xy 42.673799 -298.610315) (xy 42.699921 -298.562485)
			(xy 42.732585 -298.518861) (xy 42.771125 -298.480329) (xy 42.814757 -298.447675) (xy 42.862592 -298.421564)
			(xy 42.913657 -298.402526) (xy 42.966911 -298.390951) (xy 43.021271 -298.387073) (xy 43.075629 -298.390971)
			(xy 43.128879 -298.402566) (xy 43.179937 -298.421623) (xy 43.227762 -298.447752) (xy 43.24985 -298.463716)
			(xy 43.268862 -298.477312) (xy 43.310745 -298.498044) (xy 43.355713 -298.51077) (xy 43.40225 -298.51506)
			(xy 43.448787 -298.51077) (xy 43.493755 -298.498044) (xy 43.535638 -298.477312) (xy 43.55465 -298.463716)
			(xy 43.576717 -298.447719) (xy 43.624547 -298.421588) (xy 43.67561 -298.402529) (xy 43.728865 -298.390933)
			(xy 43.783229 -298.387034) (xy 43.837594 -298.390913) (xy 43.890854 -298.40249) (xy 43.941924 -298.421529)
			(xy 43.989764 -298.447643) (xy 44.0334 -298.4803) (xy 44.071944 -298.518835) (xy 44.104611 -298.562464)
			(xy 44.130736 -298.610299) (xy 44.149786 -298.661364) (xy 44.161375 -298.714621) (xy 44.165266 -298.768986)
			(xy 44.543282 -298.768986) (xy 44.547172 -298.714629) (xy 44.558759 -298.661379) (xy 44.577807 -298.610321)
			(xy 44.603927 -298.562493) (xy 44.636589 -298.51887) (xy 44.675128 -298.48034) (xy 44.718757 -298.447686)
			(xy 44.76659 -298.421575) (xy 44.817652 -298.402538) (xy 44.870904 -298.390962) (xy 44.925262 -298.387082)
			(xy 44.979618 -298.390979) (xy 45.032866 -298.402573) (xy 45.083922 -298.421626) (xy 45.131747 -298.447753)
			(xy 45.153834 -298.463716) (xy 45.172846 -298.477312) (xy 45.214729 -298.498044) (xy 45.259697 -298.51077)
			(xy 45.306234 -298.51506) (xy 45.352771 -298.51077) (xy 45.397739 -298.498044) (xy 45.439622 -298.477312)
			(xy 45.458634 -298.463716) (xy 45.480699 -298.447727) (xy 45.528523 -298.421608) (xy 45.579578 -298.402562)
			(xy 45.632824 -298.390975) (xy 45.687177 -298.387085) (xy 45.74153 -298.390969) (xy 45.794777 -298.402549)
			(xy 45.845835 -298.421589) (xy 45.893662 -298.447702) (xy 45.937287 -298.480355) (xy 45.97582 -298.518885)
			(xy 46.008478 -298.562506) (xy 46.034595 -298.610331) (xy 46.053641 -298.661387) (xy 46.065226 -298.714633)
			(xy 46.069115 -298.768986) (xy 46.06523 -298.823339) (xy 46.053649 -298.876586) (xy 46.034607 -298.927642)
			(xy 46.008494 -298.97547) (xy 45.975839 -299.019093) (xy 45.937309 -299.057626) (xy 45.893686 -299.090283)
			(xy 45.845861 -299.116399) (xy 45.794805 -299.135443) (xy 45.741559 -299.147027) (xy 45.687206 -299.150915)
			(xy 45.632853 -299.147029) (xy 45.579606 -299.135446) (xy 45.52855 -299.116404) (xy 45.480723 -299.090289)
			(xy 45.458634 -299.074332) (xy 45.439622 -299.060736) (xy 45.397739 -299.040004) (xy 45.352771 -299.027278)
			(xy 45.306234 -299.022988) (xy 45.259697 -299.027278) (xy 45.214729 -299.040004) (xy 45.172846 -299.060736)
			(xy 45.153834 -299.074332) (xy 45.131723 -299.090262) (xy 45.083896 -299.116385) (xy 45.032839 -299.135436)
			(xy 44.979589 -299.147025) (xy 44.925233 -299.150918) (xy 44.870876 -299.147034) (xy 44.817625 -299.135454)
			(xy 44.766564 -299.116413) (xy 44.718733 -299.090298) (xy 44.675106 -299.057642) (xy 44.636571 -299.019108)
			(xy 44.603912 -298.975483) (xy 44.577795 -298.927653) (xy 44.558751 -298.876593) (xy 44.547168 -298.823343)
			(xy 44.543282 -298.768986) (xy 44.165266 -298.768986) (xy 44.161379 -298.82335) (xy 44.149795 -298.876608)
			(xy 44.130748 -298.927675) (xy 44.104627 -298.975511) (xy 44.071963 -299.019143) (xy 44.033422 -299.057681)
			(xy 43.989788 -299.090342) (xy 43.94195 -299.116459) (xy 43.890882 -299.135502) (xy 43.837623 -299.147083)
			(xy 43.783258 -299.150966) (xy 43.728894 -299.147071) (xy 43.675638 -299.135479) (xy 43.624573 -299.116424)
			(xy 43.576741 -299.090296) (xy 43.55465 -299.074332) (xy 43.535638 -299.060736) (xy 43.493755 -299.040004)
			(xy 43.448787 -299.027278) (xy 43.40225 -299.022988) (xy 43.355713 -299.027278) (xy 43.310745 -299.040004)
			(xy 43.268862 -299.060736) (xy 43.24985 -299.074332) (xy 43.227738 -299.090264) (xy 43.179911 -299.116389)
			(xy 43.128852 -299.135442) (xy 43.075601 -299.147033) (xy 43.021242 -299.150927) (xy 42.966883 -299.147045)
			(xy 42.913629 -299.135466) (xy 42.862566 -299.116424) (xy 42.814733 -299.090309) (xy 42.771103 -299.057652)
			(xy 42.732566 -299.019118) (xy 42.699906 -298.975491) (xy 42.673787 -298.927659) (xy 42.654742 -298.876597)
			(xy 42.643159 -298.823345) (xy 42.639273 -298.768986) (xy 41.924131 -298.768986) (xy 41.920245 -298.823342)
			(xy 41.908663 -298.876593) (xy 41.88962 -298.927653) (xy 41.863504 -298.975483) (xy 41.830847 -299.019109)
			(xy 41.792313 -299.057643) (xy 41.748687 -299.090301) (xy 41.700857 -299.116418) (xy 41.649798 -299.135461)
			(xy 41.596548 -299.147044) (xy 41.542191 -299.150931) (xy 41.487834 -299.147042) (xy 41.434585 -299.135456)
			(xy 41.383526 -299.11641) (xy 41.335698 -299.090291) (xy 41.313608 -299.074332) (xy 41.294596 -299.060736)
			(xy 41.252713 -299.040004) (xy 41.207745 -299.027278) (xy 41.161208 -299.022988) (xy 41.114671 -299.027278)
			(xy 41.069703 -299.040004) (xy 41.02782 -299.060736) (xy 41.008808 -299.074332) (xy 40.986697 -299.09026)
			(xy 40.938872 -299.116379) (xy 40.887817 -299.135426) (xy 40.834571 -299.147012) (xy 40.780218 -299.150902)
			(xy 40.725865 -299.147017) (xy 40.672618 -299.135436) (xy 40.621561 -299.116394) (xy 40.573733 -299.09028)
			(xy 40.53011 -299.057625) (xy 40.491578 -299.019093) (xy 40.458922 -298.97547) (xy 40.432807 -298.927643)
			(xy 40.413765 -298.876586) (xy 40.402183 -298.823339) (xy 40.398298 -298.768986) (xy 40.037438 -298.768986)
			(xy 40.033552 -298.823344) (xy 40.021969 -298.876596) (xy 40.002926 -298.927657) (xy 39.976809 -298.975489)
			(xy 39.94415 -299.019116) (xy 39.905615 -299.057651) (xy 39.861987 -299.090309) (xy 39.814156 -299.116426)
			(xy 39.763094 -299.13547) (xy 39.709842 -299.147052) (xy 39.655484 -299.150938) (xy 39.601126 -299.147048)
			(xy 39.547875 -299.135461) (xy 39.496815 -299.116413) (xy 39.448986 -299.090292) (xy 39.426896 -299.074332)
			(xy 39.407884 -299.060736) (xy 39.366001 -299.040004) (xy 39.321033 -299.027278) (xy 39.274496 -299.022988)
			(xy 39.227959 -299.027278) (xy 39.182991 -299.040004) (xy 39.141108 -299.060736) (xy 39.122096 -299.074332)
			(xy 39.099985 -299.090259) (xy 39.052162 -299.116376) (xy 39.001108 -299.135421) (xy 38.947863 -299.147006)
			(xy 38.893511 -299.150895) (xy 38.83916 -299.147009) (xy 38.785914 -299.135427) (xy 38.734859 -299.116386)
			(xy 38.687034 -299.090272) (xy 38.643412 -299.057617) (xy 38.604881 -299.019086) (xy 38.572227 -298.975464)
			(xy 38.546113 -298.927638) (xy 38.527072 -298.876583) (xy 38.515491 -298.823337) (xy 38.511605 -298.768986)
			(xy 29.614876 -298.768986) (xy 29.614876 -299.232066) (xy 29.61535 -299.254174) (xy 29.623 -299.297722)
			(xy 29.638074 -299.339288) (xy 29.660116 -299.377616) (xy 29.688462 -299.41155) (xy 29.722255 -299.440063)
			(xy 29.760474 -299.462294) (xy 29.801966 -299.477573) (xy 29.845475 -299.485438) (xy 29.88969 -299.48565)
			(xy 29.933273 -299.478204) (xy 29.974909 -299.463324) (xy 29.994352 -299.452792) (xy 30.032527 -299.431621)
			(xy 30.112065 -299.395636) (xy 30.194595 -299.367178) (xy 30.279409 -299.346492) (xy 30.365774 -299.333756)
			(xy 30.452948 -299.32908) (xy 30.54018 -299.332504) (xy 30.626719 -299.343999) (xy 30.711821 -299.363466)
			(xy 30.794751 -299.390737) (xy 30.874797 -299.425577) (xy 30.951269 -299.467686) (xy 31.023509 -299.516702)
			(xy 31.090895 -299.572203) (xy 31.152846 -299.633711) (xy 31.208829 -299.700696) (xy 31.258363 -299.772582)
			(xy 31.301021 -299.84875) (xy 31.336435 -299.928543) (xy 31.3643 -300.011276) (xy 31.384377 -300.096235)
			(xy 31.396494 -300.18269) (xy 31.400544 -300.269895) (xy 31.398525 -300.31336) (xy 34.599874 -300.31336)
			(xy 34.599874 -300.22646) (xy 34.607892 -300.139931) (xy 34.62386 -300.054511) (xy 34.647641 -299.970929)
			(xy 34.679033 -299.889897) (xy 34.717767 -299.812108) (xy 34.763514 -299.738224) (xy 34.815883 -299.668877)
			(xy 34.874427 -299.604657) (xy 34.938647 -299.546113) (xy 35.007994 -299.493744) (xy 35.081878 -299.447997)
			(xy 35.159667 -299.409263) (xy 35.240699 -299.377871) (xy 35.324281 -299.35409) (xy 35.409701 -299.338122)
			(xy 35.49623 -299.330104) (xy 35.58313 -299.330104) (xy 35.669659 -299.338122) (xy 35.755079 -299.35409)
			(xy 35.838661 -299.377871) (xy 35.919693 -299.409263) (xy 35.997482 -299.447997) (xy 36.071366 -299.493744)
			(xy 36.140713 -299.546113) (xy 36.204933 -299.604657) (xy 36.263477 -299.668877) (xy 36.271585 -299.679614)
			(xy 97.869246 -299.679614) (xy 97.873317 -299.623992) (xy 97.885443 -299.569555) (xy 97.905366 -299.517464)
			(xy 97.932662 -299.468829) (xy 97.966748 -299.424686) (xy 98.006897 -299.385977) (xy 98.052255 -299.353526)
			(xy 98.101855 -299.328025) (xy 98.154639 -299.310018) (xy 98.209482 -299.299888) (xy 98.265216 -299.297851)
			(xy 98.320653 -299.303951) (xy 98.37461 -299.318057) (xy 98.425939 -299.339869) (xy 98.473545 -299.368923)
			(xy 98.516413 -299.404598) (xy 98.55363 -299.446135) (xy 98.584403 -299.492648) (xy 98.608075 -299.543145)
			(xy 98.624143 -299.596552) (xy 98.632263 -299.651728) (xy 98.632772 -299.679614) (xy 98.632263 -299.7075)
			(xy 98.624143 -299.762676) (xy 98.608075 -299.816083) (xy 98.584403 -299.86658) (xy 98.55363 -299.913093)
			(xy 98.516413 -299.95463) (xy 98.473545 -299.990305) (xy 98.425939 -300.019359) (xy 98.37461 -300.041171)
			(xy 98.320653 -300.055277) (xy 98.265216 -300.061377) (xy 98.209482 -300.05934) (xy 98.154639 -300.04921)
			(xy 98.101855 -300.031203) (xy 98.052255 -300.005702) (xy 98.006897 -299.973251) (xy 97.966748 -299.934542)
			(xy 97.932662 -299.890399) (xy 97.905366 -299.841764) (xy 97.885443 -299.789673) (xy 97.873317 -299.735236)
			(xy 97.869246 -299.679614) (xy 36.271585 -299.679614) (xy 36.315846 -299.738224) (xy 36.361593 -299.812108)
			(xy 36.400327 -299.889897) (xy 36.431719 -299.970929) (xy 36.4555 -300.054511) (xy 36.471468 -300.139931)
			(xy 36.479486 -300.22646) (xy 36.479988 -300.26991) (xy 36.479486 -300.31336) (xy 36.471468 -300.399889)
			(xy 36.4555 -300.485309) (xy 36.431719 -300.568891) (xy 36.400327 -300.649923) (xy 36.390318 -300.670024)
			(xy 38.511554 -300.670024) (xy 38.515438 -300.615665) (xy 38.52702 -300.562412) (xy 38.546063 -300.511349)
			(xy 38.572179 -300.463517) (xy 38.604836 -300.419888) (xy 38.643371 -300.381351) (xy 38.686998 -300.348691)
			(xy 38.734829 -300.322572) (xy 38.785891 -300.303526) (xy 38.839143 -300.291942) (xy 38.893502 -300.288054)
			(xy 38.947861 -300.291942) (xy 39.001113 -300.303527) (xy 39.052174 -300.322573) (xy 39.100005 -300.348692)
			(xy 39.122096 -300.364652) (xy 39.141108 -300.378248) (xy 39.182991 -300.39898) (xy 39.227959 -300.411706)
			(xy 39.274496 -300.415996) (xy 39.321033 -300.411706) (xy 39.366001 -300.39898) (xy 39.407884 -300.378248)
			(xy 39.426896 -300.364652) (xy 39.449022 -300.348746) (xy 39.496845 -300.32263) (xy 39.547899 -300.303586)
			(xy 39.601143 -300.292001) (xy 39.655494 -300.288113) (xy 39.709845 -300.292) (xy 39.763089 -300.303582)
			(xy 39.814143 -300.322624) (xy 39.861968 -300.348739) (xy 39.905588 -300.381394) (xy 39.944118 -300.419925)
			(xy 39.976771 -300.463547) (xy 40.002883 -300.511373) (xy 40.021923 -300.562428) (xy 40.033503 -300.615673)
			(xy 40.037387 -300.670024) (xy 40.398247 -300.670024) (xy 40.402131 -300.615663) (xy 40.413713 -300.562409)
			(xy 40.432757 -300.511345) (xy 40.458874 -300.463511) (xy 40.491533 -300.419881) (xy 40.530069 -300.381343)
			(xy 40.573698 -300.348682) (xy 40.621531 -300.322563) (xy 40.672594 -300.303518) (xy 40.725848 -300.291934)
			(xy 40.780209 -300.288047) (xy 40.834569 -300.291936) (xy 40.887823 -300.303523) (xy 40.938885 -300.32257)
			(xy 40.986717 -300.348691) (xy 41.008808 -300.364652) (xy 41.02782 -300.378248) (xy 41.069703 -300.39898)
			(xy 41.114671 -300.411706) (xy 41.161208 -300.415996) (xy 41.207745 -300.411706) (xy 41.252713 -300.39898)
			(xy 41.294596 -300.378248) (xy 41.313608 -300.364652) (xy 41.335733 -300.348747) (xy 41.383556 -300.322632)
			(xy 41.434608 -300.30359) (xy 41.487851 -300.292008) (xy 41.542201 -300.28812) (xy 41.59655 -300.292008)
			(xy 41.649793 -300.30359) (xy 41.700845 -300.322633) (xy 41.748667 -300.348747) (xy 41.792286 -300.381402)
			(xy 41.830814 -300.419932) (xy 41.863466 -300.463553) (xy 41.889577 -300.511377) (xy 41.908616 -300.562431)
			(xy 41.920196 -300.615674) (xy 41.92408 -300.670024) (xy 42.639221 -300.670024) (xy 42.643107 -300.615657)
			(xy 42.65469 -300.562397) (xy 42.673737 -300.511328) (xy 42.699857 -300.46349) (xy 42.732521 -300.419856)
			(xy 42.771062 -300.381315) (xy 42.814697 -300.348653) (xy 42.862536 -300.322533) (xy 42.913606 -300.303488)
			(xy 42.966866 -300.291906) (xy 43.021232 -300.288021) (xy 43.075598 -300.291915) (xy 43.128857 -300.303506)
			(xy 43.179923 -300.32256) (xy 43.227758 -300.348688) (xy 43.24985 -300.364652) (xy 43.268862 -300.378248)
			(xy 43.310745 -300.39898) (xy 43.355713 -300.411706) (xy 43.40225 -300.415996) (xy 43.448787 -300.411706)
			(xy 43.493755 -300.39898) (xy 43.535638 -300.378248) (xy 43.55465 -300.364652) (xy 43.576777 -300.348742)
			(xy 43.624603 -300.322618) (xy 43.675661 -300.303568) (xy 43.728911 -300.291978) (xy 43.783268 -300.288086)
			(xy 43.837625 -300.291969) (xy 43.890876 -300.303549) (xy 43.941937 -300.322591) (xy 43.989769 -300.348707)
			(xy 44.033396 -300.381364) (xy 44.071931 -300.419898) (xy 44.104589 -300.463524) (xy 44.130705 -300.511355)
			(xy 44.149748 -300.562415) (xy 44.16133 -300.615667) (xy 44.165214 -300.670024) (xy 44.543231 -300.670024)
			(xy 44.547116 -300.61566) (xy 44.558699 -300.562402) (xy 44.577744 -300.511334) (xy 44.603864 -300.463498)
			(xy 44.636526 -300.419865) (xy 44.675065 -300.381326) (xy 44.718697 -300.348664) (xy 44.766534 -300.322545)
			(xy 44.817601 -300.303499) (xy 44.870859 -300.291916) (xy 44.925223 -300.288031) (xy 44.979587 -300.291923)
			(xy 45.032844 -300.303513) (xy 45.083909 -300.322564) (xy 45.131742 -300.348689) (xy 45.153834 -300.364652)
			(xy 45.172846 -300.378248) (xy 45.214729 -300.39898) (xy 45.259697 -300.411706) (xy 45.306234 -300.415996)
			(xy 45.352771 -300.411706) (xy 45.397739 -300.39898) (xy 45.439622 -300.378248) (xy 45.458634 -300.364652)
			(xy 45.480759 -300.348749) (xy 45.52858 -300.322639) (xy 45.57963 -300.3036) (xy 45.632869 -300.292021)
			(xy 45.687215 -300.288136) (xy 45.741561 -300.292025) (xy 45.7948 -300.303609) (xy 45.845848 -300.322652)
			(xy 45.893667 -300.348765) (xy 45.937282 -300.381419) (xy 45.975807 -300.419947) (xy 46.008456 -300.463566)
			(xy 46.034565 -300.511388) (xy 46.053602 -300.562438) (xy 46.065181 -300.615678) (xy 46.069064 -300.670024)
			(xy 46.065174 -300.724369) (xy 46.055126 -300.770544) (xy 96.970086 -300.770544) (xy 96.974157 -300.714922)
			(xy 96.986283 -300.660485) (xy 97.006206 -300.608394) (xy 97.033502 -300.559759) (xy 97.067588 -300.515616)
			(xy 97.107737 -300.476907) (xy 97.153095 -300.444456) (xy 97.202695 -300.418955) (xy 97.255479 -300.400948)
			(xy 97.310322 -300.390818) (xy 97.366056 -300.388781) (xy 97.421493 -300.394881) (xy 97.47545 -300.408987)
			(xy 97.526779 -300.430799) (xy 97.574385 -300.459853) (xy 97.617253 -300.495528) (xy 97.65447 -300.537065)
			(xy 97.685243 -300.583578) (xy 97.708915 -300.634075) (xy 97.724983 -300.687482) (xy 97.733103 -300.742658)
			(xy 97.733612 -300.770544) (xy 97.733103 -300.79843) (xy 97.724983 -300.853606) (xy 97.708915 -300.907013)
			(xy 97.685243 -300.95751) (xy 97.65447 -301.004023) (xy 97.617253 -301.04556) (xy 97.574385 -301.081235)
			(xy 97.526779 -301.110289) (xy 97.47545 -301.132101) (xy 97.421493 -301.146207) (xy 97.366056 -301.152307)
			(xy 97.310322 -301.15027) (xy 97.255479 -301.14014) (xy 97.202695 -301.122133) (xy 97.153095 -301.096632)
			(xy 97.107737 -301.064181) (xy 97.067588 -301.025472) (xy 97.033502 -300.981329) (xy 97.006206 -300.932694)
			(xy 96.986283 -300.880603) (xy 96.974157 -300.826166) (xy 96.970086 -300.770544) (xy 46.055126 -300.770544)
			(xy 46.053589 -300.777608) (xy 46.034545 -300.828656) (xy 46.00843 -300.876474) (xy 45.975775 -300.920089)
			(xy 45.937246 -300.958612) (xy 45.893626 -300.991261) (xy 45.845805 -301.017368) (xy 45.794754 -301.036405)
			(xy 45.741513 -301.047982) (xy 45.687167 -301.051864) (xy 45.632822 -301.047973) (xy 45.579584 -301.036386)
			(xy 45.528536 -301.017341) (xy 45.480718 -300.991225) (xy 45.458634 -300.975268) (xy 45.439622 -300.961672)
			(xy 45.397739 -300.94094) (xy 45.352771 -300.928214) (xy 45.306234 -300.923924) (xy 45.259697 -300.928214)
			(xy 45.214729 -300.94094) (xy 45.172846 -300.961672) (xy 45.153834 -300.975268) (xy 45.131783 -300.991285)
			(xy 45.083952 -301.017416) (xy 45.03289 -301.036474) (xy 44.979635 -301.04807) (xy 44.925271 -301.051969)
			(xy 44.870907 -301.048091) (xy 44.817647 -301.036514) (xy 44.766578 -301.017475) (xy 44.718738 -300.991362)
			(xy 44.675101 -300.958705) (xy 44.636557 -300.920171) (xy 44.60389 -300.876543) (xy 44.577764 -300.828709)
			(xy 44.558713 -300.777644) (xy 44.547123 -300.724388) (xy 44.543231 -300.670024) (xy 44.165214 -300.670024)
			(xy 44.161323 -300.724381) (xy 44.149735 -300.777631) (xy 44.130685 -300.828689) (xy 44.104563 -300.876516)
			(xy 44.071899 -300.920138) (xy 44.033359 -300.958668) (xy 43.989728 -300.991319) (xy 43.941894 -301.017429)
			(xy 43.89083 -301.036464) (xy 43.837578 -301.048038) (xy 43.78322 -301.051914) (xy 43.728863 -301.048015)
			(xy 43.675615 -301.036419) (xy 43.62456 -301.017362) (xy 43.576736 -300.991232) (xy 43.55465 -300.975268)
			(xy 43.535638 -300.961672) (xy 43.493755 -300.94094) (xy 43.448787 -300.928214) (xy 43.40225 -300.923924)
			(xy 43.355713 -300.928214) (xy 43.310745 -300.94094) (xy 43.268862 -300.961672) (xy 43.24985 -300.975268)
			(xy 43.227798 -300.991286) (xy 43.179967 -301.01742) (xy 43.128903 -301.03648) (xy 43.075646 -301.048078)
			(xy 43.021281 -301.051979) (xy 42.966913 -301.048101) (xy 42.913652 -301.036525) (xy 42.86258 -301.017487)
			(xy 42.814737 -300.991373) (xy 42.771099 -300.958716) (xy 42.732552 -300.92018) (xy 42.699883 -300.876551)
			(xy 42.673757 -300.828715) (xy 42.654704 -300.777649) (xy 42.643114 -300.72439) (xy 42.639221 -300.670024)
			(xy 41.92408 -300.670024) (xy 41.920189 -300.724373) (xy 41.908603 -300.777615) (xy 41.889557 -300.828666)
			(xy 41.86344 -300.876487) (xy 41.830783 -300.920104) (xy 41.79225 -300.95863) (xy 41.748627 -300.991279)
			(xy 41.700801 -301.017387) (xy 41.649746 -301.036423) (xy 41.596502 -301.047999) (xy 41.542153 -301.05188)
			(xy 41.487804 -301.047986) (xy 41.434562 -301.036396) (xy 41.383512 -301.017348) (xy 41.335693 -300.991227)
			(xy 41.313608 -300.975268) (xy 41.294596 -300.961672) (xy 41.252713 -300.94094) (xy 41.207745 -300.928214)
			(xy 41.161208 -300.923924) (xy 41.114671 -300.928214) (xy 41.069703 -300.94094) (xy 41.02782 -300.961672)
			(xy 41.008808 -300.975268) (xy 40.986757 -300.991283) (xy 40.938929 -301.01741) (xy 40.887869 -301.036464)
			(xy 40.834617 -301.048057) (xy 40.780257 -301.051953) (xy 40.725895 -301.048073) (xy 40.67264 -301.036496)
			(xy 40.621574 -301.017457) (xy 40.573738 -300.991344) (xy 40.530105 -300.958688) (xy 40.491564 -300.920156)
			(xy 40.4589 -300.87653) (xy 40.432777 -300.828699) (xy 40.413727 -300.777637) (xy 40.402138 -300.724384)
			(xy 40.398247 -300.670024) (xy 40.037387 -300.670024) (xy 40.033496 -300.724375) (xy 40.021909 -300.777618)
			(xy 40.002863 -300.828671) (xy 39.976745 -300.876493) (xy 39.944086 -300.920111) (xy 39.905552 -300.958637)
			(xy 39.861927 -300.991287) (xy 39.8141 -301.017396) (xy 39.763043 -301.036432) (xy 39.709797 -301.048007)
			(xy 39.655446 -301.051887) (xy 39.601095 -301.047992) (xy 39.547853 -301.036401) (xy 39.496802 -301.017351)
			(xy 39.448981 -300.991228) (xy 39.426896 -300.975268) (xy 39.407884 -300.961672) (xy 39.366001 -300.94094)
			(xy 39.321033 -300.928214) (xy 39.274496 -300.923924) (xy 39.227959 -300.928214) (xy 39.182991 -300.94094)
			(xy 39.141108 -300.961672) (xy 39.122096 -300.975268) (xy 39.100045 -300.991282) (xy 39.052218 -301.017407)
			(xy 39.001159 -301.036459) (xy 38.947908 -301.048051) (xy 38.89355 -301.051946) (xy 38.83919 -301.048065)
			(xy 38.785937 -301.036487) (xy 38.734873 -301.017448) (xy 38.687038 -300.991335) (xy 38.643407 -300.958681)
			(xy 38.604868 -300.920149) (xy 38.572205 -300.876524) (xy 38.546082 -300.828694) (xy 38.527033 -300.777634)
			(xy 38.515445 -300.724383) (xy 38.511554 -300.670024) (xy 36.390318 -300.670024) (xy 36.361593 -300.727712)
			(xy 36.315846 -300.801596) (xy 36.263477 -300.870943) (xy 36.204933 -300.935163) (xy 36.140713 -300.993707)
			(xy 36.071366 -301.046076) (xy 35.997482 -301.091823) (xy 35.919693 -301.130557) (xy 35.838661 -301.161949)
			(xy 35.755079 -301.18573) (xy 35.669659 -301.201698) (xy 35.58313 -301.209716) (xy 35.49623 -301.209716)
			(xy 35.409701 -301.201698) (xy 35.324281 -301.18573) (xy 35.240699 -301.161949) (xy 35.159667 -301.130557)
			(xy 35.081878 -301.091823) (xy 35.007994 -301.046076) (xy 34.938647 -300.993707) (xy 34.874427 -300.935163)
			(xy 34.815883 -300.870943) (xy 34.763514 -300.801596) (xy 34.717767 -300.727712) (xy 34.679033 -300.649923)
			(xy 34.647641 -300.568891) (xy 34.62386 -300.485309) (xy 34.607892 -300.399889) (xy 34.599874 -300.31336)
			(xy 31.398525 -300.31336) (xy 31.396494 -300.3571) (xy 31.384379 -300.443555) (xy 31.364303 -300.528514)
			(xy 31.336438 -300.611247) (xy 31.301025 -300.691041) (xy 31.258368 -300.76721) (xy 31.208835 -300.839096)
			(xy 31.152853 -300.906082) (xy 31.090902 -300.96759) (xy 31.023517 -301.023092) (xy 30.951278 -301.072109)
			(xy 30.874806 -301.114219) (xy 30.79476 -301.14906) (xy 30.71183 -301.176332) (xy 30.626729 -301.195799)
			(xy 30.54019 -301.207295) (xy 30.452958 -301.21072) (xy 30.365784 -301.206045) (xy 30.279418 -301.19331)
			(xy 30.194605 -301.172625) (xy 30.112074 -301.144168) (xy 30.032536 -301.108183) (xy 29.994352 -301.087028)
			(xy 29.9749 -301.076527) (xy 29.933268 -301.061677) (xy 29.889696 -301.054253) (xy 29.845495 -301.05448)
			(xy 29.802001 -301.062352) (xy 29.760525 -301.07763) (xy 29.722318 -301.099855) (xy 29.688532 -301.128354)
			(xy 29.660187 -301.16227) (xy 29.638137 -301.200578) (xy 29.623049 -301.242124) (xy 29.615376 -301.285654)
			(xy 29.614876 -301.307754) (xy 29.614876 -301.772066) (xy 29.61535 -301.794174) (xy 29.623 -301.837722)
			(xy 29.638074 -301.879288) (xy 29.660116 -301.917616) (xy 29.688462 -301.95155) (xy 29.722255 -301.980063)
			(xy 29.760474 -302.002294) (xy 29.801966 -302.017573) (xy 29.845475 -302.025438) (xy 29.88969 -302.02565)
			(xy 29.933273 -302.018204) (xy 29.974909 -302.003324) (xy 29.994352 -301.992792) (xy 30.032527 -301.971621)
			(xy 30.112065 -301.935636) (xy 30.194595 -301.907178) (xy 30.279409 -301.886492) (xy 30.365774 -301.873756)
			(xy 30.452948 -301.86908) (xy 30.54018 -301.872504) (xy 30.626719 -301.883999) (xy 30.711821 -301.903466)
			(xy 30.794751 -301.930737) (xy 30.874797 -301.965577) (xy 30.951269 -302.007686) (xy 31.023509 -302.056702)
			(xy 31.090895 -302.112203) (xy 31.152846 -302.173711) (xy 31.208829 -302.240696) (xy 31.258363 -302.312582)
			(xy 31.301021 -302.38875) (xy 31.336435 -302.468543) (xy 31.3643 -302.551276) (xy 31.384377 -302.636235)
			(xy 31.396494 -302.72269) (xy 31.400544 -302.809895) (xy 31.398525 -302.85336) (xy 34.599874 -302.85336)
			(xy 34.599874 -302.76646) (xy 34.607892 -302.679931) (xy 34.62386 -302.594511) (xy 34.647641 -302.510929)
			(xy 34.679033 -302.429897) (xy 34.717767 -302.352108) (xy 34.763514 -302.278224) (xy 34.815883 -302.208877)
			(xy 34.874427 -302.144657) (xy 34.938647 -302.086113) (xy 35.007994 -302.033744) (xy 35.081878 -301.987997)
			(xy 35.159667 -301.949263) (xy 35.240699 -301.917871) (xy 35.324281 -301.89409) (xy 35.409701 -301.878122)
			(xy 35.49623 -301.870104) (xy 35.58313 -301.870104) (xy 35.669659 -301.878122) (xy 35.755079 -301.89409)
			(xy 35.838661 -301.917871) (xy 35.919693 -301.949263) (xy 35.997482 -301.987997) (xy 36.071366 -302.033744)
			(xy 36.140713 -302.086113) (xy 36.204933 -302.144657) (xy 36.263477 -302.208877) (xy 36.315846 -302.278224)
			(xy 36.357258 -302.345106) (xy 38.511578 -302.345106) (xy 38.515465 -302.29075) (xy 38.527048 -302.237501)
			(xy 38.546092 -302.186443) (xy 38.572208 -302.138614) (xy 38.604866 -302.09499) (xy 38.6434 -302.056457)
			(xy 38.687026 -302.023801) (xy 38.734855 -301.997686) (xy 38.785915 -301.978644) (xy 38.839164 -301.967063)
			(xy 38.89352 -301.963178) (xy 38.947875 -301.967068) (xy 39.001123 -301.978655) (xy 39.052181 -301.997703)
			(xy 39.100007 -302.023822) (xy 39.122096 -302.039782) (xy 39.141108 -302.053378) (xy 39.182991 -302.07411)
			(xy 39.227959 -302.086836) (xy 39.274496 -302.091126) (xy 39.321033 -302.086836) (xy 39.366001 -302.07411)
			(xy 39.407884 -302.053378) (xy 39.426896 -302.039782) (xy 39.448994 -302.023835) (xy 39.496819 -301.997715)
			(xy 39.547875 -301.978668) (xy 39.601122 -301.96708) (xy 39.655476 -301.963189) (xy 39.70983 -301.967073)
			(xy 39.763079 -301.978654) (xy 39.814137 -301.997695) (xy 39.861965 -302.023809) (xy 39.90559 -302.056464)
			(xy 39.944124 -302.094996) (xy 39.976781 -302.138619) (xy 40.002897 -302.186446) (xy 40.021941 -302.237504)
			(xy 40.033524 -302.290752) (xy 40.037411 -302.345106) (xy 40.398271 -302.345106) (xy 40.402158 -302.290749)
			(xy 40.413741 -302.237498) (xy 40.432786 -302.186438) (xy 40.458904 -302.138608) (xy 40.491563 -302.094983)
			(xy 40.530098 -302.056449) (xy 40.573726 -302.023793) (xy 40.621557 -301.997678) (xy 40.672618 -301.978636)
			(xy 40.725869 -301.967055) (xy 40.780227 -301.963171) (xy 40.834583 -301.967062) (xy 40.887833 -301.978651)
			(xy 40.938891 -301.9977) (xy 40.986719 -302.023821) (xy 41.008808 -302.039782) (xy 41.02782 -302.053378)
			(xy 41.069703 -302.07411) (xy 41.114671 -302.086836) (xy 41.161208 -302.091126) (xy 41.207745 -302.086836)
			(xy 41.252713 -302.07411) (xy 41.294596 -302.053378) (xy 41.313608 -302.039782) (xy 41.335705 -302.023836)
			(xy 41.38353 -301.997718) (xy 41.434584 -301.978672) (xy 41.48783 -301.967086) (xy 41.542183 -301.963196)
			(xy 41.596535 -301.967081) (xy 41.649782 -301.978662) (xy 41.700838 -301.997704) (xy 41.748665 -302.023817)
			(xy 41.792289 -302.056472) (xy 41.830821 -302.095003) (xy 41.863476 -302.138625) (xy 41.889592 -302.186451)
			(xy 41.908634 -302.237507) (xy 41.920217 -302.290753) (xy 41.924104 -302.345106) (xy 42.639246 -302.345106)
			(xy 42.643133 -302.290743) (xy 42.654719 -302.237487) (xy 42.673766 -302.186422) (xy 42.699887 -302.138588)
			(xy 42.732551 -302.094958) (xy 42.771092 -302.056422) (xy 42.814725 -302.023763) (xy 42.862562 -301.997647)
			(xy 42.91363 -301.978606) (xy 42.966887 -301.967027) (xy 43.02125 -301.963146) (xy 43.075613 -301.967041)
			(xy 43.128867 -301.978634) (xy 43.17993 -301.997689) (xy 43.22776 -302.023818) (xy 43.24985 -302.039782)
			(xy 43.268862 -302.053378) (xy 43.310745 -302.07411) (xy 43.355713 -302.086836) (xy 43.40225 -302.091126)
			(xy 43.448787 -302.086836) (xy 43.493755 -302.07411) (xy 43.535638 -302.053378) (xy 43.55465 -302.039782)
			(xy 43.576749 -302.023831) (xy 43.624577 -301.997704) (xy 43.675637 -301.97865) (xy 43.728889 -301.967057)
			(xy 43.78325 -301.963162) (xy 43.837611 -301.967043) (xy 43.890866 -301.978621) (xy 43.941931 -301.997662)
			(xy 43.989766 -302.023777) (xy 44.033398 -302.056434) (xy 44.071937 -302.094969) (xy 44.104599 -302.138596)
			(xy 44.13072 -302.186428) (xy 44.149766 -302.237491) (xy 44.161351 -302.290745) (xy 44.165238 -302.345106)
			(xy 44.543255 -302.345106) (xy 44.547143 -302.290745) (xy 44.558727 -302.237491) (xy 44.577774 -302.186428)
			(xy 44.603894 -302.138596) (xy 44.636555 -302.094968) (xy 44.675094 -302.056432) (xy 44.718725 -302.023774)
			(xy 44.76656 -301.997659) (xy 44.817625 -301.978617) (xy 44.87088 -301.967037) (xy 44.925241 -301.963155)
			(xy 44.979602 -301.967049) (xy 45.032854 -301.978641) (xy 45.083915 -301.997693) (xy 45.131744 -302.023819)
			(xy 45.153834 -302.039782) (xy 45.172846 -302.053378) (xy 45.214729 -302.07411) (xy 45.259697 -302.086836)
			(xy 45.306234 -302.091126) (xy 45.352771 -302.086836) (xy 45.397739 -302.07411) (xy 45.439622 -302.053378)
			(xy 45.458634 -302.039782) (xy 45.480731 -302.023838) (xy 45.528553 -301.997724) (xy 45.579606 -301.978682)
			(xy 45.632848 -301.967099) (xy 45.687197 -301.963212) (xy 45.741546 -301.967099) (xy 45.794789 -301.978681)
			(xy 45.845842 -301.997722) (xy 45.893665 -302.023836) (xy 45.937284 -302.056489) (xy 45.975813 -302.095018)
			(xy 46.008466 -302.138638) (xy 46.034579 -302.186461) (xy 46.05362 -302.237514) (xy 46.065202 -302.290757)
			(xy 46.069088 -302.345106) (xy 46.0652 -302.399455) (xy 46.053617 -302.452698) (xy 46.034574 -302.50375)
			(xy 46.00846 -302.551572) (xy 45.975805 -302.595191) (xy 45.937275 -302.633719) (xy 45.893655 -302.666371)
			(xy 45.845831 -302.692483) (xy 45.794778 -302.711523) (xy 45.741535 -302.723103) (xy 45.687185 -302.726988)
			(xy 45.632836 -302.723099) (xy 45.579594 -302.711514) (xy 45.528542 -302.692471) (xy 45.480721 -302.666355)
			(xy 45.458634 -302.650398) (xy 45.439622 -302.636802) (xy 45.397739 -302.61607) (xy 45.352771 -302.603344)
			(xy 45.306234 -302.599054) (xy 45.259697 -302.603344) (xy 45.214729 -302.61607) (xy 45.172846 -302.636802)
			(xy 45.153834 -302.650398) (xy 45.131754 -302.666374) (xy 45.083926 -302.692502) (xy 45.032866 -302.711556)
			(xy 44.979614 -302.723149) (xy 44.925253 -302.727045) (xy 44.870892 -302.723164) (xy 44.817637 -302.711586)
			(xy 44.766571 -302.692546) (xy 44.718735 -302.666432) (xy 44.675103 -302.633776) (xy 44.636563 -302.595242)
			(xy 44.6039 -302.551615) (xy 44.577779 -302.503783) (xy 44.558731 -302.45272) (xy 44.547144 -302.399467)
			(xy 44.543255 -302.345106) (xy 44.165238 -302.345106) (xy 44.161349 -302.399467) (xy 44.149763 -302.45272)
			(xy 44.130715 -302.503782) (xy 44.104593 -302.551614) (xy 44.071929 -302.59524) (xy 44.033389 -302.633774)
			(xy 43.989756 -302.66643) (xy 43.94192 -302.692543) (xy 43.890854 -302.711582) (xy 43.837599 -302.723159)
			(xy 43.783238 -302.727038) (xy 43.728878 -302.723141) (xy 43.675626 -302.711547) (xy 43.624566 -302.692491)
			(xy 43.576739 -302.666362) (xy 43.55465 -302.650398) (xy 43.535638 -302.636802) (xy 43.493755 -302.61607)
			(xy 43.448787 -302.603344) (xy 43.40225 -302.599054) (xy 43.355713 -302.603344) (xy 43.310745 -302.61607)
			(xy 43.268862 -302.636802) (xy 43.24985 -302.650398) (xy 43.22777 -302.666376) (xy 43.17994 -302.692506)
			(xy 43.128879 -302.711562) (xy 43.075625 -302.723157) (xy 43.021262 -302.727054) (xy 42.966899 -302.723175)
			(xy 42.913641 -302.711597) (xy 42.862573 -302.692558) (xy 42.814735 -302.666443) (xy 42.771101 -302.633786)
			(xy 42.732559 -302.595251) (xy 42.699894 -302.551623) (xy 42.673771 -302.503789) (xy 42.654722 -302.452725)
			(xy 42.643135 -302.399469) (xy 42.639246 -302.345106) (xy 41.924104 -302.345106) (xy 41.920215 -302.399459)
			(xy 41.908631 -302.452705) (xy 41.889587 -302.50376) (xy 41.86347 -302.551585) (xy 41.830813 -302.595206)
			(xy 41.79228 -302.633736) (xy 41.748655 -302.666389) (xy 41.700828 -302.692501) (xy 41.649771 -302.711541)
			(xy 41.596523 -302.72312) (xy 41.542171 -302.727004) (xy 41.487818 -302.723112) (xy 41.434573 -302.711524)
			(xy 41.383519 -302.692477) (xy 41.335695 -302.666357) (xy 41.313608 -302.650398) (xy 41.294596 -302.636802)
			(xy 41.252713 -302.61607) (xy 41.207745 -302.603344) (xy 41.161208 -302.599054) (xy 41.114671 -302.603344)
			(xy 41.069703 -302.61607) (xy 41.02782 -302.636802) (xy 41.008808 -302.650398) (xy 40.986729 -302.666372)
			(xy 40.938902 -302.692495) (xy 40.887845 -302.711546) (xy 40.834595 -302.723136) (xy 40.780239 -302.727029)
			(xy 40.725881 -302.723147) (xy 40.672629 -302.711568) (xy 40.621568 -302.692527) (xy 40.573736 -302.666414)
			(xy 40.530107 -302.633758) (xy 40.491571 -302.595226) (xy 40.45891 -302.551602) (xy 40.432791 -302.503773)
			(xy 40.413745 -302.452713) (xy 40.402159 -302.399463) (xy 40.398271 -302.345106) (xy 40.037411 -302.345106)
			(xy 40.033522 -302.39946) (xy 40.021938 -302.452708) (xy 40.002892 -302.503765) (xy 39.976775 -302.551591)
			(xy 39.944116 -302.595213) (xy 39.905581 -302.633744) (xy 39.861955 -302.666398) (xy 39.814126 -302.69251)
			(xy 39.763067 -302.71155) (xy 39.709818 -302.723128) (xy 39.655464 -302.727011) (xy 39.60111 -302.723118)
			(xy 39.547863 -302.711529) (xy 39.496808 -302.69248) (xy 39.448984 -302.666358) (xy 39.426896 -302.650398)
			(xy 39.407884 -302.636802) (xy 39.366001 -302.61607) (xy 39.321033 -302.603344) (xy 39.274496 -302.599054)
			(xy 39.227959 -302.603344) (xy 39.182991 -302.61607) (xy 39.141108 -302.636802) (xy 39.122096 -302.650398)
			(xy 39.100017 -302.666371) (xy 39.052191 -302.692492) (xy 39.001135 -302.711541) (xy 38.947887 -302.72313)
			(xy 38.893532 -302.727022) (xy 38.839176 -302.723139) (xy 38.785926 -302.711559) (xy 38.734866 -302.692519)
			(xy 38.687036 -302.666405) (xy 38.643409 -302.633751) (xy 38.604874 -302.595219) (xy 38.572215 -302.551596)
			(xy 38.546097 -302.503768) (xy 38.527051 -302.45271) (xy 38.515466 -302.399461) (xy 38.511578 -302.345106)
			(xy 36.357258 -302.345106) (xy 36.361593 -302.352108) (xy 36.400327 -302.429897) (xy 36.431719 -302.510929)
			(xy 36.4555 -302.594511) (xy 36.471468 -302.679931) (xy 36.479486 -302.76646) (xy 36.479988 -302.80991)
			(xy 36.479486 -302.85336) (xy 36.471468 -302.939889) (xy 36.4555 -303.025309) (xy 36.431719 -303.108891)
			(xy 36.400327 -303.189923) (xy 36.361593 -303.267712) (xy 36.315846 -303.341596) (xy 36.263477 -303.410943)
			(xy 36.204933 -303.475163) (xy 36.140713 -303.533707) (xy 36.071366 -303.586076) (xy 36.033121 -303.609756)
			(xy 66.181732 -303.609756) (xy 66.181732 -302.711358) (xy 66.182199 -302.680178) (xy 66.189822 -302.618287)
			(xy 66.204958 -302.557792) (xy 66.227382 -302.499605) (xy 66.256757 -302.444597) (xy 66.29264 -302.393597)
			(xy 66.334494 -302.34737) (xy 66.381689 -302.30661) (xy 66.433515 -302.271931) (xy 66.489195 -302.243852)
			(xy 66.547892 -302.222797) (xy 66.608724 -302.209081) (xy 66.670778 -302.20291) (xy 66.73312 -302.204377)
			(xy 66.794814 -302.213461) (xy 66.854933 -302.230024) (xy 66.912575 -302.253817) (xy 66.966872 -302.284484)
			(xy 67.01701 -302.321563) (xy 67.062234 -302.364498) (xy 67.082416 -302.38827) (xy 67.097043 -302.405285)
			(xy 67.131197 -302.434379) (xy 67.169926 -302.457029) (xy 67.212028 -302.47253) (xy 67.256198 -302.480403)
			(xy 67.301064 -302.480403) (xy 67.345234 -302.47253) (xy 67.387336 -302.457029) (xy 67.426065 -302.434379)
			(xy 67.460219 -302.405285) (xy 67.474846 -302.38827) (xy 67.494994 -302.364597) (xy 67.540046 -302.321765)
			(xy 67.589986 -302.284748) (xy 67.644068 -302.254097) (xy 67.701484 -302.230272) (xy 67.761377 -302.213627)
			(xy 67.822854 -302.20441) (xy 67.884995 -302.202761) (xy 67.946874 -302.208702) (xy 68.007566 -302.222146)
			(xy 68.066165 -302.242892) (xy 68.121797 -302.27063) (xy 68.173631 -302.304945) (xy 68.220892 -302.345326)
			(xy 68.262876 -302.39117) (xy 68.281296 -302.41621) (xy 68.29443 -302.433839) (xy 68.325722 -302.464713)
			(xy 68.361862 -302.489738) (xy 68.401772 -302.508166) (xy 68.444258 -302.519449) (xy 68.488052 -302.523247)
			(xy 68.531846 -302.519449) (xy 68.574332 -302.508166) (xy 68.614242 -302.489738) (xy 68.650382 -302.464713)
			(xy 68.681674 -302.433839) (xy 68.694808 -302.41621) (xy 68.713501 -302.390872) (xy 68.756115 -302.344516)
			(xy 68.804126 -302.303777) (xy 68.8568 -302.269278) (xy 68.913332 -302.241547) (xy 68.972854 -302.221007)
			(xy 69.034457 -302.207975) (xy 69.097198 -302.202649) (xy 69.160116 -302.20511) (xy 69.222249 -302.215321)
			(xy 69.282646 -302.233126) (xy 69.340382 -302.258252) (xy 69.394574 -302.290314) (xy 69.444393 -302.328823)
			(xy 69.489075 -302.373188) (xy 69.508878 -302.397668) (xy 69.523485 -302.415499) (xy 69.557985 -302.446061)
			(xy 69.597428 -302.469904) (xy 69.640523 -302.486247) (xy 69.685858 -302.494555) (xy 69.731948 -302.494555)
			(xy 69.777283 -302.486247) (xy 69.820378 -302.469904) (xy 69.859821 -302.446061) (xy 69.894321 -302.415499)
			(xy 69.908928 -302.397668) (xy 69.928732 -302.373192) (xy 69.973412 -302.328829) (xy 70.023229 -302.290325)
			(xy 70.077419 -302.258267) (xy 70.135154 -302.233148) (xy 70.19555 -302.215351) (xy 70.25768 -302.20515)
			(xy 70.320595 -302.2027) (xy 70.331311 -302.203612) (xy 95.969072 -302.203612) (xy 95.973143 -302.14799)
			(xy 95.985269 -302.093553) (xy 96.005192 -302.041462) (xy 96.032488 -301.992827) (xy 96.066574 -301.948684)
			(xy 96.106723 -301.909975) (xy 96.152081 -301.877524) (xy 96.201681 -301.852023) (xy 96.254465 -301.834016)
			(xy 96.309308 -301.823886) (xy 96.365042 -301.821849) (xy 96.420479 -301.827949) (xy 96.474436 -301.842055)
			(xy 96.525765 -301.863867) (xy 96.573371 -301.892921) (xy 96.616239 -301.928596) (xy 96.653456 -301.970133)
			(xy 96.684229 -302.016646) (xy 96.707901 -302.067143) (xy 96.723969 -302.12055) (xy 96.732089 -302.175726)
			(xy 96.732598 -302.203612) (xy 96.732089 -302.231498) (xy 96.723969 -302.286674) (xy 96.707901 -302.340081)
			(xy 96.684229 -302.390578) (xy 96.653456 -302.437091) (xy 96.616239 -302.478628) (xy 96.573371 -302.514303)
			(xy 96.525765 -302.543357) (xy 96.474436 -302.565169) (xy 96.420479 -302.579275) (xy 96.365042 -302.585375)
			(xy 96.309308 -302.583338) (xy 96.254465 -302.573208) (xy 96.201681 -302.555201) (xy 96.152081 -302.5297)
			(xy 96.106723 -302.497249) (xy 96.066574 -302.45854) (xy 96.032488 -302.414397) (xy 96.005192 -302.365762)
			(xy 95.985269 -302.313671) (xy 95.973143 -302.259234) (xy 95.969072 -302.203612) (xy 70.331311 -302.203612)
			(xy 70.383331 -302.208039) (xy 70.444928 -302.221085) (xy 70.504441 -302.241638) (xy 70.560961 -302.269384)
			(xy 70.613621 -302.303898) (xy 70.661615 -302.344652) (xy 70.704209 -302.39102) (xy 70.74075 -302.442295)
			(xy 70.770679 -302.497689) (xy 70.793538 -302.556356) (xy 70.808976 -302.617397) (xy 70.816757 -302.679877)
			(xy 70.817232 -302.711358) (xy 70.817232 -303.529746) (xy 95.24187 -303.529746) (xy 95.245941 -303.474124)
			(xy 95.258067 -303.419687) (xy 95.27799 -303.367596) (xy 95.305286 -303.318961) (xy 95.339372 -303.274818)
			(xy 95.379521 -303.236109) (xy 95.424879 -303.203658) (xy 95.474479 -303.178157) (xy 95.527263 -303.16015)
			(xy 95.582106 -303.15002) (xy 95.63784 -303.147983) (xy 95.693277 -303.154083) (xy 95.747234 -303.168189)
			(xy 95.798563 -303.190001) (xy 95.846169 -303.219055) (xy 95.889037 -303.25473) (xy 95.926254 -303.296267)
			(xy 95.957027 -303.34278) (xy 95.980699 -303.393277) (xy 95.996767 -303.446684) (xy 96.004887 -303.50186)
			(xy 96.005396 -303.529746) (xy 96.004887 -303.557632) (xy 95.996767 -303.612808) (xy 95.980699 -303.666215)
			(xy 95.957027 -303.716712) (xy 95.926254 -303.763225) (xy 95.889037 -303.804762) (xy 95.846169 -303.840437)
			(xy 95.798563 -303.869491) (xy 95.747234 -303.891303) (xy 95.693277 -303.905409) (xy 95.63784 -303.911509)
			(xy 95.582106 -303.909472) (xy 95.527263 -303.899342) (xy 95.474479 -303.881335) (xy 95.424879 -303.855834)
			(xy 95.379521 -303.823383) (xy 95.339372 -303.784674) (xy 95.305286 -303.740531) (xy 95.27799 -303.691896)
			(xy 95.258067 -303.639805) (xy 95.245941 -303.585368) (xy 95.24187 -303.529746) (xy 70.817232 -303.529746)
			(xy 70.817232 -303.609756) (xy 70.816708 -303.642482) (xy 70.808319 -303.707393) (xy 70.791674 -303.770692)
			(xy 70.767048 -303.831333) (xy 70.734848 -303.888315) (xy 70.715632 -303.91481) (xy 70.690232 -303.948592)
			(xy 70.690232 -303.965864) (xy 70.674992 -303.965864) (xy 70.639178 -303.99609) (xy 70.614001 -304.016943)
			(xy 70.559269 -304.052694) (xy 70.500404 -304.081133) (xy 70.438379 -304.101788) (xy 70.374217 -304.114319)
			(xy 70.308978 -304.118519) (xy 70.243739 -304.114319) (xy 70.179577 -304.101788) (xy 70.117552 -304.081133)
			(xy 70.058687 -304.052694) (xy 70.003955 -304.016943) (xy 69.978778 -303.99609) (xy 69.942964 -303.965864)
			(xy 69.927724 -303.965864) (xy 69.927724 -303.948592) (xy 69.902324 -303.91481) (xy 69.879373 -303.882978)
			(xy 69.842507 -303.813703) (xy 69.828918 -303.776888) (xy 69.82333 -303.762163) (xy 69.806066 -303.735832)
			(xy 69.782875 -303.714536) (xy 69.755171 -303.699573) (xy 69.724646 -303.691856) (xy 69.69316 -303.691856)
			(xy 69.662635 -303.699573) (xy 69.634931 -303.714536) (xy 69.61174 -303.735832) (xy 69.594476 -303.762163)
			(xy 69.588888 -303.776888) (xy 69.575318 -303.813712) (xy 69.538447 -303.882986) (xy 69.515482 -303.91481)
			(xy 69.490336 -303.948592) (xy 69.490336 -303.965864) (xy 69.474842 -303.965864) (xy 69.439028 -303.99609)
			(xy 69.413851 -304.016943) (xy 69.359119 -304.052694) (xy 69.300254 -304.081133) (xy 69.238229 -304.101788)
			(xy 69.174067 -304.114319) (xy 69.108828 -304.118519) (xy 69.043589 -304.114319) (xy 68.979427 -304.101788)
			(xy 68.917402 -304.081133) (xy 68.858537 -304.052694) (xy 68.803805 -304.016943) (xy 68.778628 -303.99609)
			(xy 68.742814 -303.965864) (xy 68.72732 -303.965864) (xy 68.72732 -303.948592) (xy 68.702174 -303.91481)
			(xy 68.694808 -303.904904) (xy 68.681674 -303.887275) (xy 68.650382 -303.856401) (xy 68.614242 -303.831376)
			(xy 68.574332 -303.812948) (xy 68.531846 -303.801665) (xy 68.488052 -303.797867) (xy 68.444258 -303.801665)
			(xy 68.401772 -303.812948) (xy 68.361862 -303.831376) (xy 68.325722 -303.856401) (xy 68.29443 -303.887275)
			(xy 68.281296 -303.904904) (xy 68.27393 -303.91481) (xy 68.248784 -303.948592) (xy 68.248784 -303.965864)
			(xy 68.23329 -303.965864) (xy 68.197476 -303.99609) (xy 68.172299 -304.016943) (xy 68.117567 -304.052694)
			(xy 68.058702 -304.081133) (xy 67.996677 -304.101788) (xy 67.932515 -304.114319) (xy 67.867276 -304.118519)
			(xy 67.802037 -304.114319) (xy 67.737875 -304.101788) (xy 67.67585 -304.081133) (xy 67.616985 -304.052694)
			(xy 67.562253 -304.016943) (xy 67.537076 -303.99609) (xy 67.501262 -303.965864) (xy 67.485768 -303.965864)
			(xy 67.485768 -303.948592) (xy 67.460622 -303.91481) (xy 67.441381 -303.888274) (xy 67.409147 -303.831199)
			(xy 67.39636 -303.801018) (xy 67.389583 -303.78568) (xy 67.369319 -303.758977) (xy 67.342803 -303.738468)
			(xy 67.311862 -303.725569) (xy 67.278631 -303.721168) (xy 67.2454 -303.725569) (xy 67.214459 -303.738468)
			(xy 67.187943 -303.758977) (xy 67.167679 -303.78568) (xy 67.160902 -303.801018) (xy 67.14811 -303.831197)
			(xy 67.115879 -303.888273) (xy 67.09664 -303.91481) (xy 67.07124 -303.948592) (xy 67.07124 -303.965864)
			(xy 67.056 -303.965864) (xy 67.020186 -303.99609) (xy 66.995009 -304.016943) (xy 66.940277 -304.052694)
			(xy 66.881412 -304.081133) (xy 66.819387 -304.101788) (xy 66.755225 -304.114319) (xy 66.689986 -304.118519)
			(xy 66.624747 -304.114319) (xy 66.560585 -304.101788) (xy 66.49856 -304.081133) (xy 66.439695 -304.052694)
			(xy 66.384963 -304.016943) (xy 66.359786 -303.99609) (xy 66.323972 -303.965864) (xy 66.308732 -303.965864)
			(xy 66.308732 -303.948592) (xy 66.283332 -303.91481) (xy 66.264093 -303.888329) (xy 66.231866 -303.831354)
			(xy 66.207228 -303.770711) (xy 66.190587 -303.707405) (xy 66.18222 -303.642485) (xy 66.181732 -303.609756)
			(xy 36.033121 -303.609756) (xy 35.997482 -303.631823) (xy 35.919693 -303.670557) (xy 35.838661 -303.701949)
			(xy 35.755079 -303.72573) (xy 35.669659 -303.741698) (xy 35.58313 -303.749716) (xy 35.49623 -303.749716)
			(xy 35.409701 -303.741698) (xy 35.324281 -303.72573) (xy 35.240699 -303.701949) (xy 35.159667 -303.670557)
			(xy 35.081878 -303.631823) (xy 35.007994 -303.586076) (xy 34.938647 -303.533707) (xy 34.874427 -303.475163)
			(xy 34.815883 -303.410943) (xy 34.763514 -303.341596) (xy 34.717767 -303.267712) (xy 34.679033 -303.189923)
			(xy 34.647641 -303.108891) (xy 34.62386 -303.025309) (xy 34.607892 -302.939889) (xy 34.599874 -302.85336)
			(xy 31.398525 -302.85336) (xy 31.396494 -302.8971) (xy 31.384379 -302.983555) (xy 31.364303 -303.068514)
			(xy 31.336438 -303.151247) (xy 31.301025 -303.231041) (xy 31.258368 -303.30721) (xy 31.208835 -303.379096)
			(xy 31.152853 -303.446082) (xy 31.090902 -303.50759) (xy 31.023517 -303.563092) (xy 30.951278 -303.612109)
			(xy 30.874806 -303.654219) (xy 30.79476 -303.68906) (xy 30.71183 -303.716332) (xy 30.626729 -303.735799)
			(xy 30.54019 -303.747295) (xy 30.452958 -303.75072) (xy 30.365784 -303.746045) (xy 30.279418 -303.73331)
			(xy 30.194605 -303.712625) (xy 30.112074 -303.684168) (xy 30.032536 -303.648183) (xy 29.994352 -303.627028)
			(xy 29.9749 -303.616527) (xy 29.933268 -303.601677) (xy 29.889696 -303.594253) (xy 29.845495 -303.59448)
			(xy 29.802001 -303.602352) (xy 29.760525 -303.61763) (xy 29.722318 -303.639855) (xy 29.688532 -303.668354)
			(xy 29.660187 -303.70227) (xy 29.638137 -303.740578) (xy 29.623049 -303.782124) (xy 29.615376 -303.825654)
			(xy 29.614876 -303.847754) (xy 29.614876 -304.312066) (xy 29.61535 -304.334174) (xy 29.619241 -304.356323)
			(xy 38.468176 -304.356323) (xy 38.47206 -304.301969) (xy 38.48364 -304.24872) (xy 38.502681 -304.197662)
			(xy 38.528794 -304.149833) (xy 38.561448 -304.106208) (xy 38.599978 -304.067674) (xy 38.6436 -304.035015)
			(xy 38.691426 -304.008897) (xy 38.742483 -303.989851) (xy 38.79573 -303.978266) (xy 38.850084 -303.974376)
			(xy 38.904438 -303.978261) (xy 38.957686 -303.989842) (xy 39.008744 -304.008883) (xy 39.056572 -304.034997)
			(xy 39.078662 -304.050954) (xy 39.097674 -304.06455) (xy 39.139557 -304.085282) (xy 39.184525 -304.098008)
			(xy 39.231062 -304.102298) (xy 39.277599 -304.098008) (xy 39.322567 -304.085282) (xy 39.36445 -304.06455)
			(xy 39.383462 -304.050954) (xy 39.405587 -304.035042) (xy 39.453413 -304.00892) (xy 39.504469 -303.989871)
			(xy 39.557718 -303.978283) (xy 39.612073 -303.974391) (xy 39.666429 -303.978275) (xy 39.719679 -303.989856)
			(xy 39.770739 -304.008898) (xy 39.818568 -304.035013) (xy 39.862194 -304.06767) (xy 39.900728 -304.106203)
			(xy 39.933385 -304.149828) (xy 39.9595 -304.197658) (xy 39.978543 -304.248717) (xy 39.990124 -304.301967)
			(xy 39.994009 -304.356323) (xy 40.354869 -304.356323) (xy 40.358753 -304.301967) (xy 40.370334 -304.248717)
			(xy 40.389375 -304.197657) (xy 40.415489 -304.149827) (xy 40.448145 -304.106201) (xy 40.486676 -304.067666)
			(xy 40.5303 -304.035007) (xy 40.578128 -304.008888) (xy 40.629186 -303.989843) (xy 40.682435 -303.978258)
			(xy 40.73679 -303.974369) (xy 40.791146 -303.978255) (xy 40.844396 -303.989838) (xy 40.895455 -304.008881)
			(xy 40.943284 -304.034996) (xy 40.965374 -304.050954) (xy 40.984386 -304.06455) (xy 41.026269 -304.085282)
			(xy 41.071237 -304.098008) (xy 41.117774 -304.102298) (xy 41.164311 -304.098008) (xy 41.209279 -304.085282)
			(xy 41.251162 -304.06455) (xy 41.270174 -304.050954) (xy 41.292298 -304.035043) (xy 41.340123 -304.008923)
			(xy 41.391179 -303.989876) (xy 41.444426 -303.978289) (xy 41.49878 -303.974398) (xy 41.553134 -303.978283)
			(xy 41.606382 -303.989865) (xy 41.65744 -304.008907) (xy 41.705268 -304.035021) (xy 41.748892 -304.067678)
			(xy 41.787424 -304.10621) (xy 41.82008 -304.149834) (xy 41.846195 -304.197662) (xy 41.865236 -304.24872)
			(xy 41.876817 -304.301968) (xy 41.880702 -304.356323) (xy 42.595843 -304.356323) (xy 42.599728 -304.301961)
			(xy 42.611311 -304.248706) (xy 42.630355 -304.197641) (xy 42.656473 -304.149807) (xy 42.689133 -304.106176)
			(xy 42.72767 -304.067638) (xy 42.771299 -304.034977) (xy 42.819133 -304.008858) (xy 42.870198 -303.989813)
			(xy 42.923453 -303.97823) (xy 42.977814 -303.974343) (xy 43.032176 -303.978234) (xy 43.08543 -303.989821)
			(xy 43.136493 -304.00887) (xy 43.184325 -304.034993) (xy 43.206416 -304.050954) (xy 43.225428 -304.06455)
			(xy 43.267311 -304.085282) (xy 43.312279 -304.098008) (xy 43.358816 -304.102298) (xy 43.405353 -304.098008)
			(xy 43.450321 -304.085282) (xy 43.492204 -304.06455) (xy 43.511216 -304.050954) (xy 43.533339 -304.035047)
			(xy 43.581162 -304.008933) (xy 43.632213 -303.989892) (xy 43.685455 -303.97831) (xy 43.739804 -303.974423)
			(xy 43.794152 -303.978311) (xy 43.847394 -303.989894) (xy 43.898445 -304.008937) (xy 43.946267 -304.035051)
			(xy 43.989885 -304.067705) (xy 44.028412 -304.106235) (xy 44.061064 -304.149855) (xy 44.087174 -304.197679)
			(xy 44.106213 -304.248732) (xy 44.117793 -304.301974) (xy 44.121677 -304.356323) (xy 44.499853 -304.356323)
			(xy 44.503738 -304.301963) (xy 44.51532 -304.24871) (xy 44.534363 -304.197647) (xy 44.560479 -304.149815)
			(xy 44.593137 -304.106186) (xy 44.631672 -304.067649) (xy 44.6753 -304.034988) (xy 44.723131 -304.00887)
			(xy 44.774193 -303.989825) (xy 44.827446 -303.97824) (xy 44.881805 -303.974353) (xy 44.936164 -303.978242)
			(xy 44.989417 -303.989828) (xy 45.040478 -304.008874) (xy 45.088309 -304.034994) (xy 45.1104 -304.050954)
			(xy 45.129412 -304.06455) (xy 45.171295 -304.085282) (xy 45.216263 -304.098008) (xy 45.2628 -304.102298)
			(xy 45.309337 -304.098008) (xy 45.354305 -304.085282) (xy 45.396188 -304.06455) (xy 45.4152 -304.050954)
			(xy 45.437324 -304.035045) (xy 45.485147 -304.00893) (xy 45.5362 -303.989886) (xy 45.589444 -303.978302)
			(xy 45.643795 -303.974414) (xy 45.698145 -303.978301) (xy 45.75139 -303.989883) (xy 45.802443 -304.008925)
			(xy 45.850267 -304.03504) (xy 45.893888 -304.067695) (xy 45.932417 -304.106225) (xy 45.96507 -304.149847)
			(xy 45.991182 -304.197673) (xy 46.010222 -304.248727) (xy 46.021802 -304.301972) (xy 46.025686 -304.356323)
			(xy 46.021795 -304.410673) (xy 46.010209 -304.463917) (xy 45.991163 -304.514969) (xy 45.965045 -304.562791)
			(xy 45.932387 -304.606409) (xy 45.893853 -304.644935) (xy 45.850229 -304.677585) (xy 45.802402 -304.703694)
			(xy 45.751346 -304.72273) (xy 45.698624 -304.734192) (xy 57.58881 -304.734192) (xy 57.592699 -304.679842)
			(xy 57.604283 -304.626599) (xy 57.623326 -304.575546) (xy 57.649441 -304.527724) (xy 57.682096 -304.484105)
			(xy 57.720627 -304.445577) (xy 57.764249 -304.412925) (xy 57.812074 -304.386813) (xy 57.863128 -304.367774)
			(xy 57.916372 -304.356194) (xy 57.970722 -304.35231) (xy 58.025071 -304.356201) (xy 58.078314 -304.367786)
			(xy 58.129366 -304.386831) (xy 58.177187 -304.412948) (xy 58.199274 -304.428906) (xy 58.218286 -304.442502)
			(xy 58.260169 -304.463234) (xy 58.305137 -304.47596) (xy 58.351674 -304.48025) (xy 58.398211 -304.47596)
			(xy 58.443179 -304.463234) (xy 58.485062 -304.442502) (xy 58.504074 -304.428906) (xy 58.52615 -304.412925)
			(xy 58.573978 -304.386798) (xy 58.625037 -304.367745) (xy 58.678289 -304.356152) (xy 58.732649 -304.352257)
			(xy 58.787009 -304.356138) (xy 58.840264 -304.367716) (xy 58.891329 -304.386756) (xy 58.939164 -304.41287)
			(xy 58.982796 -304.445526) (xy 59.021335 -304.484059) (xy 59.053998 -304.527686) (xy 59.08012 -304.575517)
			(xy 59.099167 -304.626579) (xy 59.110754 -304.679832) (xy 59.114643 -304.734192) (xy 59.475503 -304.734192)
			(xy 59.479392 -304.67984) (xy 59.490976 -304.626596) (xy 59.51002 -304.575542) (xy 59.536136 -304.527718)
			(xy 59.568793 -304.484097) (xy 59.607325 -304.445569) (xy 59.650949 -304.412916) (xy 59.698775 -304.386805)
			(xy 59.749831 -304.367766) (xy 59.803077 -304.356186) (xy 59.857428 -304.352303) (xy 59.91178 -304.356195)
			(xy 59.965024 -304.367782) (xy 60.016077 -304.386828) (xy 60.063899 -304.412947) (xy 60.085986 -304.428906)
			(xy 60.104998 -304.442502) (xy 60.146881 -304.463234) (xy 60.191849 -304.47596) (xy 60.238386 -304.48025)
			(xy 60.284923 -304.47596) (xy 60.329891 -304.463234) (xy 60.371774 -304.442502) (xy 60.390786 -304.428906)
			(xy 60.412861 -304.412926) (xy 60.460689 -304.386801) (xy 60.511747 -304.367749) (xy 60.564998 -304.356158)
			(xy 60.619356 -304.352264) (xy 60.673714 -304.356146) (xy 60.726968 -304.367724) (xy 60.778031 -304.386764)
			(xy 60.825864 -304.412878) (xy 60.869494 -304.445534) (xy 60.908032 -304.484066) (xy 60.940693 -304.527692)
			(xy 60.966814 -304.575521) (xy 60.985861 -304.626582) (xy 60.997447 -304.679833) (xy 61.001336 -304.734192)
			(xy 61.716478 -304.734192) (xy 61.720367 -304.679835) (xy 61.731953 -304.626584) (xy 61.751 -304.575525)
			(xy 61.77712 -304.527697) (xy 61.809781 -304.484073) (xy 61.848319 -304.445541) (xy 61.891948 -304.412887)
			(xy 61.939781 -304.386775) (xy 61.990843 -304.367736) (xy 62.044095 -304.356158) (xy 62.098452 -304.352278)
			(xy 62.152809 -304.356173) (xy 62.206058 -304.367765) (xy 62.257115 -304.386818) (xy 62.30494 -304.412944)
			(xy 62.327028 -304.428906) (xy 62.34604 -304.442502) (xy 62.387923 -304.463234) (xy 62.432891 -304.47596)
			(xy 62.479428 -304.48025) (xy 62.525965 -304.47596) (xy 62.570933 -304.463234) (xy 62.612816 -304.442502)
			(xy 62.631828 -304.428906) (xy 62.653902 -304.41293) (xy 62.701727 -304.386811) (xy 62.752781 -304.367766)
			(xy 62.806027 -304.356179) (xy 62.860379 -304.352289) (xy 62.914732 -304.356174) (xy 62.967979 -304.367754)
			(xy 63.019036 -304.386794) (xy 63.066863 -304.412907) (xy 63.110487 -304.445561) (xy 63.14902 -304.484091)
			(xy 63.181677 -304.527713) (xy 63.207794 -304.575538) (xy 63.226838 -304.626593) (xy 63.238422 -304.679839)
			(xy 63.242311 -304.734192) (xy 63.620487 -304.734192) (xy 63.624376 -304.679837) (xy 63.635962 -304.626589)
			(xy 63.655008 -304.575532) (xy 63.681126 -304.527705) (xy 63.713786 -304.484082) (xy 63.752321 -304.445552)
			(xy 63.795948 -304.412898) (xy 63.843779 -304.386786) (xy 63.894838 -304.367747) (xy 63.948088 -304.356169)
			(xy 64.002443 -304.352287) (xy 64.056798 -304.356181) (xy 64.110045 -304.367772) (xy 64.1611 -304.386822)
			(xy 64.208925 -304.412945) (xy 64.231012 -304.428906) (xy 64.250024 -304.442502) (xy 64.291907 -304.463234)
			(xy 64.336875 -304.47596) (xy 64.383412 -304.48025) (xy 64.429949 -304.47596) (xy 64.474917 -304.463234)
			(xy 64.5168 -304.442502) (xy 64.535812 -304.428906) (xy 64.557887 -304.412928) (xy 64.605712 -304.386808)
			(xy 64.656768 -304.367759) (xy 64.710016 -304.356171) (xy 64.76437 -304.352279) (xy 64.818726 -304.356163)
			(xy 64.871975 -304.367743) (xy 64.923034 -304.386783) (xy 64.970863 -304.412896) (xy 65.01449 -304.445551)
			(xy 65.053024 -304.484082) (xy 65.085683 -304.527705) (xy 65.111801 -304.575532) (xy 65.130847 -304.626589)
			(xy 65.142432 -304.679837) (xy 65.146321 -304.734192) (xy 65.142434 -304.788547) (xy 65.141766 -304.791618)
			(xy 94.531178 -304.791618) (xy 94.535249 -304.735996) (xy 94.547375 -304.681559) (xy 94.567298 -304.629468)
			(xy 94.594594 -304.580833) (xy 94.62868 -304.53669) (xy 94.668829 -304.497981) (xy 94.714187 -304.46553)
			(xy 94.763787 -304.440029) (xy 94.816571 -304.422022) (xy 94.871414 -304.411892) (xy 94.927148 -304.409855)
			(xy 94.982585 -304.415955) (xy 95.036542 -304.430061) (xy 95.087871 -304.451873) (xy 95.135477 -304.480927)
			(xy 95.178345 -304.516602) (xy 95.215562 -304.558139) (xy 95.246335 -304.604652) (xy 95.270007 -304.655149)
			(xy 95.286075 -304.708556) (xy 95.294195 -304.763732) (xy 95.294704 -304.791618) (xy 95.294195 -304.819504)
			(xy 95.286075 -304.87468) (xy 95.270007 -304.928087) (xy 95.246335 -304.978584) (xy 95.215562 -305.025097)
			(xy 95.178345 -305.066634) (xy 95.135477 -305.102309) (xy 95.087871 -305.131363) (xy 95.036542 -305.153175)
			(xy 94.982585 -305.167281) (xy 94.927148 -305.173381) (xy 94.871414 -305.171344) (xy 94.816571 -305.161214)
			(xy 94.763787 -305.143207) (xy 94.714187 -305.117706) (xy 94.668829 -305.085255) (xy 94.62868 -305.046546)
			(xy 94.594594 -305.002403) (xy 94.567298 -304.953768) (xy 94.547375 -304.901677) (xy 94.535249 -304.84724)
			(xy 94.531178 -304.791618) (xy 65.141766 -304.791618) (xy 65.130851 -304.841795) (xy 65.111808 -304.892853)
			(xy 65.085692 -304.940681) (xy 65.053035 -304.984306) (xy 65.014502 -305.022838) (xy 64.970878 -305.055495)
			(xy 64.923049 -305.08161) (xy 64.871991 -305.100653) (xy 64.818742 -305.112235) (xy 64.764387 -305.116121)
			(xy 64.710032 -305.112231) (xy 64.656785 -305.100645) (xy 64.605728 -305.081599) (xy 64.557901 -305.055481)
			(xy 64.535812 -305.039522) (xy 64.5168 -305.025926) (xy 64.474917 -305.005194) (xy 64.429949 -304.992468)
			(xy 64.383412 -304.988178) (xy 64.336875 -304.992468) (xy 64.291907 -305.005194) (xy 64.250024 -305.025926)
			(xy 64.231012 -305.039522) (xy 64.20891 -305.055464) (xy 64.161085 -305.081585) (xy 64.110029 -305.100633)
			(xy 64.056781 -305.112221) (xy 64.002426 -305.116113) (xy 63.948071 -305.112229) (xy 63.894822 -305.100648)
			(xy 63.843763 -305.081607) (xy 63.795934 -305.055493) (xy 63.752309 -305.022837) (xy 63.713775 -304.984305)
			(xy 63.681117 -304.940681) (xy 63.655001 -304.892853) (xy 63.635957 -304.841795) (xy 63.624374 -304.788547)
			(xy 63.620487 -304.734192) (xy 63.242311 -304.734192) (xy 63.238425 -304.788544) (xy 63.226843 -304.841791)
			(xy 63.207801 -304.892847) (xy 63.181686 -304.940673) (xy 63.149031 -304.984296) (xy 63.1105 -305.022828)
			(xy 63.066877 -305.055484) (xy 63.019051 -305.081599) (xy 62.967995 -305.100641) (xy 62.914749 -305.112224)
			(xy 62.860396 -305.116111) (xy 62.806044 -305.112223) (xy 62.752798 -305.100639) (xy 62.701742 -305.081596)
			(xy 62.653917 -305.05548) (xy 62.631828 -305.039522) (xy 62.612816 -305.025926) (xy 62.570933 -305.005194)
			(xy 62.525965 -304.992468) (xy 62.479428 -304.988178) (xy 62.432891 -304.992468) (xy 62.387923 -305.005194)
			(xy 62.34604 -305.025926) (xy 62.327028 -305.039522) (xy 62.304926 -305.055465) (xy 62.257099 -305.081589)
			(xy 62.206042 -305.100639) (xy 62.152792 -305.112229) (xy 62.098436 -305.116122) (xy 62.044078 -305.112239)
			(xy 61.990827 -305.100659) (xy 61.939765 -305.081618) (xy 61.891934 -305.055504) (xy 61.848306 -305.022848)
			(xy 61.80977 -304.984315) (xy 61.777111 -304.940689) (xy 61.750993 -304.892859) (xy 61.731948 -304.841799)
			(xy 61.720365 -304.788549) (xy 61.716478 -304.734192) (xy 61.001336 -304.734192) (xy 60.997449 -304.78855)
			(xy 60.985866 -304.841802) (xy 60.966821 -304.892863) (xy 60.940703 -304.940694) (xy 60.908043 -304.984321)
			(xy 60.869506 -305.022855) (xy 60.825878 -305.055513) (xy 60.778046 -305.081629) (xy 60.726984 -305.100671)
			(xy 60.673731 -305.112252) (xy 60.619372 -305.116136) (xy 60.565014 -305.112244) (xy 60.511763 -305.100655)
			(xy 60.460704 -305.081606) (xy 60.412876 -305.055483) (xy 60.390786 -305.039522) (xy 60.371774 -305.025926)
			(xy 60.329891 -305.005194) (xy 60.284923 -304.992468) (xy 60.238386 -304.988178) (xy 60.191849 -304.992468)
			(xy 60.146881 -305.005194) (xy 60.104998 -305.025926) (xy 60.085986 -305.039522) (xy 60.063885 -305.055462)
			(xy 60.016061 -305.081579) (xy 59.965008 -305.100623) (xy 59.911763 -305.112208) (xy 59.857412 -305.116097)
			(xy 59.80306 -305.112211) (xy 59.749815 -305.10063) (xy 59.69876 -305.081588) (xy 59.650935 -305.055475)
			(xy 59.607313 -305.02282) (xy 59.568782 -304.98429) (xy 59.536127 -304.940668) (xy 59.510013 -304.892843)
			(xy 59.490971 -304.841788) (xy 59.479389 -304.788543) (xy 59.475503 -304.734192) (xy 59.114643 -304.734192)
			(xy 59.110756 -304.788552) (xy 59.099172 -304.841805) (xy 59.080126 -304.892868) (xy 59.054007 -304.9407)
			(xy 59.021346 -304.984328) (xy 58.982808 -305.022863) (xy 58.939178 -305.055521) (xy 58.891344 -305.081637)
			(xy 58.84028 -305.100679) (xy 58.787026 -305.11226) (xy 58.732666 -305.116143) (xy 58.678306 -305.11225)
			(xy 58.625054 -305.10066) (xy 58.573993 -305.081609) (xy 58.526164 -305.055484) (xy 58.504074 -305.039522)
			(xy 58.485062 -305.025926) (xy 58.443179 -305.005194) (xy 58.398211 -304.992468) (xy 58.351674 -304.988178)
			(xy 58.305137 -304.992468) (xy 58.260169 -305.005194) (xy 58.218286 -305.025926) (xy 58.199274 -305.039522)
			(xy 58.177173 -305.055461) (xy 58.12935 -305.081576) (xy 58.078298 -305.100618) (xy 58.025055 -305.112202)
			(xy 57.970705 -305.11609) (xy 57.916355 -305.112203) (xy 57.863112 -305.100621) (xy 57.812058 -305.08158)
			(xy 57.764235 -305.055466) (xy 57.720615 -305.022812) (xy 57.682085 -304.984283) (xy 57.649432 -304.940662)
			(xy 57.623319 -304.892838) (xy 57.604278 -304.841785) (xy 57.592696 -304.788541) (xy 57.58881 -304.734192)
			(xy 45.698624 -304.734192) (xy 45.6981 -304.734306) (xy 45.643749 -304.738186) (xy 45.589399 -304.734291)
			(xy 45.536157 -304.722701) (xy 45.485106 -304.703652) (xy 45.437285 -304.67753) (xy 45.4152 -304.66157)
			(xy 45.396188 -304.647974) (xy 45.354305 -304.627242) (xy 45.309337 -304.614516) (xy 45.2628 -304.610226)
			(xy 45.216263 -304.614516) (xy 45.171295 -304.627242) (xy 45.129412 -304.647974) (xy 45.1104 -304.66157)
			(xy 45.088347 -304.677581) (xy 45.04052 -304.703707) (xy 44.989461 -304.72276) (xy 44.93621 -304.734352)
			(xy 44.881851 -304.738247) (xy 44.827491 -304.734366) (xy 44.774237 -304.722788) (xy 44.723173 -304.703749)
			(xy 44.675338 -304.677636) (xy 44.631707 -304.644981) (xy 44.593167 -304.606449) (xy 44.560504 -304.562824)
			(xy 44.534381 -304.514994) (xy 44.515332 -304.463934) (xy 44.503744 -304.410682) (xy 44.499853 -304.356323)
			(xy 44.121677 -304.356323) (xy 44.117786 -304.410671) (xy 44.1062 -304.463912) (xy 44.087155 -304.514963)
			(xy 44.061039 -304.562783) (xy 44.028382 -304.6064) (xy 43.989851 -304.644925) (xy 43.946229 -304.677574)
			(xy 43.898404 -304.703682) (xy 43.84735 -304.722719) (xy 43.794107 -304.734295) (xy 43.739758 -304.738177)
			(xy 43.68541 -304.734283) (xy 43.63217 -304.722695) (xy 43.58112 -304.703648) (xy 43.533301 -304.677529)
			(xy 43.511216 -304.66157) (xy 43.492204 -304.647974) (xy 43.450321 -304.627242) (xy 43.405353 -304.614516)
			(xy 43.358816 -304.610226) (xy 43.312279 -304.614516) (xy 43.267311 -304.627242) (xy 43.225428 -304.647974)
			(xy 43.206416 -304.66157) (xy 43.184363 -304.677583) (xy 43.136534 -304.703711) (xy 43.085474 -304.722766)
			(xy 43.032221 -304.73436) (xy 42.97786 -304.738257) (xy 42.923498 -304.734377) (xy 42.870241 -304.7228)
			(xy 42.819175 -304.703761) (xy 42.771338 -304.677647) (xy 42.727704 -304.644992) (xy 42.689163 -304.606458)
			(xy 42.656497 -304.562832) (xy 42.630374 -304.515) (xy 42.611324 -304.463938) (xy 42.599735 -304.410684)
			(xy 42.595843 -304.356323) (xy 41.880702 -304.356323) (xy 41.876811 -304.410677) (xy 41.865223 -304.463923)
			(xy 41.846176 -304.514979) (xy 41.820055 -304.562804) (xy 41.787394 -304.606424) (xy 41.748858 -304.644952)
			(xy 41.70523 -304.677603) (xy 41.657399 -304.703712) (xy 41.606339 -304.722748) (xy 41.553089 -304.734323)
			(xy 41.498734 -304.738202) (xy 41.444381 -304.734305) (xy 41.391135 -304.722711) (xy 41.340082 -304.703658)
			(xy 41.29226 -304.677532) (xy 41.270174 -304.66157) (xy 41.251162 -304.647974) (xy 41.209279 -304.627242)
			(xy 41.164311 -304.614516) (xy 41.117774 -304.610226) (xy 41.071237 -304.614516) (xy 41.026269 -304.627242)
			(xy 40.984386 -304.647974) (xy 40.965374 -304.66157) (xy 40.943322 -304.677579) (xy 40.895496 -304.703701)
			(xy 40.844439 -304.72275) (xy 40.791191 -304.734339) (xy 40.736836 -304.738231) (xy 40.68248 -304.734349)
			(xy 40.62923 -304.72277) (xy 40.578169 -304.70373) (xy 40.530339 -304.677618) (xy 40.486711 -304.644964)
			(xy 40.448174 -304.606434) (xy 40.415514 -304.562811) (xy 40.389394 -304.514984) (xy 40.370347 -304.463927)
			(xy 40.35876 -304.410678) (xy 40.354869 -304.356323) (xy 39.994009 -304.356323) (xy 39.990118 -304.410678)
			(xy 39.97853 -304.463927) (xy 39.959481 -304.514984) (xy 39.93336 -304.56281) (xy 39.900698 -304.606431)
			(xy 39.862159 -304.64496) (xy 39.81853 -304.677612) (xy 39.770697 -304.703721) (xy 39.719635 -304.722757)
			(xy 39.666384 -304.734331) (xy 39.612028 -304.738209) (xy 39.557673 -304.734311) (xy 39.504426 -304.722716)
			(xy 39.453371 -304.703661) (xy 39.405548 -304.677533) (xy 39.383462 -304.66157) (xy 39.36445 -304.647974)
			(xy 39.322567 -304.627242) (xy 39.277599 -304.614516) (xy 39.231062 -304.610226) (xy 39.184525 -304.614516)
			(xy 39.139557 -304.627242) (xy 39.097674 -304.647974) (xy 39.078662 -304.66157) (xy 39.05661 -304.677578)
			(xy 39.008785 -304.703698) (xy 38.95773 -304.722745) (xy 38.904483 -304.734332) (xy 38.850129 -304.738224)
			(xy 38.795775 -304.734341) (xy 38.742526 -304.722761) (xy 38.691468 -304.703722) (xy 38.643639 -304.67761)
			(xy 38.600013 -304.644956) (xy 38.561478 -304.606427) (xy 38.528819 -304.562805) (xy 38.5027 -304.514979)
			(xy 38.483653 -304.463923) (xy 38.472067 -304.410677) (xy 38.468176 -304.356323) (xy 29.619241 -304.356323)
			(xy 29.623 -304.377722) (xy 29.638074 -304.419288) (xy 29.660116 -304.457616) (xy 29.688462 -304.49155)
			(xy 29.722255 -304.520063) (xy 29.760474 -304.542294) (xy 29.801966 -304.557573) (xy 29.845475 -304.565438)
			(xy 29.88969 -304.56565) (xy 29.933273 -304.558204) (xy 29.974909 -304.543324) (xy 29.994352 -304.532792)
			(xy 30.032527 -304.511621) (xy 30.112065 -304.475636) (xy 30.194595 -304.447178) (xy 30.279409 -304.426492)
			(xy 30.365774 -304.413756) (xy 30.452948 -304.40908) (xy 30.54018 -304.412504) (xy 30.626719 -304.423999)
			(xy 30.711821 -304.443466) (xy 30.794751 -304.470737) (xy 30.874797 -304.505577) (xy 30.951269 -304.547686)
			(xy 31.023509 -304.596702) (xy 31.090895 -304.652203) (xy 31.152846 -304.713711) (xy 31.208829 -304.780696)
			(xy 31.258363 -304.852582) (xy 31.301021 -304.92875) (xy 31.336435 -305.008543) (xy 31.3643 -305.091276)
			(xy 31.384377 -305.176235) (xy 31.396494 -305.26269) (xy 31.400544 -305.349895) (xy 31.398525 -305.39336)
			(xy 34.599874 -305.39336) (xy 34.599874 -305.30646) (xy 34.607892 -305.219931) (xy 34.62386 -305.134511)
			(xy 34.647641 -305.050929) (xy 34.679033 -304.969897) (xy 34.717767 -304.892108) (xy 34.763514 -304.818224)
			(xy 34.815883 -304.748877) (xy 34.874427 -304.684657) (xy 34.938647 -304.626113) (xy 35.007994 -304.573744)
			(xy 35.081878 -304.527997) (xy 35.159667 -304.489263) (xy 35.240699 -304.457871) (xy 35.324281 -304.43409)
			(xy 35.409701 -304.418122) (xy 35.49623 -304.410104) (xy 35.58313 -304.410104) (xy 35.669659 -304.418122)
			(xy 35.755079 -304.43409) (xy 35.838661 -304.457871) (xy 35.919693 -304.489263) (xy 35.997482 -304.527997)
			(xy 36.071366 -304.573744) (xy 36.140713 -304.626113) (xy 36.204933 -304.684657) (xy 36.263477 -304.748877)
			(xy 36.315846 -304.818224) (xy 36.361593 -304.892108) (xy 36.400327 -304.969897) (xy 36.431719 -305.050929)
			(xy 36.4555 -305.134511) (xy 36.471468 -305.219931) (xy 36.479486 -305.30646) (xy 36.479988 -305.34991)
			(xy 36.479486 -305.39336) (xy 36.471468 -305.479889) (xy 36.456973 -305.557428) (xy 51.27498 -305.557428)
			(xy 52.926996 -305.557428) (xy 52.926996 -306.00015) (xy 93.984824 -306.00015) (xy 93.988895 -305.944528)
			(xy 94.001021 -305.890091) (xy 94.020944 -305.838) (xy 94.04824 -305.789365) (xy 94.082326 -305.745222)
			(xy 94.122475 -305.706513) (xy 94.167833 -305.674062) (xy 94.217433 -305.648561) (xy 94.270217 -305.630554)
			(xy 94.32506 -305.620424) (xy 94.380794 -305.618387) (xy 94.436231 -305.624487) (xy 94.490188 -305.638593)
			(xy 94.541517 -305.660405) (xy 94.589123 -305.689459) (xy 94.631991 -305.725134) (xy 94.669208 -305.766671)
			(xy 94.699981 -305.813184) (xy 94.723653 -305.863681) (xy 94.739721 -305.917088) (xy 94.747841 -305.972264)
			(xy 94.74835 -306.00015) (xy 94.747841 -306.028036) (xy 94.739721 -306.083212) (xy 94.723653 -306.136619)
			(xy 94.699981 -306.187116) (xy 94.669208 -306.233629) (xy 94.631991 -306.275166) (xy 94.589123 -306.310841)
			(xy 94.541517 -306.339895) (xy 94.490188 -306.361707) (xy 94.436231 -306.375813) (xy 94.380794 -306.381913)
			(xy 94.32506 -306.379876) (xy 94.270217 -306.369746) (xy 94.217433 -306.351739) (xy 94.167833 -306.326238)
			(xy 94.122475 -306.293787) (xy 94.082326 -306.255078) (xy 94.04824 -306.210935) (xy 94.020944 -306.1623)
			(xy 94.001021 -306.110209) (xy 93.988895 -306.055772) (xy 93.984824 -306.00015) (xy 52.926996 -306.00015)
			(xy 52.926996 -306.775425) (xy 57.588765 -306.775425) (xy 57.59265 -306.721069) (xy 57.60423 -306.667818)
			(xy 57.623271 -306.616758) (xy 57.649385 -306.568928) (xy 57.682041 -306.525301) (xy 57.720572 -306.486765)
			(xy 57.764196 -306.454105) (xy 57.812024 -306.427987) (xy 57.863083 -306.408941) (xy 57.916332 -306.397355)
			(xy 57.970688 -306.393465) (xy 58.025044 -306.397351) (xy 58.078294 -306.408934) (xy 58.129354 -306.427977)
			(xy 58.177183 -306.454092) (xy 58.199274 -306.47005) (xy 58.218286 -306.483646) (xy 58.260169 -306.504378)
			(xy 58.305137 -306.517104) (xy 58.351674 -306.521394) (xy 58.398211 -306.517104) (xy 58.443179 -306.504378)
			(xy 58.485062 -306.483646) (xy 58.504074 -306.47005) (xy 58.526202 -306.454144) (xy 58.574027 -306.428025)
			(xy 58.625082 -306.408978) (xy 58.678329 -306.397392) (xy 58.732682 -306.393502) (xy 58.787036 -306.397387)
			(xy 58.840284 -306.408968) (xy 58.891341 -306.42801) (xy 58.939168 -306.454125) (xy 58.982792 -306.486782)
			(xy 59.021323 -306.525314) (xy 59.053979 -306.568938) (xy 59.080093 -306.616766) (xy 59.099134 -306.667823)
			(xy 59.110714 -306.721071) (xy 59.114598 -306.775425) (xy 59.475458 -306.775425) (xy 59.479343 -306.721067)
			(xy 59.490923 -306.667815) (xy 59.509965 -306.616754) (xy 59.53608 -306.568922) (xy 59.568737 -306.525293)
			(xy 59.607271 -306.486757) (xy 59.650896 -306.454097) (xy 59.698726 -306.427978) (xy 59.749786 -306.408932)
			(xy 59.803037 -306.397347) (xy 59.857395 -306.393458) (xy 59.911753 -306.397345) (xy 59.965004 -306.408929)
			(xy 60.016065 -306.427974) (xy 60.063895 -306.454091) (xy 60.085986 -306.47005) (xy 60.104998 -306.483646)
			(xy 60.146881 -306.504378) (xy 60.191849 -306.517104) (xy 60.238386 -306.521394) (xy 60.284923 -306.517104)
			(xy 60.329891 -306.504378) (xy 60.371774 -306.483646) (xy 60.390786 -306.47005) (xy 60.412914 -306.454146)
			(xy 60.460738 -306.428028) (xy 60.511792 -306.408983) (xy 60.565037 -306.397398) (xy 60.619389 -306.393509)
			(xy 60.673741 -306.397395) (xy 60.726987 -306.408977) (xy 60.778042 -306.428019) (xy 60.825868 -306.454134)
			(xy 60.86949 -306.486789) (xy 60.90802 -306.525321) (xy 60.940674 -306.568944) (xy 60.966787 -306.616771)
			(xy 60.985827 -306.667827) (xy 60.997407 -306.721073) (xy 61.001291 -306.775425) (xy 61.716433 -306.775425)
			(xy 61.720318 -306.721061) (xy 61.731901 -306.667804) (xy 61.750945 -306.616737) (xy 61.777064 -306.568901)
			(xy 61.809725 -306.525269) (xy 61.848264 -306.486729) (xy 61.891895 -306.454067) (xy 61.939731 -306.427948)
			(xy 61.990798 -306.408902) (xy 62.044055 -306.397319) (xy 62.098419 -306.393433) (xy 62.152782 -306.397324)
			(xy 62.206038 -306.408913) (xy 62.257103 -306.427963) (xy 62.304936 -306.454088) (xy 62.327028 -306.47005)
			(xy 62.34604 -306.483646) (xy 62.387923 -306.504378) (xy 62.432891 -306.517104) (xy 62.479428 -306.521394)
			(xy 62.525965 -306.517104) (xy 62.570933 -306.504378) (xy 62.612816 -306.483646) (xy 62.631828 -306.47005)
			(xy 62.653955 -306.454149) (xy 62.701776 -306.428038) (xy 62.752826 -306.408999) (xy 62.806067 -306.397419)
			(xy 62.860413 -306.393534) (xy 62.914759 -306.397423) (xy 62.967999 -306.409006) (xy 63.019048 -306.428049)
			(xy 63.066867 -306.454163) (xy 63.110483 -306.486817) (xy 63.149008 -306.525346) (xy 63.181657 -306.568965)
			(xy 63.207767 -306.616787) (xy 63.226804 -306.667838) (xy 63.238383 -306.721079) (xy 63.242266 -306.775425)
			(xy 63.620443 -306.775425) (xy 63.624327 -306.721064) (xy 63.635909 -306.667808) (xy 63.654953 -306.616743)
			(xy 63.68107 -306.568909) (xy 63.71373 -306.525278) (xy 63.752266 -306.48674) (xy 63.795896 -306.454079)
			(xy 63.843729 -306.427959) (xy 63.894793 -306.408914) (xy 63.948048 -306.39733) (xy 64.00241 -306.393443)
			(xy 64.056771 -306.397332) (xy 64.110025 -306.408919) (xy 64.161088 -306.427967) (xy 64.208921 -306.454089)
			(xy 64.231012 -306.47005) (xy 64.250024 -306.483646) (xy 64.291907 -306.504378) (xy 64.336875 -306.517104)
			(xy 64.383412 -306.521394) (xy 64.429949 -306.517104) (xy 64.474917 -306.504378) (xy 64.5168 -306.483646)
			(xy 64.535812 -306.47005) (xy 64.557939 -306.454148) (xy 64.605761 -306.428034) (xy 64.656813 -306.408993)
			(xy 64.710055 -306.397411) (xy 64.764404 -306.393524) (xy 64.818752 -306.397412) (xy 64.871994 -306.408995)
			(xy 64.923046 -306.428038) (xy 64.970867 -306.454152) (xy 65.014486 -306.486807) (xy 65.053013 -306.525336)
			(xy 65.085664 -306.568957) (xy 65.111774 -306.616781) (xy 65.130813 -306.667834) (xy 65.142392 -306.721076)
			(xy 65.146276 -306.775425) (xy 65.142385 -306.829773) (xy 65.130799 -306.883015) (xy 65.111753 -306.934065)
			(xy 65.085636 -306.981885) (xy 65.05298 -307.025502) (xy 65.014448 -307.064026) (xy 64.970825 -307.096675)
			(xy 64.923 -307.122783) (xy 64.871946 -307.141819) (xy 64.818703 -307.153395) (xy 64.764354 -307.157276)
			(xy 64.710006 -307.153382) (xy 64.656765 -307.141793) (xy 64.605716 -307.122745) (xy 64.557897 -307.096625)
			(xy 64.535812 -307.080666) (xy 64.5168 -307.06707) (xy 64.474917 -307.046338) (xy 64.429949 -307.033612)
			(xy 64.383412 -307.029322) (xy 64.336875 -307.033612) (xy 64.291907 -307.046338) (xy 64.250024 -307.06707)
			(xy 64.231012 -307.080666) (xy 64.208963 -307.096684) (xy 64.161134 -307.122812) (xy 64.110074 -307.141867)
			(xy 64.056821 -307.153461) (xy 64.00246 -307.157357) (xy 63.948098 -307.153478) (xy 63.894842 -307.141901)
			(xy 63.843775 -307.122862) (xy 63.795938 -307.096749) (xy 63.752305 -307.064093) (xy 63.713763 -307.02556)
			(xy 63.681098 -306.981934) (xy 63.654974 -306.934102) (xy 63.635924 -306.88304) (xy 63.624334 -306.829786)
			(xy 63.620443 -306.775425) (xy 63.242266 -306.775425) (xy 63.238376 -306.829771) (xy 63.22679 -306.88301)
			(xy 63.207746 -306.934059) (xy 63.18163 -306.981877) (xy 63.148975 -307.025492) (xy 63.110445 -307.064016)
			(xy 63.066825 -307.096664) (xy 63.019002 -307.122772) (xy 62.96795 -307.141808) (xy 62.914709 -307.153384)
			(xy 62.860363 -307.157266) (xy 62.806017 -307.153374) (xy 62.752778 -307.141787) (xy 62.70173 -307.122741)
			(xy 62.653912 -307.096624) (xy 62.631828 -307.080666) (xy 62.612816 -307.06707) (xy 62.570933 -307.046338)
			(xy 62.525965 -307.033612) (xy 62.479428 -307.029322) (xy 62.432891 -307.033612) (xy 62.387923 -307.046338)
			(xy 62.34604 -307.06707) (xy 62.327028 -307.080666) (xy 62.304979 -307.096685) (xy 62.257149 -307.122816)
			(xy 62.206087 -307.141873) (xy 62.152832 -307.153469) (xy 62.098469 -307.157367) (xy 62.044105 -307.153488)
			(xy 61.990846 -307.141912) (xy 61.939777 -307.122873) (xy 61.891938 -307.09676) (xy 61.848302 -307.064104)
			(xy 61.809758 -307.025569) (xy 61.777091 -306.981942) (xy 61.750966 -306.934109) (xy 61.731915 -306.883044)
			(xy 61.720325 -306.829788) (xy 61.716433 -306.775425) (xy 61.001291 -306.775425) (xy 60.9974 -306.829777)
			(xy 60.985813 -306.883022) (xy 60.966766 -306.934075) (xy 60.940647 -306.981898) (xy 60.907987 -307.025517)
			(xy 60.869452 -307.064044) (xy 60.825826 -307.096693) (xy 60.777997 -307.122802) (xy 60.726939 -307.141837)
			(xy 60.673691 -307.153412) (xy 60.619339 -307.157291) (xy 60.564987 -307.153395) (xy 60.511744 -307.141803)
			(xy 60.460692 -307.122751) (xy 60.412871 -307.096627) (xy 60.390786 -307.080666) (xy 60.371774 -307.06707)
			(xy 60.329891 -307.046338) (xy 60.284923 -307.033612) (xy 60.238386 -307.029322) (xy 60.191849 -307.033612)
			(xy 60.146881 -307.046338) (xy 60.104998 -307.06707) (xy 60.085986 -307.080666) (xy 60.063938 -307.096681)
			(xy 60.016111 -307.122805) (xy 59.965052 -307.141857) (xy 59.911803 -307.153447) (xy 59.857445 -307.157342)
			(xy 59.803087 -307.15346) (xy 59.749835 -307.141882) (xy 59.698772 -307.122843) (xy 59.650939 -307.09673)
			(xy 59.607309 -307.064076) (xy 59.56877 -307.025545) (xy 59.536108 -306.981921) (xy 59.509986 -306.934092)
			(xy 59.490938 -306.883033) (xy 59.47935 -306.829783) (xy 59.475458 -306.775425) (xy 59.114598 -306.775425)
			(xy 59.110707 -306.829779) (xy 59.09912 -306.883025) (xy 59.080072 -306.93408) (xy 59.053951 -306.981904)
			(xy 59.02129 -307.025524) (xy 58.982754 -307.064051) (xy 58.939126 -307.096702) (xy 58.891295 -307.12281)
			(xy 58.840235 -307.141846) (xy 58.786986 -307.15342) (xy 58.732632 -307.157298) (xy 58.678279 -307.153401)
			(xy 58.625034 -307.141808) (xy 58.573981 -307.122754) (xy 58.52616 -307.096628) (xy 58.504074 -307.080666)
			(xy 58.485062 -307.06707) (xy 58.443179 -307.046338) (xy 58.398211 -307.033612) (xy 58.351674 -307.029322)
			(xy 58.305137 -307.033612) (xy 58.260169 -307.046338) (xy 58.218286 -307.06707) (xy 58.199274 -307.080666)
			(xy 58.177226 -307.09668) (xy 58.1294 -307.122802) (xy 58.078343 -307.141852) (xy 58.025094 -307.153441)
			(xy 57.970738 -307.157335) (xy 57.916382 -307.153452) (xy 57.863131 -307.141874) (xy 57.81207 -307.122834)
			(xy 57.764239 -307.096722) (xy 57.720611 -307.064068) (xy 57.682074 -307.025538) (xy 57.649412 -306.981915)
			(xy 57.623292 -306.934088) (xy 57.604244 -306.88303) (xy 57.592657 -306.829781) (xy 57.588765 -306.775425)
			(xy 52.926996 -306.775425) (xy 52.926996 -307.208936) (xy 51.27498 -307.208936) (xy 51.27498 -305.557428)
			(xy 36.456973 -305.557428) (xy 36.4555 -305.565309) (xy 36.431719 -305.648891) (xy 36.400327 -305.729923)
			(xy 36.361593 -305.807712) (xy 36.315846 -305.881596) (xy 36.263477 -305.950943) (xy 36.204933 -306.015163)
			(xy 36.140713 -306.073707) (xy 36.071366 -306.126076) (xy 35.997482 -306.171823) (xy 35.919693 -306.210557)
			(xy 35.838661 -306.241949) (xy 35.755079 -306.26573) (xy 35.669659 -306.281698) (xy 35.58313 -306.289716)
			(xy 35.49623 -306.289716) (xy 35.409701 -306.281698) (xy 35.324281 -306.26573) (xy 35.240699 -306.241949)
			(xy 35.159667 -306.210557) (xy 35.081878 -306.171823) (xy 35.007994 -306.126076) (xy 34.938647 -306.073707)
			(xy 34.874427 -306.015163) (xy 34.815883 -305.950943) (xy 34.763514 -305.881596) (xy 34.717767 -305.807712)
			(xy 34.679033 -305.729923) (xy 34.647641 -305.648891) (xy 34.62386 -305.565309) (xy 34.607892 -305.479889)
			(xy 34.599874 -305.39336) (xy 31.398525 -305.39336) (xy 31.396494 -305.4371) (xy 31.384379 -305.523555)
			(xy 31.364303 -305.608514) (xy 31.336438 -305.691247) (xy 31.301025 -305.771041) (xy 31.258368 -305.84721)
			(xy 31.208835 -305.919096) (xy 31.152853 -305.986082) (xy 31.090902 -306.04759) (xy 31.023517 -306.103092)
			(xy 30.951278 -306.152109) (xy 30.874806 -306.194219) (xy 30.79476 -306.22906) (xy 30.71183 -306.256332)
			(xy 30.626729 -306.275799) (xy 30.54019 -306.287295) (xy 30.452958 -306.29072) (xy 30.365784 -306.286045)
			(xy 30.279418 -306.27331) (xy 30.194605 -306.252625) (xy 30.112074 -306.224168) (xy 30.032536 -306.188183)
			(xy 29.994352 -306.167028) (xy 29.9749 -306.156527) (xy 29.933268 -306.141677) (xy 29.889696 -306.134253)
			(xy 29.845495 -306.13448) (xy 29.802001 -306.142352) (xy 29.760525 -306.15763) (xy 29.722318 -306.179855)
			(xy 29.688532 -306.208354) (xy 29.660187 -306.24227) (xy 29.638137 -306.280578) (xy 29.623049 -306.322124)
			(xy 29.615376 -306.365654) (xy 29.614876 -306.387754) (xy 29.614876 -306.423737) (xy 47.775358 -306.423737)
			(xy 47.775358 -306.342627) (xy 47.783308 -306.261908) (xy 47.799131 -306.182357) (xy 47.822676 -306.104741)
			(xy 47.853715 -306.029805) (xy 47.89195 -305.958273) (xy 47.937012 -305.890833) (xy 47.988467 -305.828134)
			(xy 48.04582 -305.770781) (xy 48.108519 -305.719326) (xy 48.175959 -305.674264) (xy 48.247491 -305.636029)
			(xy 48.322427 -305.60499) (xy 48.400043 -305.581445) (xy 48.479594 -305.565622) (xy 48.560313 -305.557672)
			(xy 48.641423 -305.557672) (xy 48.722142 -305.565622) (xy 48.801693 -305.581445) (xy 48.879309 -305.60499)
			(xy 48.954245 -305.636029) (xy 49.025777 -305.674264) (xy 49.093217 -305.719326) (xy 49.155916 -305.770781)
			(xy 49.213269 -305.828134) (xy 49.264724 -305.890833) (xy 49.309786 -305.958273) (xy 49.348021 -306.029805)
			(xy 49.37906 -306.104741) (xy 49.402605 -306.182357) (xy 49.418428 -306.261908) (xy 49.426378 -306.342627)
			(xy 49.426876 -306.383182) (xy 49.426378 -306.423737) (xy 49.418428 -306.504456) (xy 49.402605 -306.584007)
			(xy 49.37906 -306.661623) (xy 49.348021 -306.736559) (xy 49.309786 -306.808091) (xy 49.264724 -306.875531)
			(xy 49.213269 -306.93823) (xy 49.155916 -306.995583) (xy 49.093217 -307.047038) (xy 49.025777 -307.0921)
			(xy 48.954245 -307.130335) (xy 48.879309 -307.161374) (xy 48.801693 -307.184919) (xy 48.722142 -307.200742)
			(xy 48.641423 -307.208692) (xy 48.560313 -307.208692) (xy 48.479594 -307.200742) (xy 48.400043 -307.184919)
			(xy 48.322427 -307.161374) (xy 48.247491 -307.130335) (xy 48.175959 -307.0921) (xy 48.108519 -307.047038)
			(xy 48.04582 -306.995583) (xy 47.988467 -306.93823) (xy 47.937012 -306.875531) (xy 47.89195 -306.808091)
			(xy 47.853715 -306.736559) (xy 47.822676 -306.661623) (xy 47.799131 -306.584007) (xy 47.783308 -306.504456)
			(xy 47.775358 -306.423737) (xy 29.614876 -306.423737) (xy 29.614876 -306.852066) (xy 29.61535 -306.874174)
			(xy 29.623 -306.917722) (xy 29.638074 -306.959288) (xy 29.660116 -306.997616) (xy 29.688462 -307.03155)
			(xy 29.722255 -307.060063) (xy 29.760474 -307.082294) (xy 29.801966 -307.097573) (xy 29.845475 -307.105438)
			(xy 29.88969 -307.10565) (xy 29.933273 -307.098204) (xy 29.974909 -307.083324) (xy 29.994352 -307.072792)
			(xy 30.032527 -307.051621) (xy 30.112065 -307.015636) (xy 30.194595 -306.987178) (xy 30.279409 -306.966492)
			(xy 30.365774 -306.953756) (xy 30.452948 -306.94908) (xy 30.54018 -306.952504) (xy 30.626719 -306.963999)
			(xy 30.711821 -306.983466) (xy 30.794751 -307.010737) (xy 30.874797 -307.045577) (xy 30.951269 -307.087686)
			(xy 31.023509 -307.136702) (xy 31.090895 -307.192203) (xy 31.152846 -307.253711) (xy 31.208829 -307.320696)
			(xy 31.258363 -307.392582) (xy 31.301021 -307.46875) (xy 31.336435 -307.548543) (xy 31.3643 -307.631276)
			(xy 31.384377 -307.716235) (xy 31.396494 -307.80269) (xy 31.400544 -307.889895) (xy 31.398525 -307.93336)
			(xy 34.599874 -307.93336) (xy 34.599874 -307.84646) (xy 34.607892 -307.759931) (xy 34.62386 -307.674511)
			(xy 34.647641 -307.590929) (xy 34.679033 -307.509897) (xy 34.717767 -307.432108) (xy 34.763514 -307.358224)
			(xy 34.815883 -307.288877) (xy 34.874427 -307.224657) (xy 34.938647 -307.166113) (xy 35.007994 -307.113744)
			(xy 35.081878 -307.067997) (xy 35.159667 -307.029263) (xy 35.240699 -306.997871) (xy 35.324281 -306.97409)
			(xy 35.409701 -306.958122) (xy 35.49623 -306.950104) (xy 35.58313 -306.950104) (xy 35.669659 -306.958122)
			(xy 35.755079 -306.97409) (xy 35.838661 -306.997871) (xy 35.919693 -307.029263) (xy 35.997482 -307.067997)
			(xy 36.071366 -307.113744) (xy 36.140713 -307.166113) (xy 36.204933 -307.224657) (xy 36.263477 -307.288877)
			(xy 36.315846 -307.358224) (xy 36.361593 -307.432108) (xy 36.400327 -307.509897) (xy 36.431719 -307.590929)
			(xy 36.4555 -307.674511) (xy 36.471468 -307.759931) (xy 36.479486 -307.84646) (xy 36.479988 -307.88991)
			(xy 36.479486 -307.93336) (xy 36.471468 -308.019889) (xy 36.4555 -308.105309) (xy 36.431719 -308.188891)
			(xy 36.400327 -308.269923) (xy 36.361593 -308.347712) (xy 36.315846 -308.421596) (xy 36.263477 -308.490943)
			(xy 36.204933 -308.555163) (xy 36.140713 -308.613707) (xy 36.071366 -308.666076) (xy 36.040464 -308.68521)
			(xy 57.588786 -308.68521) (xy 57.592672 -308.630856) (xy 57.604254 -308.577609) (xy 57.623297 -308.526553)
			(xy 57.649411 -308.478726) (xy 57.682067 -308.435102) (xy 57.720598 -308.39657) (xy 57.764221 -308.363914)
			(xy 57.812047 -308.337799) (xy 57.863104 -308.318756) (xy 57.91635 -308.307173) (xy 57.970704 -308.303286)
			(xy 58.025057 -308.307174) (xy 58.078303 -308.318758) (xy 58.129359 -308.337802) (xy 58.177185 -308.363918)
			(xy 58.199274 -308.379876) (xy 58.218286 -308.393472) (xy 58.260169 -308.414204) (xy 58.305137 -308.42693)
			(xy 58.351674 -308.43122) (xy 58.398211 -308.42693) (xy 58.443179 -308.414204) (xy 58.485062 -308.393472)
			(xy 58.504074 -308.379876) (xy 58.526178 -308.363935) (xy 58.574004 -308.337813) (xy 58.625062 -308.318763)
			(xy 58.67831 -308.307173) (xy 58.732667 -308.303281) (xy 58.787024 -308.307164) (xy 58.840275 -308.318744)
			(xy 58.891335 -308.337785) (xy 58.939166 -308.363899) (xy 58.982794 -308.396556) (xy 59.021329 -308.435089)
			(xy 59.053988 -308.478714) (xy 59.080105 -308.526543) (xy 59.099149 -308.577603) (xy 59.110733 -308.630853)
			(xy 59.114619 -308.68521) (xy 59.475479 -308.68521) (xy 59.479365 -308.630855) (xy 59.490948 -308.577606)
			(xy 59.509991 -308.526548) (xy 59.536106 -308.47872) (xy 59.568763 -308.435095) (xy 59.607296 -308.396563)
			(xy 59.650921 -308.363906) (xy 59.698749 -308.33779) (xy 59.749807 -308.318748) (xy 59.803056 -308.307165)
			(xy 59.85741 -308.303279) (xy 59.911765 -308.307168) (xy 59.965013 -308.318754) (xy 60.01607 -308.337799)
			(xy 60.063897 -308.363917) (xy 60.085986 -308.379876) (xy 60.104998 -308.393472) (xy 60.146881 -308.414204)
			(xy 60.191849 -308.42693) (xy 60.238386 -308.43122) (xy 60.284923 -308.42693) (xy 60.329891 -308.414204)
			(xy 60.371774 -308.393472) (xy 60.390786 -308.379876) (xy 60.41289 -308.363936) (xy 60.460715 -308.337816)
			(xy 60.511771 -308.318767) (xy 60.565019 -308.307179) (xy 60.619374 -308.303288) (xy 60.673729 -308.307172)
			(xy 60.726978 -308.318752) (xy 60.778037 -308.337794) (xy 60.825866 -308.363908) (xy 60.869492 -308.396564)
			(xy 60.908025 -308.435096) (xy 60.940683 -308.47872) (xy 60.966799 -308.526548) (xy 60.985843 -308.577606)
			(xy 60.997426 -308.630855) (xy 61.001312 -308.68521) (xy 61.716454 -308.68521) (xy 61.720341 -308.630849)
			(xy 61.731925 -308.577595) (xy 61.750971 -308.526532) (xy 61.77709 -308.478699) (xy 61.809751 -308.435071)
			(xy 61.848289 -308.396535) (xy 61.89192 -308.363877) (xy 61.939754 -308.33776) (xy 61.990819 -308.318718)
			(xy 62.044073 -308.307137) (xy 62.098434 -308.303254) (xy 62.152795 -308.307147) (xy 62.206047 -308.318737)
			(xy 62.257108 -308.337789) (xy 62.304938 -308.363914) (xy 62.327028 -308.379876) (xy 62.34604 -308.393472)
			(xy 62.387923 -308.414204) (xy 62.432891 -308.42693) (xy 62.479428 -308.43122) (xy 62.525965 -308.42693)
			(xy 62.570933 -308.414204) (xy 62.612816 -308.393472) (xy 62.631828 -308.379876) (xy 62.653931 -308.36394)
			(xy 62.701753 -308.337826) (xy 62.752805 -308.318784) (xy 62.806048 -308.307201) (xy 62.860397 -308.303313)
			(xy 62.914747 -308.3072) (xy 62.96799 -308.318782) (xy 63.019042 -308.337824) (xy 63.066865 -308.363937)
			(xy 63.110485 -308.396591) (xy 63.149014 -308.43512) (xy 63.181667 -308.478741) (xy 63.207779 -308.526564)
			(xy 63.22682 -308.577617) (xy 63.238401 -308.63086) (xy 63.242287 -308.68521) (xy 63.620463 -308.68521)
			(xy 63.62435 -308.630851) (xy 63.635934 -308.577599) (xy 63.654978 -308.526538) (xy 63.681096 -308.478707)
			(xy 63.713756 -308.43508) (xy 63.752292 -308.396545) (xy 63.79592 -308.363888) (xy 63.843752 -308.337772)
			(xy 63.894814 -308.318729) (xy 63.948067 -308.307148) (xy 64.002425 -308.303263) (xy 64.056783 -308.307155)
			(xy 64.110034 -308.318743) (xy 64.161094 -308.337793) (xy 64.208922 -308.363915) (xy 64.231012 -308.379876)
			(xy 64.250024 -308.393472) (xy 64.291907 -308.414204) (xy 64.336875 -308.42693) (xy 64.383412 -308.43122)
			(xy 64.429949 -308.42693) (xy 64.474917 -308.414204) (xy 64.5168 -308.393472) (xy 64.535812 -308.379876)
			(xy 64.557915 -308.363939) (xy 64.605739 -308.337822) (xy 64.656792 -308.318777) (xy 64.710037 -308.307193)
			(xy 64.764388 -308.303303) (xy 64.81874 -308.307189) (xy 64.871985 -308.318771) (xy 64.92304 -308.337812)
			(xy 64.970866 -308.363926) (xy 65.014488 -308.396581) (xy 65.053018 -308.435111) (xy 65.085673 -308.478733)
			(xy 65.111787 -308.526558) (xy 65.130829 -308.577613) (xy 65.14241 -308.630858) (xy 65.146297 -308.68521)
			(xy 65.142408 -308.739561) (xy 65.130823 -308.792806) (xy 65.111779 -308.84386) (xy 65.085662 -308.891683)
			(xy 65.053006 -308.935304) (xy 65.014473 -308.973832) (xy 64.970849 -309.006484) (xy 64.923023 -309.032596)
			(xy 64.871967 -309.051635) (xy 64.818721 -309.063213) (xy 64.764369 -309.067097) (xy 64.710018 -309.063205)
			(xy 64.656774 -309.051617) (xy 64.605721 -309.03257) (xy 64.557899 -309.006451) (xy 64.535812 -308.990492)
			(xy 64.5168 -308.976896) (xy 64.474917 -308.956164) (xy 64.429949 -308.943438) (xy 64.383412 -308.939148)
			(xy 64.336875 -308.943438) (xy 64.291907 -308.956164) (xy 64.250024 -308.976896) (xy 64.231012 -308.990492)
			(xy 64.208939 -309.006475) (xy 64.161111 -309.032599) (xy 64.110053 -309.051651) (xy 64.056802 -309.063242)
			(xy 64.002444 -309.067137) (xy 63.948086 -309.063255) (xy 63.894833 -309.051676) (xy 63.84377 -309.032636)
			(xy 63.795936 -309.006523) (xy 63.752306 -308.973867) (xy 63.713768 -308.935334) (xy 63.681107 -308.891709)
			(xy 63.654986 -308.84388) (xy 63.635939 -308.792819) (xy 63.624353 -308.739568) (xy 63.620463 -308.68521)
			(xy 63.242287 -308.68521) (xy 63.238398 -308.739559) (xy 63.226815 -308.792801) (xy 63.207771 -308.843853)
			(xy 63.181656 -308.891675) (xy 63.149001 -308.935294) (xy 63.110471 -308.973822) (xy 63.066849 -309.006473)
			(xy 63.019025 -309.032584) (xy 62.967971 -309.051623) (xy 62.914728 -309.063203) (xy 62.860378 -309.067087)
			(xy 62.806029 -309.063197) (xy 62.752787 -309.051611) (xy 62.701736 -309.032566) (xy 62.653914 -309.00645)
			(xy 62.631828 -308.990492) (xy 62.612816 -308.976896) (xy 62.570933 -308.956164) (xy 62.525965 -308.943438)
			(xy 62.479428 -308.939148) (xy 62.432891 -308.943438) (xy 62.387923 -308.956164) (xy 62.34604 -308.976896)
			(xy 62.327028 -308.990492) (xy 62.304954 -309.006476) (xy 62.257126 -309.032603) (xy 62.206066 -309.051657)
			(xy 62.152814 -309.06325) (xy 62.098454 -309.067146) (xy 62.044092 -309.063266) (xy 61.990837 -309.051687)
			(xy 61.939772 -309.032648) (xy 61.891936 -309.006534) (xy 61.848304 -308.973878) (xy 61.809764 -308.935344)
			(xy 61.7771 -308.891717) (xy 61.750979 -308.843886) (xy 61.73193 -308.792824) (xy 61.720343 -308.73957)
			(xy 61.716454 -308.68521) (xy 61.001312 -308.68521) (xy 60.997423 -308.739565) (xy 60.985837 -308.792813)
			(xy 60.966791 -308.84387) (xy 60.940673 -308.891696) (xy 60.908013 -308.935319) (xy 60.869477 -308.973849)
			(xy 60.82585 -309.006502) (xy 60.778019 -309.032614) (xy 60.72696 -309.051653) (xy 60.67371 -309.063231)
			(xy 60.619354 -309.067112) (xy 60.565 -309.063218) (xy 60.511753 -309.051627) (xy 60.460698 -309.032576)
			(xy 60.412873 -309.006453) (xy 60.390786 -308.990492) (xy 60.371774 -308.976896) (xy 60.329891 -308.956164)
			(xy 60.284923 -308.943438) (xy 60.238386 -308.939148) (xy 60.191849 -308.943438) (xy 60.146881 -308.956164)
			(xy 60.104998 -308.976896) (xy 60.085986 -308.990492) (xy 60.063913 -309.006472) (xy 60.016088 -309.032593)
			(xy 59.965032 -309.051641) (xy 59.911784 -309.063229) (xy 59.85743 -309.067121) (xy 59.803075 -309.063237)
			(xy 59.749825 -309.051658) (xy 59.698766 -309.032618) (xy 59.650937 -309.006504) (xy 59.607311 -308.97385)
			(xy 59.568776 -308.935319) (xy 59.536117 -308.891696) (xy 59.509999 -308.843869) (xy 59.490953 -308.792812)
			(xy 59.479368 -308.739564) (xy 59.475479 -308.68521) (xy 59.114619 -308.68521) (xy 59.11073 -308.739566)
			(xy 59.099144 -308.792816) (xy 59.080097 -308.843874) (xy 59.053977 -308.891702) (xy 59.021316 -308.935326)
			(xy 58.982779 -308.973857) (xy 58.93915 -309.006511) (xy 58.891318 -309.032623) (xy 58.840256 -309.051661)
			(xy 58.787005 -309.063239) (xy 58.732648 -309.067119) (xy 58.678291 -309.063224) (xy 58.625043 -309.051632)
			(xy 58.573987 -309.032579) (xy 58.526162 -309.006454) (xy 58.504074 -308.990492) (xy 58.485062 -308.976896)
			(xy 58.443179 -308.956164) (xy 58.398211 -308.943438) (xy 58.351674 -308.939148) (xy 58.305137 -308.943438)
			(xy 58.260169 -308.956164) (xy 58.218286 -308.976896) (xy 58.199274 -308.990492) (xy 58.177201 -309.006471)
			(xy 58.129377 -309.03259) (xy 58.078322 -309.051636) (xy 58.025076 -309.063223) (xy 57.970723 -309.067114)
			(xy 57.916369 -309.063229) (xy 57.863122 -309.051649) (xy 57.812065 -309.032609) (xy 57.764237 -309.006496)
			(xy 57.720612 -308.973842) (xy 57.682079 -308.935312) (xy 57.649422 -308.89169) (xy 57.623305 -308.843865)
			(xy 57.60426 -308.792809) (xy 57.592675 -308.739563) (xy 57.588786 -308.68521) (xy 36.040464 -308.68521)
			(xy 35.997482 -308.711823) (xy 35.919693 -308.750557) (xy 35.838661 -308.781949) (xy 35.755079 -308.80573)
			(xy 35.669659 -308.821698) (xy 35.58313 -308.829716) (xy 35.49623 -308.829716) (xy 35.409701 -308.821698)
			(xy 35.324281 -308.80573) (xy 35.240699 -308.781949) (xy 35.159667 -308.750557) (xy 35.081878 -308.711823)
			(xy 35.007994 -308.666076) (xy 34.938647 -308.613707) (xy 34.874427 -308.555163) (xy 34.815883 -308.490943)
			(xy 34.763514 -308.421596) (xy 34.717767 -308.347712) (xy 34.679033 -308.269923) (xy 34.647641 -308.188891)
			(xy 34.62386 -308.105309) (xy 34.607892 -308.019889) (xy 34.599874 -307.93336) (xy 31.398525 -307.93336)
			(xy 31.396494 -307.9771) (xy 31.384379 -308.063555) (xy 31.364303 -308.148514) (xy 31.336438 -308.231247)
			(xy 31.301025 -308.311041) (xy 31.258368 -308.38721) (xy 31.208835 -308.459096) (xy 31.152853 -308.526082)
			(xy 31.090902 -308.58759) (xy 31.023517 -308.643092) (xy 30.951278 -308.692109) (xy 30.874806 -308.734219)
			(xy 30.79476 -308.76906) (xy 30.71183 -308.796332) (xy 30.626729 -308.815799) (xy 30.54019 -308.827295)
			(xy 30.452958 -308.83072) (xy 30.365784 -308.826045) (xy 30.279418 -308.81331) (xy 30.194605 -308.792625)
			(xy 30.112074 -308.764168) (xy 30.032536 -308.728183) (xy 29.994352 -308.707028) (xy 29.9749 -308.696527)
			(xy 29.933268 -308.681677) (xy 29.889696 -308.674253) (xy 29.845495 -308.67448) (xy 29.802001 -308.682352)
			(xy 29.760525 -308.69763) (xy 29.722318 -308.719855) (xy 29.688532 -308.748354) (xy 29.660187 -308.78227)
			(xy 29.638137 -308.820578) (xy 29.623049 -308.862124) (xy 29.615376 -308.905654) (xy 29.614876 -308.927754)
			(xy 29.614876 -309.392066) (xy 29.61535 -309.414174) (xy 29.623 -309.457722) (xy 29.638074 -309.499288)
			(xy 29.660116 -309.537616) (xy 29.688462 -309.57155) (xy 29.722255 -309.600063) (xy 29.760474 -309.622294)
			(xy 29.801966 -309.637573) (xy 29.845475 -309.645438) (xy 29.88969 -309.64565) (xy 29.933273 -309.638204)
			(xy 29.974909 -309.623324) (xy 29.994352 -309.612792) (xy 30.032005 -309.591907) (xy 30.110414 -309.556316)
			(xy 30.191748 -309.528041) (xy 30.275326 -309.507317) (xy 30.360449 -309.494319) (xy 30.446403 -309.489156)
			(xy 30.532469 -309.49187) (xy 30.617927 -309.50244) (xy 30.702061 -309.520775) (xy 30.784167 -309.546724)
			(xy 30.863558 -309.580069) (xy 30.939568 -309.62053) (xy 30.975808 -309.64378) (xy 31.009874 -309.666661)
			(xy 31.074295 -309.717506) (xy 31.134039 -309.773774) (xy 31.188649 -309.835036) (xy 31.237711 -309.900825)
			(xy 31.28085 -309.970642) (xy 31.317738 -310.043954) (xy 31.348094 -310.120203) (xy 31.371686 -310.198808)
			(xy 31.38043 -310.238902) (xy 31.388507 -310.280118) (xy 31.398177 -310.363555) (xy 31.399734 -310.405526)
			(xy 31.400367 -310.4486) (xy 31.398739 -310.47336) (xy 34.599874 -310.47336) (xy 34.599874 -310.38646)
			(xy 34.607892 -310.299931) (xy 34.62386 -310.214511) (xy 34.647641 -310.130929) (xy 34.679033 -310.049897)
			(xy 34.717767 -309.972108) (xy 34.763514 -309.898224) (xy 34.815883 -309.828877) (xy 34.874427 -309.764657)
			(xy 34.938647 -309.706113) (xy 35.007994 -309.653744) (xy 35.081878 -309.607997) (xy 35.159667 -309.569263)
			(xy 35.240699 -309.537871) (xy 35.324281 -309.51409) (xy 35.409701 -309.498122) (xy 35.49623 -309.490104)
			(xy 35.58313 -309.490104) (xy 35.669659 -309.498122) (xy 35.755079 -309.51409) (xy 35.838661 -309.537871)
			(xy 35.919693 -309.569263) (xy 35.997482 -309.607997) (xy 36.071366 -309.653744) (xy 36.140713 -309.706113)
			(xy 36.204933 -309.764657) (xy 36.263477 -309.828877) (xy 36.315846 -309.898224) (xy 36.361593 -309.972108)
			(xy 36.400327 -310.049897) (xy 36.431719 -310.130929) (xy 36.4555 -310.214511) (xy 36.471468 -310.299931)
			(xy 36.479486 -310.38646) (xy 36.479988 -310.42991) (xy 36.479486 -310.47336) (xy 36.471468 -310.559889)
			(xy 36.4555 -310.645309) (xy 36.431719 -310.728891) (xy 36.400327 -310.809923) (xy 36.361593 -310.887712)
			(xy 36.315846 -310.961596) (xy 36.263477 -311.030943) (xy 36.204933 -311.095163) (xy 36.140713 -311.153707)
			(xy 36.071366 -311.206076) (xy 35.997482 -311.251823) (xy 35.919693 -311.290557) (xy 35.838661 -311.321949)
			(xy 35.755079 -311.34573) (xy 35.669659 -311.361698) (xy 35.58313 -311.369716) (xy 35.49623 -311.369716)
			(xy 35.409701 -311.361698) (xy 35.324281 -311.34573) (xy 35.240699 -311.321949) (xy 35.159667 -311.290557)
			(xy 35.081878 -311.251823) (xy 35.007994 -311.206076) (xy 34.938647 -311.153707) (xy 34.874427 -311.095163)
			(xy 34.815883 -311.030943) (xy 34.763514 -310.961596) (xy 34.717767 -310.887712) (xy 34.679033 -310.809923)
			(xy 34.647641 -310.728891) (xy 34.62386 -310.645309) (xy 34.607892 -310.559889) (xy 34.599874 -310.47336)
			(xy 31.398739 -310.47336) (xy 31.394714 -310.534567) (xy 31.381222 -310.619656) (xy 31.360006 -310.703155)
			(xy 31.331243 -310.784363) (xy 31.295173 -310.862601) (xy 31.252099 -310.937213) (xy 31.202383 -311.007572)
			(xy 31.14644 -311.07309) (xy 31.08474 -311.133217) (xy 31.017799 -311.18745) (xy 30.94618 -311.235333)
			(xy 30.870481 -311.276466) (xy 30.791338 -311.310504) (xy 30.75051 -311.324244) (xy 30.710085 -311.3369)
			(xy 30.627492 -311.355747) (xy 30.543539 -311.367087) (xy 30.458906 -311.37083) (xy 30.374279 -311.366944)
			(xy 30.290345 -311.355462) (xy 30.207785 -311.336476) (xy 30.127266 -311.310141) (xy 30.049443 -311.27667)
			(xy 29.974947 -311.236334) (xy 29.90438 -311.189461) (xy 29.838316 -311.13643) (xy 29.77729 -311.077671)
			(xy 29.721797 -311.013661) (xy 29.672287 -310.944919) (xy 29.629161 -310.872002) (xy 29.592769 -310.795502)
			(xy 29.563406 -310.716038) (xy 29.551884 -310.675274) (xy 29.545189 -310.654438) (xy 29.525677 -310.615269)
			(xy 29.499743 -310.580022) (xy 29.468153 -310.549739) (xy 29.431842 -310.525316) (xy 29.391884 -310.507475)
			(xy 29.34946 -310.496744) (xy 29.305825 -310.49344) (xy 29.262269 -310.497661) (xy 29.22008 -310.509281)
			(xy 29.180506 -310.527958) (xy 29.144716 -310.553139) (xy 29.128974 -310.56834) (xy 28.067 -311.630314)
			(xy 28.067 -313.01336) (xy 29.519874 -313.01336) (xy 29.519874 -312.92646) (xy 29.527892 -312.839931)
			(xy 29.54386 -312.754511) (xy 29.567641 -312.670929) (xy 29.599033 -312.589897) (xy 29.637767 -312.512108)
			(xy 29.683514 -312.438224) (xy 29.735883 -312.368877) (xy 29.794427 -312.304657) (xy 29.858647 -312.246113)
			(xy 29.927994 -312.193744) (xy 30.001878 -312.147997) (xy 30.079667 -312.109263) (xy 30.160699 -312.077871)
			(xy 30.244281 -312.05409) (xy 30.329701 -312.038122) (xy 30.41623 -312.030104) (xy 30.50313 -312.030104)
			(xy 30.589659 -312.038122) (xy 30.675079 -312.05409) (xy 30.758661 -312.077871) (xy 30.839693 -312.109263)
			(xy 30.917482 -312.147997) (xy 30.991366 -312.193744) (xy 31.060713 -312.246113) (xy 31.124933 -312.304657)
			(xy 31.183477 -312.368877) (xy 31.235846 -312.438224) (xy 31.281593 -312.512108) (xy 31.320327 -312.589897)
			(xy 31.351719 -312.670929) (xy 31.3755 -312.754511) (xy 31.391468 -312.839931) (xy 31.399486 -312.92646)
			(xy 31.399988 -312.96991) (xy 31.399486 -313.01336) (xy 34.599874 -313.01336) (xy 34.599874 -312.92646)
			(xy 34.607892 -312.839931) (xy 34.62386 -312.754511) (xy 34.647641 -312.670929) (xy 34.679033 -312.589897)
			(xy 34.717767 -312.512108) (xy 34.763514 -312.438224) (xy 34.815883 -312.368877) (xy 34.874427 -312.304657)
			(xy 34.938647 -312.246113) (xy 35.007994 -312.193744) (xy 35.081878 -312.147997) (xy 35.159667 -312.109263)
			(xy 35.240699 -312.077871) (xy 35.324281 -312.05409) (xy 35.409701 -312.038122) (xy 35.49623 -312.030104)
			(xy 35.58313 -312.030104) (xy 35.669659 -312.038122) (xy 35.755079 -312.05409) (xy 35.838661 -312.077871)
			(xy 35.919693 -312.109263) (xy 35.997482 -312.147997) (xy 36.071366 -312.193744) (xy 36.140713 -312.246113)
			(xy 36.204933 -312.304657) (xy 36.263477 -312.368877) (xy 36.315846 -312.438224) (xy 36.361593 -312.512108)
			(xy 36.400327 -312.589897) (xy 36.431719 -312.670929) (xy 36.4555 -312.754511) (xy 36.471468 -312.839931)
			(xy 36.479486 -312.92646) (xy 36.479988 -312.96991) (xy 36.479486 -313.01336) (xy 36.471468 -313.099889)
			(xy 36.4555 -313.185309) (xy 36.431719 -313.268891) (xy 36.400327 -313.349923) (xy 36.361593 -313.427712)
			(xy 36.315846 -313.501596) (xy 36.263477 -313.570943) (xy 36.204933 -313.635163) (xy 36.140713 -313.693707)
			(xy 36.071366 -313.746076) (xy 35.997482 -313.791823) (xy 35.919693 -313.830557) (xy 35.838661 -313.861949)
			(xy 35.755079 -313.88573) (xy 35.669659 -313.901698) (xy 35.58313 -313.909716) (xy 35.49623 -313.909716)
			(xy 35.409701 -313.901698) (xy 35.324281 -313.88573) (xy 35.240699 -313.861949) (xy 35.159667 -313.830557)
			(xy 35.081878 -313.791823) (xy 35.007994 -313.746076) (xy 34.938647 -313.693707) (xy 34.874427 -313.635163)
			(xy 34.815883 -313.570943) (xy 34.763514 -313.501596) (xy 34.717767 -313.427712) (xy 34.679033 -313.349923)
			(xy 34.647641 -313.268891) (xy 34.62386 -313.185309) (xy 34.607892 -313.099889) (xy 34.599874 -313.01336)
			(xy 31.399486 -313.01336) (xy 31.391468 -313.099889) (xy 31.3755 -313.185309) (xy 31.351719 -313.268891)
			(xy 31.320327 -313.349923) (xy 31.281593 -313.427712) (xy 31.235846 -313.501596) (xy 31.183477 -313.570943)
			(xy 31.124933 -313.635163) (xy 31.060713 -313.693707) (xy 30.991366 -313.746076) (xy 30.917482 -313.791823)
			(xy 30.839693 -313.830557) (xy 30.758661 -313.861949) (xy 30.675079 -313.88573) (xy 30.589659 -313.901698)
			(xy 30.50313 -313.909716) (xy 30.41623 -313.909716) (xy 30.329701 -313.901698) (xy 30.244281 -313.88573)
			(xy 30.160699 -313.861949) (xy 30.079667 -313.830557) (xy 30.001878 -313.791823) (xy 29.927994 -313.746076)
			(xy 29.858647 -313.693707) (xy 29.794427 -313.635163) (xy 29.735883 -313.570943) (xy 29.683514 -313.501596)
			(xy 29.637767 -313.427712) (xy 29.599033 -313.349923) (xy 29.567641 -313.268891) (xy 29.54386 -313.185309)
			(xy 29.527892 -313.099889) (xy 29.519874 -313.01336) (xy 28.067 -313.01336) (xy 28.067 -315.55336)
			(xy 29.519874 -315.55336) (xy 29.519874 -315.46646) (xy 29.527892 -315.379931) (xy 29.54386 -315.294511)
			(xy 29.567641 -315.210929) (xy 29.599033 -315.129897) (xy 29.637767 -315.052108) (xy 29.683514 -314.978224)
			(xy 29.735883 -314.908877) (xy 29.794427 -314.844657) (xy 29.858647 -314.786113) (xy 29.927994 -314.733744)
			(xy 30.001878 -314.687997) (xy 30.079667 -314.649263) (xy 30.160699 -314.617871) (xy 30.244281 -314.59409)
			(xy 30.329701 -314.578122) (xy 30.41623 -314.570104) (xy 30.50313 -314.570104) (xy 30.589659 -314.578122)
			(xy 30.675079 -314.59409) (xy 30.758661 -314.617871) (xy 30.839693 -314.649263) (xy 30.917482 -314.687997)
			(xy 30.991366 -314.733744) (xy 31.060713 -314.786113) (xy 31.124933 -314.844657) (xy 31.183477 -314.908877)
			(xy 31.235846 -314.978224) (xy 31.281593 -315.052108) (xy 31.320327 -315.129897) (xy 31.351719 -315.210929)
			(xy 31.3755 -315.294511) (xy 31.391468 -315.379931) (xy 31.399486 -315.46646) (xy 31.399988 -315.50991)
			(xy 31.399486 -315.55336) (xy 34.599874 -315.55336) (xy 34.599874 -315.46646) (xy 34.607892 -315.379931)
			(xy 34.62386 -315.294511) (xy 34.647641 -315.210929) (xy 34.679033 -315.129897) (xy 34.717767 -315.052108)
			(xy 34.763514 -314.978224) (xy 34.815883 -314.908877) (xy 34.874427 -314.844657) (xy 34.938647 -314.786113)
			(xy 35.007994 -314.733744) (xy 35.081878 -314.687997) (xy 35.159667 -314.649263) (xy 35.240699 -314.617871)
			(xy 35.324281 -314.59409) (xy 35.409701 -314.578122) (xy 35.49623 -314.570104) (xy 35.58313 -314.570104)
			(xy 35.669659 -314.578122) (xy 35.755079 -314.59409) (xy 35.838661 -314.617871) (xy 35.919693 -314.649263)
			(xy 35.997482 -314.687997) (xy 36.071366 -314.733744) (xy 36.140713 -314.786113) (xy 36.204933 -314.844657)
			(xy 36.263477 -314.908877) (xy 36.315846 -314.978224) (xy 36.361593 -315.052108) (xy 36.400327 -315.129897)
			(xy 36.431719 -315.210929) (xy 36.4555 -315.294511) (xy 36.471468 -315.379931) (xy 36.479486 -315.46646)
			(xy 36.479988 -315.50991) (xy 36.479486 -315.55336) (xy 36.471468 -315.639889) (xy 36.4555 -315.725309)
			(xy 36.431719 -315.808891) (xy 36.400327 -315.889923) (xy 36.361593 -315.967712) (xy 36.315846 -316.041596)
			(xy 36.263477 -316.110943) (xy 36.204933 -316.175163) (xy 36.140713 -316.233707) (xy 36.071366 -316.286076)
			(xy 35.997482 -316.331823) (xy 35.919693 -316.370557) (xy 35.838661 -316.401949) (xy 35.755079 -316.42573)
			(xy 35.669659 -316.441698) (xy 35.58313 -316.449716) (xy 35.49623 -316.449716) (xy 35.409701 -316.441698)
			(xy 35.324281 -316.42573) (xy 35.240699 -316.401949) (xy 35.159667 -316.370557) (xy 35.081878 -316.331823)
			(xy 35.007994 -316.286076) (xy 34.938647 -316.233707) (xy 34.874427 -316.175163) (xy 34.815883 -316.110943)
			(xy 34.763514 -316.041596) (xy 34.717767 -315.967712) (xy 34.679033 -315.889923) (xy 34.647641 -315.808891)
			(xy 34.62386 -315.725309) (xy 34.607892 -315.639889) (xy 34.599874 -315.55336) (xy 31.399486 -315.55336)
			(xy 31.391468 -315.639889) (xy 31.3755 -315.725309) (xy 31.351719 -315.808891) (xy 31.320327 -315.889923)
			(xy 31.281593 -315.967712) (xy 31.235846 -316.041596) (xy 31.183477 -316.110943) (xy 31.124933 -316.175163)
			(xy 31.060713 -316.233707) (xy 30.991366 -316.286076) (xy 30.917482 -316.331823) (xy 30.839693 -316.370557)
			(xy 30.758661 -316.401949) (xy 30.675079 -316.42573) (xy 30.589659 -316.441698) (xy 30.50313 -316.449716)
			(xy 30.41623 -316.449716) (xy 30.329701 -316.441698) (xy 30.244281 -316.42573) (xy 30.160699 -316.401949)
			(xy 30.079667 -316.370557) (xy 30.001878 -316.331823) (xy 29.927994 -316.286076) (xy 29.858647 -316.233707)
			(xy 29.794427 -316.175163) (xy 29.735883 -316.110943) (xy 29.683514 -316.041596) (xy 29.637767 -315.967712)
			(xy 29.599033 -315.889923) (xy 29.567641 -315.808891) (xy 29.54386 -315.725309) (xy 29.527892 -315.639889)
			(xy 29.519874 -315.55336) (xy 28.067 -315.55336) (xy 28.067 -318.09336) (xy 29.519874 -318.09336)
			(xy 29.519874 -318.00646) (xy 29.527892 -317.919931) (xy 29.54386 -317.834511) (xy 29.567641 -317.750929)
			(xy 29.599033 -317.669897) (xy 29.637767 -317.592108) (xy 29.683514 -317.518224) (xy 29.735883 -317.448877)
			(xy 29.794427 -317.384657) (xy 29.858647 -317.326113) (xy 29.927994 -317.273744) (xy 30.001878 -317.227997)
			(xy 30.079667 -317.189263) (xy 30.160699 -317.157871) (xy 30.244281 -317.13409) (xy 30.329701 -317.118122)
			(xy 30.41623 -317.110104) (xy 30.50313 -317.110104) (xy 30.589659 -317.118122) (xy 30.675079 -317.13409)
			(xy 30.758661 -317.157871) (xy 30.839693 -317.189263) (xy 30.917482 -317.227997) (xy 30.991366 -317.273744)
			(xy 31.060713 -317.326113) (xy 31.124933 -317.384657) (xy 31.183477 -317.448877) (xy 31.235846 -317.518224)
			(xy 31.281593 -317.592108) (xy 31.320327 -317.669897) (xy 31.351719 -317.750929) (xy 31.3755 -317.834511)
			(xy 31.391468 -317.919931) (xy 31.399486 -318.00646) (xy 31.399988 -318.04991) (xy 31.399486 -318.09336)
			(xy 34.599874 -318.09336) (xy 34.599874 -318.00646) (xy 34.607892 -317.919931) (xy 34.62386 -317.834511)
			(xy 34.647641 -317.750929) (xy 34.679033 -317.669897) (xy 34.717767 -317.592108) (xy 34.763514 -317.518224)
			(xy 34.815883 -317.448877) (xy 34.874427 -317.384657) (xy 34.938647 -317.326113) (xy 35.007994 -317.273744)
			(xy 35.081878 -317.227997) (xy 35.159667 -317.189263) (xy 35.240699 -317.157871) (xy 35.324281 -317.13409)
			(xy 35.409701 -317.118122) (xy 35.49623 -317.110104) (xy 35.58313 -317.110104) (xy 35.669659 -317.118122)
			(xy 35.755079 -317.13409) (xy 35.838661 -317.157871) (xy 35.919693 -317.189263) (xy 35.997482 -317.227997)
			(xy 36.071366 -317.273744) (xy 36.140713 -317.326113) (xy 36.204933 -317.384657) (xy 36.263477 -317.448877)
			(xy 36.315846 -317.518224) (xy 36.361593 -317.592108) (xy 36.400327 -317.669897) (xy 36.431719 -317.750929)
			(xy 36.4555 -317.834511) (xy 36.471468 -317.919931) (xy 36.479486 -318.00646) (xy 36.479988 -318.04991)
			(xy 36.479871 -318.06007) (xy 39.818564 -318.06007) (xy 39.819058 -318.002661) (xy 39.826902 -317.888113)
			(xy 39.842544 -317.774366) (xy 39.865911 -317.661952) (xy 39.896896 -317.551394) (xy 39.935352 -317.443209)
			(xy 39.981101 -317.3379) (xy 40.03393 -317.235958) (xy 40.093592 -317.137859) (xy 40.159809 -317.04406)
			(xy 40.232272 -316.954998) (xy 40.310645 -316.871089) (xy 40.39456 -316.792723) (xy 40.483627 -316.720266)
			(xy 40.577431 -316.654056) (xy 40.675535 -316.594402) (xy 40.777481 -316.541581) (xy 40.882793 -316.495839)
			(xy 40.990981 -316.457391) (xy 41.101541 -316.426415) (xy 41.213957 -316.403056) (xy 41.327705 -316.387423)
			(xy 41.442254 -316.379588) (xy 41.557072 -316.379588) (xy 41.671621 -316.387423) (xy 41.785369 -316.403056)
			(xy 41.897785 -316.426415) (xy 42.008345 -316.457391) (xy 42.116533 -316.495839) (xy 42.221845 -316.541581)
			(xy 42.323791 -316.594402) (xy 42.421895 -316.654056) (xy 42.501239 -316.71006) (xy 43.327577 -316.71006)
			(xy 43.331612 -316.634356) (xy 43.343671 -316.559511) (xy 43.363617 -316.48637) (xy 43.391224 -316.415765)
			(xy 43.42618 -316.348494) (xy 43.468088 -316.285319) (xy 43.516474 -316.226957) (xy 43.57079 -316.174069)
			(xy 43.630419 -316.127254) (xy 43.694687 -316.087042) (xy 43.762864 -316.05389) (xy 43.83418 -316.028172)
			(xy 43.907825 -316.01018) (xy 43.982965 -316.000118) (xy 44.058749 -315.998099) (xy 44.134319 -316.004148)
			(xy 44.208817 -316.018195) (xy 44.2814 -316.040081) (xy 44.351246 -316.069558) (xy 44.417563 -316.106293)
			(xy 44.479599 -316.149868) (xy 44.536652 -316.19979) (xy 44.588076 -316.255494) (xy 44.633287 -316.316349)
			(xy 44.671774 -316.381664) (xy 44.7031 -316.4507) (xy 44.72691 -316.522675) (xy 44.742935 -316.596773)
			(xy 44.750994 -316.672154) (xy 44.751498 -316.71006) (xy 45.867577 -316.71006) (xy 45.871612 -316.634356)
			(xy 45.883671 -316.559511) (xy 45.903617 -316.48637) (xy 45.931224 -316.415765) (xy 45.96618 -316.348494)
			(xy 46.008088 -316.285319) (xy 46.056474 -316.226957) (xy 46.11079 -316.174069) (xy 46.170419 -316.127254)
			(xy 46.234687 -316.087042) (xy 46.302864 -316.05389) (xy 46.37418 -316.028172) (xy 46.447825 -316.01018)
			(xy 46.522965 -316.000118) (xy 46.598749 -315.998099) (xy 46.674319 -316.004148) (xy 46.748817 -316.018195)
			(xy 46.8214 -316.040081) (xy 46.891246 -316.069558) (xy 46.957563 -316.106293) (xy 47.019599 -316.149868)
			(xy 47.076652 -316.19979) (xy 47.128076 -316.255494) (xy 47.173287 -316.316349) (xy 47.211774 -316.381664)
			(xy 47.2431 -316.4507) (xy 47.26691 -316.522675) (xy 47.282935 -316.596773) (xy 47.290994 -316.672154)
			(xy 47.291498 -316.71006) (xy 48.407577 -316.71006) (xy 48.411612 -316.634356) (xy 48.423671 -316.559511)
			(xy 48.443617 -316.48637) (xy 48.471224 -316.415765) (xy 48.50618 -316.348494) (xy 48.548088 -316.285319)
			(xy 48.596474 -316.226957) (xy 48.65079 -316.174069) (xy 48.710419 -316.127254) (xy 48.774687 -316.087042)
			(xy 48.842864 -316.05389) (xy 48.91418 -316.028172) (xy 48.987825 -316.01018) (xy 49.062965 -316.000118)
			(xy 49.138749 -315.998099) (xy 49.214319 -316.004148) (xy 49.288817 -316.018195) (xy 49.3614 -316.040081)
			(xy 49.431246 -316.069558) (xy 49.497563 -316.106293) (xy 49.559599 -316.149868) (xy 49.616652 -316.19979)
			(xy 49.668076 -316.255494) (xy 49.713287 -316.316349) (xy 49.751774 -316.381664) (xy 49.7831 -316.4507)
			(xy 49.80691 -316.522675) (xy 49.822935 -316.596773) (xy 49.830994 -316.672154) (xy 49.831498 -316.71006)
			(xy 50.947577 -316.71006) (xy 50.951612 -316.634356) (xy 50.963671 -316.559511) (xy 50.983617 -316.48637)
			(xy 51.011224 -316.415765) (xy 51.04618 -316.348494) (xy 51.088088 -316.285319) (xy 51.136474 -316.226957)
			(xy 51.19079 -316.174069) (xy 51.250419 -316.127254) (xy 51.314687 -316.087042) (xy 51.382864 -316.05389)
			(xy 51.45418 -316.028172) (xy 51.527825 -316.01018) (xy 51.602965 -316.000118) (xy 51.678749 -315.998099)
			(xy 51.754319 -316.004148) (xy 51.828817 -316.018195) (xy 51.9014 -316.040081) (xy 51.971246 -316.069558)
			(xy 52.037563 -316.106293) (xy 52.099599 -316.149868) (xy 52.156652 -316.19979) (xy 52.208076 -316.255494)
			(xy 52.253287 -316.316349) (xy 52.291774 -316.381664) (xy 52.3231 -316.4507) (xy 52.34691 -316.522675)
			(xy 52.362935 -316.596773) (xy 52.370994 -316.672154) (xy 52.371498 -316.71006) (xy 53.487577 -316.71006)
			(xy 53.491612 -316.634356) (xy 53.503671 -316.559511) (xy 53.523617 -316.48637) (xy 53.551224 -316.415765)
			(xy 53.58618 -316.348494) (xy 53.628088 -316.285319) (xy 53.676474 -316.226957) (xy 53.73079 -316.174069)
			(xy 53.790419 -316.127254) (xy 53.854687 -316.087042) (xy 53.922864 -316.05389) (xy 53.99418 -316.028172)
			(xy 54.067825 -316.01018) (xy 54.142965 -316.000118) (xy 54.218749 -315.998099) (xy 54.294319 -316.004148)
			(xy 54.368817 -316.018195) (xy 54.4414 -316.040081) (xy 54.511246 -316.069558) (xy 54.577563 -316.106293)
			(xy 54.639599 -316.149868) (xy 54.696652 -316.19979) (xy 54.748076 -316.255494) (xy 54.793287 -316.316349)
			(xy 54.831774 -316.381664) (xy 54.8631 -316.4507) (xy 54.88691 -316.522675) (xy 54.902935 -316.596773)
			(xy 54.910994 -316.672154) (xy 54.911498 -316.71006) (xy 56.027577 -316.71006) (xy 56.031612 -316.634356)
			(xy 56.043671 -316.559511) (xy 56.063617 -316.48637) (xy 56.091224 -316.415765) (xy 56.12618 -316.348494)
			(xy 56.168088 -316.285319) (xy 56.216474 -316.226957) (xy 56.27079 -316.174069) (xy 56.330419 -316.127254)
			(xy 56.394687 -316.087042) (xy 56.462864 -316.05389) (xy 56.53418 -316.028172) (xy 56.607825 -316.01018)
			(xy 56.682965 -316.000118) (xy 56.758749 -315.998099) (xy 56.834319 -316.004148) (xy 56.908817 -316.018195)
			(xy 56.9814 -316.040081) (xy 57.051246 -316.069558) (xy 57.117563 -316.106293) (xy 57.179599 -316.149868)
			(xy 57.236652 -316.19979) (xy 57.288076 -316.255494) (xy 57.333287 -316.316349) (xy 57.371774 -316.381664)
			(xy 57.4031 -316.4507) (xy 57.42691 -316.522675) (xy 57.442935 -316.596773) (xy 57.450994 -316.672154)
			(xy 57.451498 -316.71006) (xy 58.567577 -316.71006) (xy 58.571612 -316.634356) (xy 58.583671 -316.559511)
			(xy 58.603617 -316.48637) (xy 58.631224 -316.415765) (xy 58.66618 -316.348494) (xy 58.708088 -316.285319)
			(xy 58.756474 -316.226957) (xy 58.81079 -316.174069) (xy 58.870419 -316.127254) (xy 58.934687 -316.087042)
			(xy 59.002864 -316.05389) (xy 59.07418 -316.028172) (xy 59.147825 -316.01018) (xy 59.222965 -316.000118)
			(xy 59.298749 -315.998099) (xy 59.374319 -316.004148) (xy 59.448817 -316.018195) (xy 59.5214 -316.040081)
			(xy 59.591246 -316.069558) (xy 59.657563 -316.106293) (xy 59.719599 -316.149868) (xy 59.776652 -316.19979)
			(xy 59.828076 -316.255494) (xy 59.873287 -316.316349) (xy 59.911774 -316.381664) (xy 59.9431 -316.4507)
			(xy 59.96691 -316.522675) (xy 59.982935 -316.596773) (xy 59.990994 -316.672154) (xy 59.991498 -316.71006)
			(xy 61.107577 -316.71006) (xy 61.111612 -316.634356) (xy 61.123671 -316.559511) (xy 61.143617 -316.48637)
			(xy 61.171224 -316.415765) (xy 61.20618 -316.348494) (xy 61.248088 -316.285319) (xy 61.296474 -316.226957)
			(xy 61.35079 -316.174069) (xy 61.410419 -316.127254) (xy 61.474687 -316.087042) (xy 61.542864 -316.05389)
			(xy 61.61418 -316.028172) (xy 61.687825 -316.01018) (xy 61.762965 -316.000118) (xy 61.838749 -315.998099)
			(xy 61.914319 -316.004148) (xy 61.988817 -316.018195) (xy 62.0614 -316.040081) (xy 62.131246 -316.069558)
			(xy 62.197563 -316.106293) (xy 62.259599 -316.149868) (xy 62.265544 -316.15507) (xy 86.197697 -316.15507)
			(xy 86.201732 -316.079366) (xy 86.213791 -316.004521) (xy 86.233737 -315.93138) (xy 86.261344 -315.860775)
			(xy 86.2963 -315.793504) (xy 86.338208 -315.730329) (xy 86.386594 -315.671967) (xy 86.44091 -315.619079)
			(xy 86.500539 -315.572264) (xy 86.564807 -315.532052) (xy 86.632984 -315.4989) (xy 86.7043 -315.473182)
			(xy 86.777945 -315.45519) (xy 86.853085 -315.445128) (xy 86.928869 -315.443109) (xy 87.004439 -315.449158)
			(xy 87.078937 -315.463205) (xy 87.15152 -315.485091) (xy 87.221366 -315.514568) (xy 87.287683 -315.551303)
			(xy 87.349719 -315.594878) (xy 87.406772 -315.6448) (xy 87.458196 -315.700504) (xy 87.503407 -315.761359)
			(xy 87.541894 -315.826674) (xy 87.57322 -315.89571) (xy 87.59703 -315.967685) (xy 87.613055 -316.041783)
			(xy 87.621114 -316.117164) (xy 87.621618 -316.15507) (xy 88.737697 -316.15507) (xy 88.741732 -316.079366)
			(xy 88.753791 -316.004521) (xy 88.773737 -315.93138) (xy 88.801344 -315.860775) (xy 88.8363 -315.793504)
			(xy 88.878208 -315.730329) (xy 88.926594 -315.671967) (xy 88.98091 -315.619079) (xy 89.040539 -315.572264)
			(xy 89.104807 -315.532052) (xy 89.172984 -315.4989) (xy 89.2443 -315.473182) (xy 89.317945 -315.45519)
			(xy 89.393085 -315.445128) (xy 89.468869 -315.443109) (xy 89.544439 -315.449158) (xy 89.618937 -315.463205)
			(xy 89.69152 -315.485091) (xy 89.761366 -315.514568) (xy 89.827683 -315.551303) (xy 89.889719 -315.594878)
			(xy 89.946772 -315.6448) (xy 89.998196 -315.700504) (xy 90.043407 -315.761359) (xy 90.081894 -315.826674)
			(xy 90.11322 -315.89571) (xy 90.13703 -315.967685) (xy 90.153055 -316.041783) (xy 90.161114 -316.117164)
			(xy 90.161618 -316.15507) (xy 91.277697 -316.15507) (xy 91.281732 -316.079366) (xy 91.293791 -316.004521)
			(xy 91.313737 -315.93138) (xy 91.341344 -315.860775) (xy 91.3763 -315.793504) (xy 91.418208 -315.730329)
			(xy 91.466594 -315.671967) (xy 91.52091 -315.619079) (xy 91.580539 -315.572264) (xy 91.644807 -315.532052)
			(xy 91.712984 -315.4989) (xy 91.7843 -315.473182) (xy 91.857945 -315.45519) (xy 91.933085 -315.445128)
			(xy 92.008869 -315.443109) (xy 92.084439 -315.449158) (xy 92.158937 -315.463205) (xy 92.23152 -315.485091)
			(xy 92.301366 -315.514568) (xy 92.367683 -315.551303) (xy 92.429719 -315.594878) (xy 92.486772 -315.6448)
			(xy 92.538196 -315.700504) (xy 92.583407 -315.761359) (xy 92.621894 -315.826674) (xy 92.65322 -315.89571)
			(xy 92.67703 -315.967685) (xy 92.693055 -316.041783) (xy 92.701114 -316.117164) (xy 92.701618 -316.15507)
			(xy 92.701114 -316.192976) (xy 92.693055 -316.268357) (xy 92.67703 -316.342455) (xy 92.65322 -316.41443)
			(xy 92.621894 -316.483466) (xy 92.583407 -316.548781) (xy 92.538196 -316.609636) (xy 92.486772 -316.66534)
			(xy 92.429719 -316.715262) (xy 92.367683 -316.758837) (xy 92.301366 -316.795572) (xy 92.23152 -316.825049)
			(xy 92.158937 -316.846935) (xy 92.084439 -316.860982) (xy 92.008869 -316.867031) (xy 91.933085 -316.865012)
			(xy 91.857945 -316.85495) (xy 91.7843 -316.836958) (xy 91.712984 -316.81124) (xy 91.644807 -316.778088)
			(xy 91.580539 -316.737876) (xy 91.52091 -316.691061) (xy 91.466594 -316.638173) (xy 91.418208 -316.579811)
			(xy 91.3763 -316.516636) (xy 91.341344 -316.449365) (xy 91.313737 -316.37876) (xy 91.293791 -316.305619)
			(xy 91.281732 -316.230774) (xy 91.277697 -316.15507) (xy 90.161618 -316.15507) (xy 90.161114 -316.192976)
			(xy 90.153055 -316.268357) (xy 90.13703 -316.342455) (xy 90.11322 -316.41443) (xy 90.081894 -316.483466)
			(xy 90.043407 -316.548781) (xy 89.998196 -316.609636) (xy 89.946772 -316.66534) (xy 89.889719 -316.715262)
			(xy 89.827683 -316.758837) (xy 89.761366 -316.795572) (xy 89.69152 -316.825049) (xy 89.618937 -316.846935)
			(xy 89.544439 -316.860982) (xy 89.468869 -316.867031) (xy 89.393085 -316.865012) (xy 89.317945 -316.85495)
			(xy 89.2443 -316.836958) (xy 89.172984 -316.81124) (xy 89.104807 -316.778088) (xy 89.040539 -316.737876)
			(xy 88.98091 -316.691061) (xy 88.926594 -316.638173) (xy 88.878208 -316.579811) (xy 88.8363 -316.516636)
			(xy 88.801344 -316.449365) (xy 88.773737 -316.37876) (xy 88.753791 -316.305619) (xy 88.741732 -316.230774)
			(xy 88.737697 -316.15507) (xy 87.621618 -316.15507) (xy 87.621114 -316.192976) (xy 87.613055 -316.268357)
			(xy 87.59703 -316.342455) (xy 87.57322 -316.41443) (xy 87.541894 -316.483466) (xy 87.503407 -316.548781)
			(xy 87.458196 -316.609636) (xy 87.406772 -316.66534) (xy 87.349719 -316.715262) (xy 87.287683 -316.758837)
			(xy 87.221366 -316.795572) (xy 87.15152 -316.825049) (xy 87.078937 -316.846935) (xy 87.004439 -316.860982)
			(xy 86.928869 -316.867031) (xy 86.853085 -316.865012) (xy 86.777945 -316.85495) (xy 86.7043 -316.836958)
			(xy 86.632984 -316.81124) (xy 86.564807 -316.778088) (xy 86.500539 -316.737876) (xy 86.44091 -316.691061)
			(xy 86.386594 -316.638173) (xy 86.338208 -316.579811) (xy 86.2963 -316.516636) (xy 86.261344 -316.449365)
			(xy 86.233737 -316.37876) (xy 86.213791 -316.305619) (xy 86.201732 -316.230774) (xy 86.197697 -316.15507)
			(xy 62.265544 -316.15507) (xy 62.316652 -316.19979) (xy 62.368076 -316.255494) (xy 62.413287 -316.316349)
			(xy 62.451774 -316.381664) (xy 62.4831 -316.4507) (xy 62.50691 -316.522675) (xy 62.522935 -316.596773)
			(xy 62.530994 -316.672154) (xy 62.531498 -316.71006) (xy 62.530994 -316.747966) (xy 62.522935 -316.823347)
			(xy 62.50691 -316.897445) (xy 62.4831 -316.96942) (xy 62.451774 -317.038456) (xy 62.413287 -317.103771)
			(xy 62.368076 -317.164626) (xy 62.316652 -317.22033) (xy 62.259599 -317.270252) (xy 62.197563 -317.313827)
			(xy 62.131246 -317.350562) (xy 62.0614 -317.380039) (xy 61.988817 -317.401925) (xy 61.914319 -317.415972)
			(xy 61.838749 -317.422021) (xy 61.762965 -317.420002) (xy 61.687825 -317.40994) (xy 61.61418 -317.391948)
			(xy 61.542864 -317.36623) (xy 61.474687 -317.333078) (xy 61.410419 -317.292866) (xy 61.35079 -317.246051)
			(xy 61.296474 -317.193163) (xy 61.248088 -317.134801) (xy 61.20618 -317.071626) (xy 61.171224 -317.004355)
			(xy 61.143617 -316.93375) (xy 61.123671 -316.860609) (xy 61.111612 -316.785764) (xy 61.107577 -316.71006)
			(xy 59.991498 -316.71006) (xy 59.990994 -316.747966) (xy 59.982935 -316.823347) (xy 59.96691 -316.897445)
			(xy 59.9431 -316.96942) (xy 59.911774 -317.038456) (xy 59.873287 -317.103771) (xy 59.828076 -317.164626)
			(xy 59.776652 -317.22033) (xy 59.719599 -317.270252) (xy 59.657563 -317.313827) (xy 59.591246 -317.350562)
			(xy 59.5214 -317.380039) (xy 59.448817 -317.401925) (xy 59.374319 -317.415972) (xy 59.298749 -317.422021)
			(xy 59.222965 -317.420002) (xy 59.147825 -317.40994) (xy 59.07418 -317.391948) (xy 59.002864 -317.36623)
			(xy 58.934687 -317.333078) (xy 58.870419 -317.292866) (xy 58.81079 -317.246051) (xy 58.756474 -317.193163)
			(xy 58.708088 -317.134801) (xy 58.66618 -317.071626) (xy 58.631224 -317.004355) (xy 58.603617 -316.93375)
			(xy 58.583671 -316.860609) (xy 58.571612 -316.785764) (xy 58.567577 -316.71006) (xy 57.451498 -316.71006)
			(xy 57.450994 -316.747966) (xy 57.442935 -316.823347) (xy 57.42691 -316.897445) (xy 57.4031 -316.96942)
			(xy 57.371774 -317.038456) (xy 57.333287 -317.103771) (xy 57.288076 -317.164626) (xy 57.236652 -317.22033)
			(xy 57.179599 -317.270252) (xy 57.117563 -317.313827) (xy 57.051246 -317.350562) (xy 56.9814 -317.380039)
			(xy 56.908817 -317.401925) (xy 56.834319 -317.415972) (xy 56.758749 -317.422021) (xy 56.682965 -317.420002)
			(xy 56.607825 -317.40994) (xy 56.53418 -317.391948) (xy 56.462864 -317.36623) (xy 56.394687 -317.333078)
			(xy 56.330419 -317.292866) (xy 56.27079 -317.246051) (xy 56.216474 -317.193163) (xy 56.168088 -317.134801)
			(xy 56.12618 -317.071626) (xy 56.091224 -317.004355) (xy 56.063617 -316.93375) (xy 56.043671 -316.860609)
			(xy 56.031612 -316.785764) (xy 56.027577 -316.71006) (xy 54.911498 -316.71006) (xy 54.910994 -316.747966)
			(xy 54.902935 -316.823347) (xy 54.88691 -316.897445) (xy 54.8631 -316.96942) (xy 54.831774 -317.038456)
			(xy 54.793287 -317.103771) (xy 54.748076 -317.164626) (xy 54.696652 -317.22033) (xy 54.639599 -317.270252)
			(xy 54.577563 -317.313827) (xy 54.511246 -317.350562) (xy 54.4414 -317.380039) (xy 54.368817 -317.401925)
			(xy 54.294319 -317.415972) (xy 54.218749 -317.422021) (xy 54.142965 -317.420002) (xy 54.067825 -317.40994)
			(xy 53.99418 -317.391948) (xy 53.922864 -317.36623) (xy 53.854687 -317.333078) (xy 53.790419 -317.292866)
			(xy 53.73079 -317.246051) (xy 53.676474 -317.193163) (xy 53.628088 -317.134801) (xy 53.58618 -317.071626)
			(xy 53.551224 -317.004355) (xy 53.523617 -316.93375) (xy 53.503671 -316.860609) (xy 53.491612 -316.785764)
			(xy 53.487577 -316.71006) (xy 52.371498 -316.71006) (xy 52.370994 -316.747966) (xy 52.362935 -316.823347)
			(xy 52.34691 -316.897445) (xy 52.3231 -316.96942) (xy 52.291774 -317.038456) (xy 52.253287 -317.103771)
			(xy 52.208076 -317.164626) (xy 52.156652 -317.22033) (xy 52.099599 -317.270252) (xy 52.037563 -317.313827)
			(xy 51.971246 -317.350562) (xy 51.9014 -317.380039) (xy 51.828817 -317.401925) (xy 51.754319 -317.415972)
			(xy 51.678749 -317.422021) (xy 51.602965 -317.420002) (xy 51.527825 -317.40994) (xy 51.45418 -317.391948)
			(xy 51.382864 -317.36623) (xy 51.314687 -317.333078) (xy 51.250419 -317.292866) (xy 51.19079 -317.246051)
			(xy 51.136474 -317.193163) (xy 51.088088 -317.134801) (xy 51.04618 -317.071626) (xy 51.011224 -317.004355)
			(xy 50.983617 -316.93375) (xy 50.963671 -316.860609) (xy 50.951612 -316.785764) (xy 50.947577 -316.71006)
			(xy 49.831498 -316.71006) (xy 49.830994 -316.747966) (xy 49.822935 -316.823347) (xy 49.80691 -316.897445)
			(xy 49.7831 -316.96942) (xy 49.751774 -317.038456) (xy 49.713287 -317.103771) (xy 49.668076 -317.164626)
			(xy 49.616652 -317.22033) (xy 49.559599 -317.270252) (xy 49.497563 -317.313827) (xy 49.431246 -317.350562)
			(xy 49.3614 -317.380039) (xy 49.288817 -317.401925) (xy 49.214319 -317.415972) (xy 49.138749 -317.422021)
			(xy 49.062965 -317.420002) (xy 48.987825 -317.40994) (xy 48.91418 -317.391948) (xy 48.842864 -317.36623)
			(xy 48.774687 -317.333078) (xy 48.710419 -317.292866) (xy 48.65079 -317.246051) (xy 48.596474 -317.193163)
			(xy 48.548088 -317.134801) (xy 48.50618 -317.071626) (xy 48.471224 -317.004355) (xy 48.443617 -316.93375)
			(xy 48.423671 -316.860609) (xy 48.411612 -316.785764) (xy 48.407577 -316.71006) (xy 47.291498 -316.71006)
			(xy 47.290994 -316.747966) (xy 47.282935 -316.823347) (xy 47.26691 -316.897445) (xy 47.2431 -316.96942)
			(xy 47.211774 -317.038456) (xy 47.173287 -317.103771) (xy 47.128076 -317.164626) (xy 47.076652 -317.22033)
			(xy 47.019599 -317.270252) (xy 46.957563 -317.313827) (xy 46.891246 -317.350562) (xy 46.8214 -317.380039)
			(xy 46.748817 -317.401925) (xy 46.674319 -317.415972) (xy 46.598749 -317.422021) (xy 46.522965 -317.420002)
			(xy 46.447825 -317.40994) (xy 46.37418 -317.391948) (xy 46.302864 -317.36623) (xy 46.234687 -317.333078)
			(xy 46.170419 -317.292866) (xy 46.11079 -317.246051) (xy 46.056474 -317.193163) (xy 46.008088 -317.134801)
			(xy 45.96618 -317.071626) (xy 45.931224 -317.004355) (xy 45.903617 -316.93375) (xy 45.883671 -316.860609)
			(xy 45.871612 -316.785764) (xy 45.867577 -316.71006) (xy 44.751498 -316.71006) (xy 44.750994 -316.747966)
			(xy 44.742935 -316.823347) (xy 44.72691 -316.897445) (xy 44.7031 -316.96942) (xy 44.671774 -317.038456)
			(xy 44.633287 -317.103771) (xy 44.588076 -317.164626) (xy 44.536652 -317.22033) (xy 44.479599 -317.270252)
			(xy 44.417563 -317.313827) (xy 44.351246 -317.350562) (xy 44.2814 -317.380039) (xy 44.208817 -317.401925)
			(xy 44.134319 -317.415972) (xy 44.058749 -317.422021) (xy 43.982965 -317.420002) (xy 43.907825 -317.40994)
			(xy 43.83418 -317.391948) (xy 43.762864 -317.36623) (xy 43.694687 -317.333078) (xy 43.630419 -317.292866)
			(xy 43.57079 -317.246051) (xy 43.516474 -317.193163) (xy 43.468088 -317.134801) (xy 43.42618 -317.071626)
			(xy 43.391224 -317.004355) (xy 43.363617 -316.93375) (xy 43.343671 -316.860609) (xy 43.331612 -316.785764)
			(xy 43.327577 -316.71006) (xy 42.501239 -316.71006) (xy 42.515699 -316.720266) (xy 42.604766 -316.792723)
			(xy 42.688681 -316.871089) (xy 42.767054 -316.954998) (xy 42.839517 -317.04406) (xy 42.905734 -317.137859)
			(xy 42.965396 -317.235958) (xy 43.018225 -317.3379) (xy 43.056094 -317.42507) (xy 84.927697 -317.42507)
			(xy 84.931732 -317.349366) (xy 84.943791 -317.274521) (xy 84.963737 -317.20138) (xy 84.991344 -317.130775)
			(xy 85.0263 -317.063504) (xy 85.068208 -317.000329) (xy 85.116594 -316.941967) (xy 85.17091 -316.889079)
			(xy 85.230539 -316.842264) (xy 85.294807 -316.802052) (xy 85.362984 -316.7689) (xy 85.4343 -316.743182)
			(xy 85.507945 -316.72519) (xy 85.583085 -316.715128) (xy 85.658869 -316.713109) (xy 85.734439 -316.719158)
			(xy 85.808937 -316.733205) (xy 85.88152 -316.755091) (xy 85.951366 -316.784568) (xy 86.017683 -316.821303)
			(xy 86.079719 -316.864878) (xy 86.136772 -316.9148) (xy 86.188196 -316.970504) (xy 86.233407 -317.031359)
			(xy 86.271894 -317.096674) (xy 86.30322 -317.16571) (xy 86.32703 -317.237685) (xy 86.343055 -317.311783)
			(xy 86.351114 -317.387164) (xy 86.351618 -317.42507) (xy 87.467697 -317.42507) (xy 87.471732 -317.349366)
			(xy 87.483791 -317.274521) (xy 87.503737 -317.20138) (xy 87.531344 -317.130775) (xy 87.5663 -317.063504)
			(xy 87.608208 -317.000329) (xy 87.656594 -316.941967) (xy 87.71091 -316.889079) (xy 87.770539 -316.842264)
			(xy 87.834807 -316.802052) (xy 87.902984 -316.7689) (xy 87.9743 -316.743182) (xy 88.047945 -316.72519)
			(xy 88.123085 -316.715128) (xy 88.198869 -316.713109) (xy 88.274439 -316.719158) (xy 88.348937 -316.733205)
			(xy 88.42152 -316.755091) (xy 88.491366 -316.784568) (xy 88.557683 -316.821303) (xy 88.619719 -316.864878)
			(xy 88.676772 -316.9148) (xy 88.728196 -316.970504) (xy 88.773407 -317.031359) (xy 88.811894 -317.096674)
			(xy 88.84322 -317.16571) (xy 88.86703 -317.237685) (xy 88.883055 -317.311783) (xy 88.891114 -317.387164)
			(xy 88.891618 -317.42507) (xy 90.007697 -317.42507) (xy 90.011732 -317.349366) (xy 90.023791 -317.274521)
			(xy 90.043737 -317.20138) (xy 90.071344 -317.130775) (xy 90.1063 -317.063504) (xy 90.148208 -317.000329)
			(xy 90.196594 -316.941967) (xy 90.25091 -316.889079) (xy 90.310539 -316.842264) (xy 90.374807 -316.802052)
			(xy 90.442984 -316.7689) (xy 90.5143 -316.743182) (xy 90.587945 -316.72519) (xy 90.663085 -316.715128)
			(xy 90.738869 -316.713109) (xy 90.814439 -316.719158) (xy 90.888937 -316.733205) (xy 90.96152 -316.755091)
			(xy 91.031366 -316.784568) (xy 91.097683 -316.821303) (xy 91.159719 -316.864878) (xy 91.216772 -316.9148)
			(xy 91.268196 -316.970504) (xy 91.313407 -317.031359) (xy 91.351894 -317.096674) (xy 91.38322 -317.16571)
			(xy 91.40703 -317.237685) (xy 91.423055 -317.311783) (xy 91.431114 -317.387164) (xy 91.431618 -317.42507)
			(xy 91.431114 -317.462976) (xy 91.423055 -317.538357) (xy 91.40703 -317.612455) (xy 91.38322 -317.68443)
			(xy 91.351894 -317.753466) (xy 91.313407 -317.818781) (xy 91.268196 -317.879636) (xy 91.216772 -317.93534)
			(xy 91.159719 -317.985262) (xy 91.097683 -318.028837) (xy 91.031366 -318.065572) (xy 90.96152 -318.095049)
			(xy 90.888937 -318.116935) (xy 90.814439 -318.130982) (xy 90.738869 -318.137031) (xy 90.663085 -318.135012)
			(xy 90.587945 -318.12495) (xy 90.5143 -318.106958) (xy 90.442984 -318.08124) (xy 90.374807 -318.048088)
			(xy 90.310539 -318.007876) (xy 90.25091 -317.961061) (xy 90.196594 -317.908173) (xy 90.148208 -317.849811)
			(xy 90.1063 -317.786636) (xy 90.071344 -317.719365) (xy 90.043737 -317.64876) (xy 90.023791 -317.575619)
			(xy 90.011732 -317.500774) (xy 90.007697 -317.42507) (xy 88.891618 -317.42507) (xy 88.891114 -317.462976)
			(xy 88.883055 -317.538357) (xy 88.86703 -317.612455) (xy 88.84322 -317.68443) (xy 88.811894 -317.753466)
			(xy 88.773407 -317.818781) (xy 88.728196 -317.879636) (xy 88.676772 -317.93534) (xy 88.619719 -317.985262)
			(xy 88.557683 -318.028837) (xy 88.491366 -318.065572) (xy 88.42152 -318.095049) (xy 88.348937 -318.116935)
			(xy 88.274439 -318.130982) (xy 88.198869 -318.137031) (xy 88.123085 -318.135012) (xy 88.047945 -318.12495)
			(xy 87.9743 -318.106958) (xy 87.902984 -318.08124) (xy 87.834807 -318.048088) (xy 87.770539 -318.007876)
			(xy 87.71091 -317.961061) (xy 87.656594 -317.908173) (xy 87.608208 -317.849811) (xy 87.5663 -317.786636)
			(xy 87.531344 -317.719365) (xy 87.503737 -317.64876) (xy 87.483791 -317.575619) (xy 87.471732 -317.500774)
			(xy 87.467697 -317.42507) (xy 86.351618 -317.42507) (xy 86.351114 -317.462976) (xy 86.343055 -317.538357)
			(xy 86.32703 -317.612455) (xy 86.30322 -317.68443) (xy 86.271894 -317.753466) (xy 86.233407 -317.818781)
			(xy 86.188196 -317.879636) (xy 86.136772 -317.93534) (xy 86.079719 -317.985262) (xy 86.017683 -318.028837)
			(xy 85.951366 -318.065572) (xy 85.88152 -318.095049) (xy 85.808937 -318.116935) (xy 85.734439 -318.130982)
			(xy 85.658869 -318.137031) (xy 85.583085 -318.135012) (xy 85.507945 -318.12495) (xy 85.4343 -318.106958)
			(xy 85.362984 -318.08124) (xy 85.294807 -318.048088) (xy 85.230539 -318.007876) (xy 85.17091 -317.961061)
			(xy 85.116594 -317.908173) (xy 85.068208 -317.849811) (xy 85.0263 -317.786636) (xy 84.991344 -317.719365)
			(xy 84.963737 -317.64876) (xy 84.943791 -317.575619) (xy 84.931732 -317.500774) (xy 84.927697 -317.42507)
			(xy 43.056094 -317.42507) (xy 43.063974 -317.443209) (xy 43.10243 -317.551394) (xy 43.133415 -317.661952)
			(xy 43.156782 -317.774366) (xy 43.172424 -317.888113) (xy 43.180268 -318.002661) (xy 43.180762 -318.06007)
			(xy 43.180576 -318.093253) (xy 43.177909 -318.159567) (xy 43.175428 -318.192658) (xy 43.170272 -318.250942)
			(xy 43.152948 -318.366671) (xy 43.127616 -318.480914) (xy 43.094401 -318.593119) (xy 43.056327 -318.69507)
			(xy 86.197697 -318.69507) (xy 86.201732 -318.619366) (xy 86.213791 -318.544521) (xy 86.233737 -318.47138)
			(xy 86.261344 -318.400775) (xy 86.2963 -318.333504) (xy 86.338208 -318.270329) (xy 86.386594 -318.211967)
			(xy 86.44091 -318.159079) (xy 86.500539 -318.112264) (xy 86.564807 -318.072052) (xy 86.632984 -318.0389)
			(xy 86.7043 -318.013182) (xy 86.777945 -317.99519) (xy 86.853085 -317.985128) (xy 86.928869 -317.983109)
			(xy 87.004439 -317.989158) (xy 87.078937 -318.003205) (xy 87.15152 -318.025091) (xy 87.221366 -318.054568)
			(xy 87.287683 -318.091303) (xy 87.349719 -318.134878) (xy 87.406772 -318.1848) (xy 87.458196 -318.240504)
			(xy 87.503407 -318.301359) (xy 87.541894 -318.366674) (xy 87.57322 -318.43571) (xy 87.59703 -318.507685)
			(xy 87.613055 -318.581783) (xy 87.621114 -318.657164) (xy 87.621618 -318.69507) (xy 88.737697 -318.69507)
			(xy 88.741732 -318.619366) (xy 88.753791 -318.544521) (xy 88.773737 -318.47138) (xy 88.801344 -318.400775)
			(xy 88.8363 -318.333504) (xy 88.878208 -318.270329) (xy 88.926594 -318.211967) (xy 88.98091 -318.159079)
			(xy 89.040539 -318.112264) (xy 89.104807 -318.072052) (xy 89.172984 -318.0389) (xy 89.2443 -318.013182)
			(xy 89.317945 -317.99519) (xy 89.393085 -317.985128) (xy 89.468869 -317.983109) (xy 89.544439 -317.989158)
			(xy 89.618937 -318.003205) (xy 89.69152 -318.025091) (xy 89.761366 -318.054568) (xy 89.827683 -318.091303)
			(xy 89.889719 -318.134878) (xy 89.946772 -318.1848) (xy 89.998196 -318.240504) (xy 90.043407 -318.301359)
			(xy 90.081894 -318.366674) (xy 90.11322 -318.43571) (xy 90.13703 -318.507685) (xy 90.153055 -318.581783)
			(xy 90.161114 -318.657164) (xy 90.161618 -318.69507) (xy 91.277697 -318.69507) (xy 91.281732 -318.619366)
			(xy 91.293791 -318.544521) (xy 91.313737 -318.47138) (xy 91.341344 -318.400775) (xy 91.3763 -318.333504)
			(xy 91.418208 -318.270329) (xy 91.466594 -318.211967) (xy 91.52091 -318.159079) (xy 91.580539 -318.112264)
			(xy 91.644807 -318.072052) (xy 91.712984 -318.0389) (xy 91.7843 -318.013182) (xy 91.857945 -317.99519)
			(xy 91.933085 -317.985128) (xy 92.008869 -317.983109) (xy 92.084439 -317.989158) (xy 92.158937 -318.003205)
			(xy 92.23152 -318.025091) (xy 92.301366 -318.054568) (xy 92.367683 -318.091303) (xy 92.429719 -318.134878)
			(xy 92.486772 -318.1848) (xy 92.538196 -318.240504) (xy 92.583407 -318.301359) (xy 92.621894 -318.366674)
			(xy 92.65322 -318.43571) (xy 92.67703 -318.507685) (xy 92.693055 -318.581783) (xy 92.701114 -318.657164)
			(xy 92.701618 -318.69507) (xy 92.701114 -318.732976) (xy 92.693055 -318.808357) (xy 92.67703 -318.882455)
			(xy 92.65322 -318.95443) (xy 92.621894 -319.023466) (xy 92.583407 -319.088781) (xy 92.538196 -319.149636)
			(xy 92.486772 -319.20534) (xy 92.429719 -319.255262) (xy 92.367683 -319.298837) (xy 92.301366 -319.335572)
			(xy 92.23152 -319.365049) (xy 92.158937 -319.386935) (xy 92.084439 -319.400982) (xy 92.008869 -319.407031)
			(xy 91.933085 -319.405012) (xy 91.857945 -319.39495) (xy 91.7843 -319.376958) (xy 91.712984 -319.35124)
			(xy 91.644807 -319.318088) (xy 91.580539 -319.277876) (xy 91.52091 -319.231061) (xy 91.466594 -319.178173)
			(xy 91.418208 -319.119811) (xy 91.3763 -319.056636) (xy 91.341344 -318.989365) (xy 91.313737 -318.91876)
			(xy 91.293791 -318.845619) (xy 91.281732 -318.770774) (xy 91.277697 -318.69507) (xy 90.161618 -318.69507)
			(xy 90.161114 -318.732976) (xy 90.153055 -318.808357) (xy 90.13703 -318.882455) (xy 90.11322 -318.95443)
			(xy 90.081894 -319.023466) (xy 90.043407 -319.088781) (xy 89.998196 -319.149636) (xy 89.946772 -319.20534)
			(xy 89.889719 -319.255262) (xy 89.827683 -319.298837) (xy 89.761366 -319.335572) (xy 89.69152 -319.365049)
			(xy 89.618937 -319.386935) (xy 89.544439 -319.400982) (xy 89.468869 -319.407031) (xy 89.393085 -319.405012)
			(xy 89.317945 -319.39495) (xy 89.2443 -319.376958) (xy 89.172984 -319.35124) (xy 89.104807 -319.318088)
			(xy 89.040539 -319.277876) (xy 88.98091 -319.231061) (xy 88.926594 -319.178173) (xy 88.878208 -319.119811)
			(xy 88.8363 -319.056636) (xy 88.801344 -318.989365) (xy 88.773737 -318.91876) (xy 88.753791 -318.845619)
			(xy 88.741732 -318.770774) (xy 88.737697 -318.69507) (xy 87.621618 -318.69507) (xy 87.621114 -318.732976)
			(xy 87.613055 -318.808357) (xy 87.59703 -318.882455) (xy 87.57322 -318.95443) (xy 87.541894 -319.023466)
			(xy 87.503407 -319.088781) (xy 87.458196 -319.149636) (xy 87.406772 -319.20534) (xy 87.349719 -319.255262)
			(xy 87.287683 -319.298837) (xy 87.221366 -319.335572) (xy 87.15152 -319.365049) (xy 87.078937 -319.386935)
			(xy 87.004439 -319.400982) (xy 86.928869 -319.407031) (xy 86.853085 -319.405012) (xy 86.777945 -319.39495)
			(xy 86.7043 -319.376958) (xy 86.632984 -319.35124) (xy 86.564807 -319.318088) (xy 86.500539 -319.277876)
			(xy 86.44091 -319.231061) (xy 86.386594 -319.178173) (xy 86.338208 -319.119811) (xy 86.2963 -319.056636)
			(xy 86.261344 -318.989365) (xy 86.233737 -318.91876) (xy 86.213791 -318.845619) (xy 86.201732 -318.770774)
			(xy 86.197697 -318.69507) (xy 43.056327 -318.69507) (xy 43.055094 -318.698372) (xy 43.328336 -318.698372)
			(xy 44.751244 -318.698372) (xy 44.751244 -319.41008) (xy 45.867577 -319.41008) (xy 45.871612 -319.334376)
			(xy 45.883671 -319.259531) (xy 45.903617 -319.18639) (xy 45.931224 -319.115785) (xy 45.96618 -319.048514)
			(xy 46.008088 -318.985339) (xy 46.056474 -318.926977) (xy 46.11079 -318.874089) (xy 46.170419 -318.827274)
			(xy 46.234687 -318.787062) (xy 46.302864 -318.75391) (xy 46.37418 -318.728192) (xy 46.447825 -318.7102)
			(xy 46.522965 -318.700138) (xy 46.598749 -318.698119) (xy 46.674319 -318.704168) (xy 46.748817 -318.718215)
			(xy 46.8214 -318.740101) (xy 46.891246 -318.769578) (xy 46.957563 -318.806313) (xy 47.019599 -318.849888)
			(xy 47.076652 -318.89981) (xy 47.128076 -318.955514) (xy 47.173287 -319.016369) (xy 47.211774 -319.081684)
			(xy 47.2431 -319.15072) (xy 47.26691 -319.222695) (xy 47.282935 -319.296793) (xy 47.290994 -319.372174)
			(xy 47.291498 -319.41008) (xy 48.407577 -319.41008) (xy 48.411612 -319.334376) (xy 48.423671 -319.259531)
			(xy 48.443617 -319.18639) (xy 48.471224 -319.115785) (xy 48.50618 -319.048514) (xy 48.548088 -318.985339)
			(xy 48.596474 -318.926977) (xy 48.65079 -318.874089) (xy 48.710419 -318.827274) (xy 48.774687 -318.787062)
			(xy 48.842864 -318.75391) (xy 48.91418 -318.728192) (xy 48.987825 -318.7102) (xy 49.062965 -318.700138)
			(xy 49.138749 -318.698119) (xy 49.214319 -318.704168) (xy 49.288817 -318.718215) (xy 49.3614 -318.740101)
			(xy 49.431246 -318.769578) (xy 49.497563 -318.806313) (xy 49.559599 -318.849888) (xy 49.616652 -318.89981)
			(xy 49.668076 -318.955514) (xy 49.713287 -319.016369) (xy 49.751774 -319.081684) (xy 49.7831 -319.15072)
			(xy 49.80691 -319.222695) (xy 49.822935 -319.296793) (xy 49.830994 -319.372174) (xy 49.831498 -319.41008)
			(xy 50.947577 -319.41008) (xy 50.951612 -319.334376) (xy 50.963671 -319.259531) (xy 50.983617 -319.18639)
			(xy 51.011224 -319.115785) (xy 51.04618 -319.048514) (xy 51.088088 -318.985339) (xy 51.136474 -318.926977)
			(xy 51.19079 -318.874089) (xy 51.250419 -318.827274) (xy 51.314687 -318.787062) (xy 51.382864 -318.75391)
			(xy 51.45418 -318.728192) (xy 51.527825 -318.7102) (xy 51.602965 -318.700138) (xy 51.678749 -318.698119)
			(xy 51.754319 -318.704168) (xy 51.828817 -318.718215) (xy 51.9014 -318.740101) (xy 51.971246 -318.769578)
			(xy 52.037563 -318.806313) (xy 52.099599 -318.849888) (xy 52.156652 -318.89981) (xy 52.208076 -318.955514)
			(xy 52.253287 -319.016369) (xy 52.291774 -319.081684) (xy 52.3231 -319.15072) (xy 52.34691 -319.222695)
			(xy 52.362935 -319.296793) (xy 52.370994 -319.372174) (xy 52.371498 -319.41008) (xy 53.487577 -319.41008)
			(xy 53.491612 -319.334376) (xy 53.503671 -319.259531) (xy 53.523617 -319.18639) (xy 53.551224 -319.115785)
			(xy 53.58618 -319.048514) (xy 53.628088 -318.985339) (xy 53.676474 -318.926977) (xy 53.73079 -318.874089)
			(xy 53.790419 -318.827274) (xy 53.854687 -318.787062) (xy 53.922864 -318.75391) (xy 53.99418 -318.728192)
			(xy 54.067825 -318.7102) (xy 54.142965 -318.700138) (xy 54.218749 -318.698119) (xy 54.294319 -318.704168)
			(xy 54.368817 -318.718215) (xy 54.4414 -318.740101) (xy 54.511246 -318.769578) (xy 54.577563 -318.806313)
			(xy 54.639599 -318.849888) (xy 54.696652 -318.89981) (xy 54.748076 -318.955514) (xy 54.793287 -319.016369)
			(xy 54.831774 -319.081684) (xy 54.8631 -319.15072) (xy 54.88691 -319.222695) (xy 54.902935 -319.296793)
			(xy 54.910994 -319.372174) (xy 54.911498 -319.41008) (xy 56.027577 -319.41008) (xy 56.031612 -319.334376)
			(xy 56.043671 -319.259531) (xy 56.063617 -319.18639) (xy 56.091224 -319.115785) (xy 56.12618 -319.048514)
			(xy 56.168088 -318.985339) (xy 56.216474 -318.926977) (xy 56.27079 -318.874089) (xy 56.330419 -318.827274)
			(xy 56.394687 -318.787062) (xy 56.462864 -318.75391) (xy 56.53418 -318.728192) (xy 56.607825 -318.7102)
			(xy 56.682965 -318.700138) (xy 56.758749 -318.698119) (xy 56.834319 -318.704168) (xy 56.908817 -318.718215)
			(xy 56.9814 -318.740101) (xy 57.051246 -318.769578) (xy 57.117563 -318.806313) (xy 57.179599 -318.849888)
			(xy 57.236652 -318.89981) (xy 57.288076 -318.955514) (xy 57.333287 -319.016369) (xy 57.371774 -319.081684)
			(xy 57.4031 -319.15072) (xy 57.42691 -319.222695) (xy 57.442935 -319.296793) (xy 57.450994 -319.372174)
			(xy 57.451498 -319.41008) (xy 58.567577 -319.41008) (xy 58.571612 -319.334376) (xy 58.583671 -319.259531)
			(xy 58.603617 -319.18639) (xy 58.631224 -319.115785) (xy 58.66618 -319.048514) (xy 58.708088 -318.985339)
			(xy 58.756474 -318.926977) (xy 58.81079 -318.874089) (xy 58.870419 -318.827274) (xy 58.934687 -318.787062)
			(xy 59.002864 -318.75391) (xy 59.07418 -318.728192) (xy 59.147825 -318.7102) (xy 59.222965 -318.700138)
			(xy 59.298749 -318.698119) (xy 59.374319 -318.704168) (xy 59.448817 -318.718215) (xy 59.5214 -318.740101)
			(xy 59.591246 -318.769578) (xy 59.657563 -318.806313) (xy 59.719599 -318.849888) (xy 59.776652 -318.89981)
			(xy 59.828076 -318.955514) (xy 59.873287 -319.016369) (xy 59.911774 -319.081684) (xy 59.9431 -319.15072)
			(xy 59.96691 -319.222695) (xy 59.982935 -319.296793) (xy 59.990994 -319.372174) (xy 59.991498 -319.41008)
			(xy 61.107577 -319.41008) (xy 61.111612 -319.334376) (xy 61.123671 -319.259531) (xy 61.143617 -319.18639)
			(xy 61.171224 -319.115785) (xy 61.20618 -319.048514) (xy 61.248088 -318.985339) (xy 61.296474 -318.926977)
			(xy 61.35079 -318.874089) (xy 61.410419 -318.827274) (xy 61.474687 -318.787062) (xy 61.542864 -318.75391)
			(xy 61.61418 -318.728192) (xy 61.687825 -318.7102) (xy 61.762965 -318.700138) (xy 61.838749 -318.698119)
			(xy 61.914319 -318.704168) (xy 61.988817 -318.718215) (xy 62.0614 -318.740101) (xy 62.131246 -318.769578)
			(xy 62.197563 -318.806313) (xy 62.259599 -318.849888) (xy 62.316652 -318.89981) (xy 62.368076 -318.955514)
			(xy 62.413287 -319.016369) (xy 62.451774 -319.081684) (xy 62.4831 -319.15072) (xy 62.50691 -319.222695)
			(xy 62.522935 -319.296793) (xy 62.530994 -319.372174) (xy 62.531498 -319.41008) (xy 62.530994 -319.447986)
			(xy 62.522935 -319.523367) (xy 62.50691 -319.597465) (xy 62.4831 -319.66944) (xy 62.451774 -319.738476)
			(xy 62.413287 -319.803791) (xy 62.368076 -319.864646) (xy 62.316652 -319.92035) (xy 62.265544 -319.96507)
			(xy 84.927697 -319.96507) (xy 84.931732 -319.889366) (xy 84.943791 -319.814521) (xy 84.963737 -319.74138)
			(xy 84.991344 -319.670775) (xy 85.0263 -319.603504) (xy 85.068208 -319.540329) (xy 85.116594 -319.481967)
			(xy 85.17091 -319.429079) (xy 85.230539 -319.382264) (xy 85.294807 -319.342052) (xy 85.362984 -319.3089)
			(xy 85.4343 -319.283182) (xy 85.507945 -319.26519) (xy 85.583085 -319.255128) (xy 85.658869 -319.253109)
			(xy 85.734439 -319.259158) (xy 85.808937 -319.273205) (xy 85.88152 -319.295091) (xy 85.951366 -319.324568)
			(xy 86.017683 -319.361303) (xy 86.079719 -319.404878) (xy 86.136772 -319.4548) (xy 86.188196 -319.510504)
			(xy 86.233407 -319.571359) (xy 86.271894 -319.636674) (xy 86.30322 -319.70571) (xy 86.32703 -319.777685)
			(xy 86.343055 -319.851783) (xy 86.351114 -319.927164) (xy 86.351618 -319.96507) (xy 87.467697 -319.96507)
			(xy 87.471732 -319.889366) (xy 87.483791 -319.814521) (xy 87.503737 -319.74138) (xy 87.531344 -319.670775)
			(xy 87.5663 -319.603504) (xy 87.608208 -319.540329) (xy 87.656594 -319.481967) (xy 87.71091 -319.429079)
			(xy 87.770539 -319.382264) (xy 87.834807 -319.342052) (xy 87.902984 -319.3089) (xy 87.9743 -319.283182)
			(xy 88.047945 -319.26519) (xy 88.123085 -319.255128) (xy 88.198869 -319.253109) (xy 88.274439 -319.259158)
			(xy 88.348937 -319.273205) (xy 88.42152 -319.295091) (xy 88.491366 -319.324568) (xy 88.557683 -319.361303)
			(xy 88.619719 -319.404878) (xy 88.676772 -319.4548) (xy 88.728196 -319.510504) (xy 88.773407 -319.571359)
			(xy 88.811894 -319.636674) (xy 88.84322 -319.70571) (xy 88.86703 -319.777685) (xy 88.883055 -319.851783)
			(xy 88.891114 -319.927164) (xy 88.891618 -319.96507) (xy 90.007697 -319.96507) (xy 90.011732 -319.889366)
			(xy 90.023791 -319.814521) (xy 90.043737 -319.74138) (xy 90.071344 -319.670775) (xy 90.1063 -319.603504)
			(xy 90.148208 -319.540329) (xy 90.196594 -319.481967) (xy 90.25091 -319.429079) (xy 90.310539 -319.382264)
			(xy 90.374807 -319.342052) (xy 90.442984 -319.3089) (xy 90.5143 -319.283182) (xy 90.587945 -319.26519)
			(xy 90.663085 -319.255128) (xy 90.738869 -319.253109) (xy 90.814439 -319.259158) (xy 90.888937 -319.273205)
			(xy 90.96152 -319.295091) (xy 91.031366 -319.324568) (xy 91.097683 -319.361303) (xy 91.159719 -319.404878)
			(xy 91.165664 -319.41008) (xy 93.154506 -319.41008) (xy 93.158522 -319.29381) (xy 93.170549 -319.178095)
			(xy 93.190531 -319.063485) (xy 93.218373 -318.950526) (xy 93.253942 -318.839758) (xy 93.297068 -318.731707)
			(xy 93.347545 -318.626889) (xy 93.405134 -318.525804) (xy 93.46956 -318.428932) (xy 93.540515 -318.336736)
			(xy 93.617662 -318.249655) (xy 93.700633 -318.168104) (xy 93.789033 -318.092472) (xy 93.88244 -318.023118)
			(xy 93.980409 -317.960375) (xy 94.082473 -317.904539) (xy 94.188147 -317.855878) (xy 94.296926 -317.814624)
			(xy 94.408291 -317.780973) (xy 94.521714 -317.755085) (xy 94.636651 -317.737084) (xy 94.752557 -317.727055)
			(xy 94.868879 -317.725047) (xy 94.985062 -317.731069) (xy 95.100553 -317.745092) (xy 95.214801 -317.76705)
			(xy 95.327262 -317.796837) (xy 95.4374 -317.834312) (xy 95.54469 -317.879297) (xy 95.648621 -317.931576)
			(xy 95.748697 -317.990901) (xy 95.844443 -318.056989) (xy 95.9354 -318.129525) (xy 96.021136 -318.208164)
			(xy 96.101243 -318.29253) (xy 96.175339 -318.382222) (xy 96.243069 -318.476812) (xy 96.304113 -318.57585)
			(xy 96.358178 -318.678863) (xy 96.405008 -318.78536) (xy 96.444379 -318.894835) (xy 96.476103 -319.006765)
			(xy 96.500029 -319.120617) (xy 96.516043 -319.235849) (xy 96.52407 -319.351911) (xy 96.524572 -319.41008)
			(xy 96.52407 -319.468249) (xy 96.516043 -319.584311) (xy 96.500029 -319.699543) (xy 96.476103 -319.813395)
			(xy 96.444379 -319.925325) (xy 96.405008 -320.0348) (xy 96.358178 -320.141297) (xy 96.304113 -320.24431)
			(xy 96.243069 -320.343348) (xy 96.175339 -320.437938) (xy 96.101243 -320.52763) (xy 96.021136 -320.611996)
			(xy 95.9354 -320.690635) (xy 95.844443 -320.763171) (xy 95.748697 -320.829259) (xy 95.648621 -320.888584)
			(xy 95.54469 -320.940863) (xy 95.4374 -320.985848) (xy 95.327262 -321.023323) (xy 95.214801 -321.05311)
			(xy 95.100553 -321.075068) (xy 94.985062 -321.089091) (xy 94.868879 -321.095113) (xy 94.752557 -321.093105)
			(xy 94.636651 -321.083076) (xy 94.521714 -321.065075) (xy 94.408291 -321.039187) (xy 94.296926 -321.005536)
			(xy 94.188147 -320.964282) (xy 94.082473 -320.915621) (xy 93.980409 -320.859785) (xy 93.88244 -320.797042)
			(xy 93.789033 -320.727688) (xy 93.700633 -320.652056) (xy 93.617662 -320.570505) (xy 93.540515 -320.483424)
			(xy 93.46956 -320.391228) (xy 93.405134 -320.294356) (xy 93.347545 -320.193271) (xy 93.297068 -320.088453)
			(xy 93.253942 -319.980402) (xy 93.218373 -319.869634) (xy 93.190531 -319.756675) (xy 93.170549 -319.642065)
			(xy 93.158522 -319.52635) (xy 93.154506 -319.41008) (xy 91.165664 -319.41008) (xy 91.216772 -319.4548)
			(xy 91.268196 -319.510504) (xy 91.313407 -319.571359) (xy 91.351894 -319.636674) (xy 91.38322 -319.70571)
			(xy 91.40703 -319.777685) (xy 91.423055 -319.851783) (xy 91.431114 -319.927164) (xy 91.431618 -319.96507)
			(xy 91.431114 -320.002976) (xy 91.423055 -320.078357) (xy 91.40703 -320.152455) (xy 91.38322 -320.22443)
			(xy 91.351894 -320.293466) (xy 91.313407 -320.358781) (xy 91.268196 -320.419636) (xy 91.216772 -320.47534)
			(xy 91.159719 -320.525262) (xy 91.097683 -320.568837) (xy 91.031366 -320.605572) (xy 90.96152 -320.635049)
			(xy 90.888937 -320.656935) (xy 90.814439 -320.670982) (xy 90.738869 -320.677031) (xy 90.663085 -320.675012)
			(xy 90.587945 -320.66495) (xy 90.5143 -320.646958) (xy 90.442984 -320.62124) (xy 90.374807 -320.588088)
			(xy 90.310539 -320.547876) (xy 90.25091 -320.501061) (xy 90.196594 -320.448173) (xy 90.148208 -320.389811)
			(xy 90.1063 -320.326636) (xy 90.071344 -320.259365) (xy 90.043737 -320.18876) (xy 90.023791 -320.115619)
			(xy 90.011732 -320.040774) (xy 90.007697 -319.96507) (xy 88.891618 -319.96507) (xy 88.891114 -320.002976)
			(xy 88.883055 -320.078357) (xy 88.86703 -320.152455) (xy 88.84322 -320.22443) (xy 88.811894 -320.293466)
			(xy 88.773407 -320.358781) (xy 88.728196 -320.419636) (xy 88.676772 -320.47534) (xy 88.619719 -320.525262)
			(xy 88.557683 -320.568837) (xy 88.491366 -320.605572) (xy 88.42152 -320.635049) (xy 88.348937 -320.656935)
			(xy 88.274439 -320.670982) (xy 88.198869 -320.677031) (xy 88.123085 -320.675012) (xy 88.047945 -320.66495)
			(xy 87.9743 -320.646958) (xy 87.902984 -320.62124) (xy 87.834807 -320.588088) (xy 87.770539 -320.547876)
			(xy 87.71091 -320.501061) (xy 87.656594 -320.448173) (xy 87.608208 -320.389811) (xy 87.5663 -320.326636)
			(xy 87.531344 -320.259365) (xy 87.503737 -320.18876) (xy 87.483791 -320.115619) (xy 87.471732 -320.040774)
			(xy 87.467697 -319.96507) (xy 86.351618 -319.96507) (xy 86.351114 -320.002976) (xy 86.343055 -320.078357)
			(xy 86.32703 -320.152455) (xy 86.30322 -320.22443) (xy 86.271894 -320.293466) (xy 86.233407 -320.358781)
			(xy 86.188196 -320.419636) (xy 86.136772 -320.47534) (xy 86.079719 -320.525262) (xy 86.017683 -320.568837)
			(xy 85.951366 -320.605572) (xy 85.88152 -320.635049) (xy 85.808937 -320.656935) (xy 85.734439 -320.670982)
			(xy 85.658869 -320.677031) (xy 85.583085 -320.675012) (xy 85.507945 -320.66495) (xy 85.4343 -320.646958)
			(xy 85.362984 -320.62124) (xy 85.294807 -320.588088) (xy 85.230539 -320.547876) (xy 85.17091 -320.501061)
			(xy 85.116594 -320.448173) (xy 85.068208 -320.389811) (xy 85.0263 -320.326636) (xy 84.991344 -320.259365)
			(xy 84.963737 -320.18876) (xy 84.943791 -320.115619) (xy 84.931732 -320.040774) (xy 84.927697 -319.96507)
			(xy 62.265544 -319.96507) (xy 62.259599 -319.970272) (xy 62.197563 -320.013847) (xy 62.131246 -320.050582)
			(xy 62.0614 -320.080059) (xy 61.988817 -320.101945) (xy 61.914319 -320.115992) (xy 61.838749 -320.122041)
			(xy 61.762965 -320.120022) (xy 61.687825 -320.10996) (xy 61.61418 -320.091968) (xy 61.542864 -320.06625)
			(xy 61.474687 -320.033098) (xy 61.410419 -319.992886) (xy 61.35079 -319.946071) (xy 61.296474 -319.893183)
			(xy 61.248088 -319.834821) (xy 61.20618 -319.771646) (xy 61.171224 -319.704375) (xy 61.143617 -319.63377)
			(xy 61.123671 -319.560629) (xy 61.111612 -319.485784) (xy 61.107577 -319.41008) (xy 59.991498 -319.41008)
			(xy 59.990994 -319.447986) (xy 59.982935 -319.523367) (xy 59.96691 -319.597465) (xy 59.9431 -319.66944)
			(xy 59.911774 -319.738476) (xy 59.873287 -319.803791) (xy 59.828076 -319.864646) (xy 59.776652 -319.92035)
			(xy 59.719599 -319.970272) (xy 59.657563 -320.013847) (xy 59.591246 -320.050582) (xy 59.5214 -320.080059)
			(xy 59.448817 -320.101945) (xy 59.374319 -320.115992) (xy 59.298749 -320.122041) (xy 59.222965 -320.120022)
			(xy 59.147825 -320.10996) (xy 59.07418 -320.091968) (xy 59.002864 -320.06625) (xy 58.934687 -320.033098)
			(xy 58.870419 -319.992886) (xy 58.81079 -319.946071) (xy 58.756474 -319.893183) (xy 58.708088 -319.834821)
			(xy 58.66618 -319.771646) (xy 58.631224 -319.704375) (xy 58.603617 -319.63377) (xy 58.583671 -319.560629)
			(xy 58.571612 -319.485784) (xy 58.567577 -319.41008) (xy 57.451498 -319.41008) (xy 57.450994 -319.447986)
			(xy 57.442935 -319.523367) (xy 57.42691 -319.597465) (xy 57.4031 -319.66944) (xy 57.371774 -319.738476)
			(xy 57.333287 -319.803791) (xy 57.288076 -319.864646) (xy 57.236652 -319.92035) (xy 57.179599 -319.970272)
			(xy 57.117563 -320.013847) (xy 57.051246 -320.050582) (xy 56.9814 -320.080059) (xy 56.908817 -320.101945)
			(xy 56.834319 -320.115992) (xy 56.758749 -320.122041) (xy 56.682965 -320.120022) (xy 56.607825 -320.10996)
			(xy 56.53418 -320.091968) (xy 56.462864 -320.06625) (xy 56.394687 -320.033098) (xy 56.330419 -319.992886)
			(xy 56.27079 -319.946071) (xy 56.216474 -319.893183) (xy 56.168088 -319.834821) (xy 56.12618 -319.771646)
			(xy 56.091224 -319.704375) (xy 56.063617 -319.63377) (xy 56.043671 -319.560629) (xy 56.031612 -319.485784)
			(xy 56.027577 -319.41008) (xy 54.911498 -319.41008) (xy 54.910994 -319.447986) (xy 54.902935 -319.523367)
			(xy 54.88691 -319.597465) (xy 54.8631 -319.66944) (xy 54.831774 -319.738476) (xy 54.793287 -319.803791)
			(xy 54.748076 -319.864646) (xy 54.696652 -319.92035) (xy 54.639599 -319.970272) (xy 54.577563 -320.013847)
			(xy 54.511246 -320.050582) (xy 54.4414 -320.080059) (xy 54.368817 -320.101945) (xy 54.294319 -320.115992)
			(xy 54.218749 -320.122041) (xy 54.142965 -320.120022) (xy 54.067825 -320.10996) (xy 53.99418 -320.091968)
			(xy 53.922864 -320.06625) (xy 53.854687 -320.033098) (xy 53.790419 -319.992886) (xy 53.73079 -319.946071)
			(xy 53.676474 -319.893183) (xy 53.628088 -319.834821) (xy 53.58618 -319.771646) (xy 53.551224 -319.704375)
			(xy 53.523617 -319.63377) (xy 53.503671 -319.560629) (xy 53.491612 -319.485784) (xy 53.487577 -319.41008)
			(xy 52.371498 -319.41008) (xy 52.370994 -319.447986) (xy 52.362935 -319.523367) (xy 52.34691 -319.597465)
			(xy 52.3231 -319.66944) (xy 52.291774 -319.738476) (xy 52.253287 -319.803791) (xy 52.208076 -319.864646)
			(xy 52.156652 -319.92035) (xy 52.099599 -319.970272) (xy 52.037563 -320.013847) (xy 51.971246 -320.050582)
			(xy 51.9014 -320.080059) (xy 51.828817 -320.101945) (xy 51.754319 -320.115992) (xy 51.678749 -320.122041)
			(xy 51.602965 -320.120022) (xy 51.527825 -320.10996) (xy 51.45418 -320.091968) (xy 51.382864 -320.06625)
			(xy 51.314687 -320.033098) (xy 51.250419 -319.992886) (xy 51.19079 -319.946071) (xy 51.136474 -319.893183)
			(xy 51.088088 -319.834821) (xy 51.04618 -319.771646) (xy 51.011224 -319.704375) (xy 50.983617 -319.63377)
			(xy 50.963671 -319.560629) (xy 50.951612 -319.485784) (xy 50.947577 -319.41008) (xy 49.831498 -319.41008)
			(xy 49.830994 -319.447986) (xy 49.822935 -319.523367) (xy 49.80691 -319.597465) (xy 49.7831 -319.66944)
			(xy 49.751774 -319.738476) (xy 49.713287 -319.803791) (xy 49.668076 -319.864646) (xy 49.616652 -319.92035)
			(xy 49.559599 -319.970272) (xy 49.497563 -320.013847) (xy 49.431246 -320.050582) (xy 49.3614 -320.080059)
			(xy 49.288817 -320.101945) (xy 49.214319 -320.115992) (xy 49.138749 -320.122041) (xy 49.062965 -320.120022)
			(xy 48.987825 -320.10996) (xy 48.91418 -320.091968) (xy 48.842864 -320.06625) (xy 48.774687 -320.033098)
			(xy 48.710419 -319.992886) (xy 48.65079 -319.946071) (xy 48.596474 -319.893183) (xy 48.548088 -319.834821)
			(xy 48.50618 -319.771646) (xy 48.471224 -319.704375) (xy 48.443617 -319.63377) (xy 48.423671 -319.560629)
			(xy 48.411612 -319.485784) (xy 48.407577 -319.41008) (xy 47.291498 -319.41008) (xy 47.290994 -319.447986)
			(xy 47.282935 -319.523367) (xy 47.26691 -319.597465) (xy 47.2431 -319.66944) (xy 47.211774 -319.738476)
			(xy 47.173287 -319.803791) (xy 47.128076 -319.864646) (xy 47.076652 -319.92035) (xy 47.019599 -319.970272)
			(xy 46.957563 -320.013847) (xy 46.891246 -320.050582) (xy 46.8214 -320.080059) (xy 46.748817 -320.101945)
			(xy 46.674319 -320.115992) (xy 46.598749 -320.122041) (xy 46.522965 -320.120022) (xy 46.447825 -320.10996)
			(xy 46.37418 -320.091968) (xy 46.302864 -320.06625) (xy 46.234687 -320.033098) (xy 46.170419 -319.992886)
			(xy 46.11079 -319.946071) (xy 46.056474 -319.893183) (xy 46.008088 -319.834821) (xy 45.96618 -319.771646)
			(xy 45.931224 -319.704375) (xy 45.903617 -319.63377) (xy 45.883671 -319.560629) (xy 45.871612 -319.485784)
			(xy 45.867577 -319.41008) (xy 44.751244 -319.41008) (xy 44.751244 -320.121788) (xy 43.328336 -320.121788)
			(xy 43.328336 -318.698372) (xy 43.055094 -318.698372) (xy 43.053462 -318.702742) (xy 43.004999 -318.809253)
			(xy 42.949245 -318.912135) (xy 42.886471 -319.010891) (xy 42.816981 -319.105042) (xy 42.741111 -319.194132)
			(xy 42.659229 -319.277729) (xy 42.571732 -319.35543) (xy 42.479042 -319.426857) (xy 42.381609 -319.491665)
			(xy 42.279905 -319.54954) (xy 42.174422 -319.600202) (xy 42.065671 -319.643404) (xy 41.954179 -319.678939)
			(xy 41.840485 -319.706634) (xy 41.725141 -319.726354) (xy 41.608704 -319.738005) (xy 41.491739 -319.74153)
			(xy 41.374812 -319.736912) (xy 41.258489 -319.724173) (xy 41.143334 -319.703375) (xy 41.029905 -319.674618)
			(xy 40.91875 -319.638042) (xy 40.810407 -319.593825) (xy 40.705403 -319.542179) (xy 40.604244 -319.483356)
			(xy 40.507421 -319.41764) (xy 40.415403 -319.345349) (xy 40.328636 -319.266834) (xy 40.247539 -319.182474)
			(xy 40.172506 -319.092679) (xy 40.103899 -318.997883) (xy 40.042051 -318.898544) (xy 39.987262 -318.795145)
			(xy 39.939796 -318.688186) (xy 39.899884 -318.578185) (xy 39.86772 -318.465674) (xy 39.843457 -318.351199)
			(xy 39.827215 -318.235313) (xy 39.819072 -318.118579) (xy 39.818564 -318.06007) (xy 36.479871 -318.06007)
			(xy 36.479486 -318.09336) (xy 36.471468 -318.179889) (xy 36.4555 -318.265309) (xy 36.431719 -318.348891)
			(xy 36.400327 -318.429923) (xy 36.361593 -318.507712) (xy 36.315846 -318.581596) (xy 36.263477 -318.650943)
			(xy 36.204933 -318.715163) (xy 36.140713 -318.773707) (xy 36.071366 -318.826076) (xy 35.997482 -318.871823)
			(xy 35.919693 -318.910557) (xy 35.838661 -318.941949) (xy 35.755079 -318.96573) (xy 35.669659 -318.981698)
			(xy 35.58313 -318.989716) (xy 35.49623 -318.989716) (xy 35.409701 -318.981698) (xy 35.324281 -318.96573)
			(xy 35.240699 -318.941949) (xy 35.159667 -318.910557) (xy 35.081878 -318.871823) (xy 35.007994 -318.826076)
			(xy 34.938647 -318.773707) (xy 34.874427 -318.715163) (xy 34.815883 -318.650943) (xy 34.763514 -318.581596)
			(xy 34.717767 -318.507712) (xy 34.679033 -318.429923) (xy 34.647641 -318.348891) (xy 34.62386 -318.265309)
			(xy 34.607892 -318.179889) (xy 34.599874 -318.09336) (xy 31.399486 -318.09336) (xy 31.391468 -318.179889)
			(xy 31.3755 -318.265309) (xy 31.351719 -318.348891) (xy 31.320327 -318.429923) (xy 31.281593 -318.507712)
			(xy 31.235846 -318.581596) (xy 31.183477 -318.650943) (xy 31.124933 -318.715163) (xy 31.060713 -318.773707)
			(xy 30.991366 -318.826076) (xy 30.917482 -318.871823) (xy 30.839693 -318.910557) (xy 30.758661 -318.941949)
			(xy 30.675079 -318.96573) (xy 30.589659 -318.981698) (xy 30.50313 -318.989716) (xy 30.41623 -318.989716)
			(xy 30.329701 -318.981698) (xy 30.244281 -318.96573) (xy 30.160699 -318.941949) (xy 30.079667 -318.910557)
			(xy 30.001878 -318.871823) (xy 29.927994 -318.826076) (xy 29.858647 -318.773707) (xy 29.794427 -318.715163)
			(xy 29.735883 -318.650943) (xy 29.683514 -318.581596) (xy 29.637767 -318.507712) (xy 29.599033 -318.429923)
			(xy 29.567641 -318.348891) (xy 29.54386 -318.265309) (xy 29.527892 -318.179889) (xy 29.519874 -318.09336)
			(xy 28.067 -318.09336) (xy 28.067 -324.979538) (xy 82.79079 -324.979538) (xy 82.794861 -324.923916)
			(xy 82.806987 -324.869479) (xy 82.82691 -324.817388) (xy 82.854206 -324.768753) (xy 82.888292 -324.72461)
			(xy 82.928441 -324.685901) (xy 82.973799 -324.65345) (xy 83.023399 -324.627949) (xy 83.076183 -324.609942)
			(xy 83.131026 -324.599812) (xy 83.18676 -324.597775) (xy 83.242197 -324.603875) (xy 83.296154 -324.617981)
			(xy 83.347483 -324.639793) (xy 83.395089 -324.668847) (xy 83.437957 -324.704522) (xy 83.475174 -324.746059)
			(xy 83.505947 -324.792572) (xy 83.529619 -324.843069) (xy 83.545687 -324.896476) (xy 83.553807 -324.951652)
			(xy 83.554316 -324.979538) (xy 83.553807 -325.007424) (xy 83.545687 -325.0626) (xy 83.529619 -325.116007)
			(xy 83.505947 -325.166504) (xy 83.475174 -325.213017) (xy 83.437957 -325.254554) (xy 83.395089 -325.290229)
			(xy 83.347483 -325.319283) (xy 83.296154 -325.341095) (xy 83.242197 -325.355201) (xy 83.18676 -325.361301)
			(xy 83.131026 -325.359264) (xy 83.076183 -325.349134) (xy 83.023399 -325.331127) (xy 82.973799 -325.305626)
			(xy 82.928441 -325.273175) (xy 82.888292 -325.234466) (xy 82.854206 -325.190323) (xy 82.82691 -325.141688)
			(xy 82.806987 -325.089597) (xy 82.794861 -325.03516) (xy 82.79079 -324.979538) (xy 28.067 -324.979538)
			(xy 28.067 -325.649844) (xy 81.400394 -325.649844) (xy 81.404465 -325.594222) (xy 81.416591 -325.539785)
			(xy 81.436514 -325.487694) (xy 81.46381 -325.439059) (xy 81.497896 -325.394916) (xy 81.538045 -325.356207)
			(xy 81.583403 -325.323756) (xy 81.633003 -325.298255) (xy 81.685787 -325.280248) (xy 81.74063 -325.270118)
			(xy 81.796364 -325.268081) (xy 81.851801 -325.274181) (xy 81.905758 -325.288287) (xy 81.957087 -325.310099)
			(xy 82.004693 -325.339153) (xy 82.047561 -325.374828) (xy 82.084778 -325.416365) (xy 82.115551 -325.462878)
			(xy 82.139223 -325.513375) (xy 82.155291 -325.566782) (xy 82.163411 -325.621958) (xy 82.16392 -325.649844)
			(xy 82.163411 -325.67773) (xy 82.155291 -325.732906) (xy 82.139223 -325.786313) (xy 82.115551 -325.83681)
			(xy 82.084778 -325.883323) (xy 82.047561 -325.92486) (xy 82.004693 -325.960535) (xy 81.957087 -325.989589)
			(xy 81.905758 -326.011401) (xy 81.851801 -326.025507) (xy 81.796364 -326.031607) (xy 81.74063 -326.02957)
			(xy 81.685787 -326.01944) (xy 81.633003 -326.001433) (xy 81.583403 -325.975932) (xy 81.538045 -325.943481)
			(xy 81.497896 -325.904772) (xy 81.46381 -325.860629) (xy 81.436514 -325.811994) (xy 81.416591 -325.759903)
			(xy 81.404465 -325.705466) (xy 81.400394 -325.649844) (xy 28.067 -325.649844) (xy 28.067 -326.140064)
			(xy 83.341208 -326.140064) (xy 83.345279 -326.084442) (xy 83.357405 -326.030005) (xy 83.377328 -325.977914)
			(xy 83.404624 -325.929279) (xy 83.43871 -325.885136) (xy 83.478859 -325.846427) (xy 83.524217 -325.813976)
			(xy 83.573817 -325.788475) (xy 83.626601 -325.770468) (xy 83.681444 -325.760338) (xy 83.737178 -325.758301)
			(xy 83.792615 -325.764401) (xy 83.846572 -325.778507) (xy 83.897901 -325.800319) (xy 83.945507 -325.829373)
			(xy 83.988375 -325.865048) (xy 84.025592 -325.906585) (xy 84.056365 -325.953098) (xy 84.080037 -326.003595)
			(xy 84.096105 -326.057002) (xy 84.104225 -326.112178) (xy 84.104734 -326.140064) (xy 84.104225 -326.16795)
			(xy 84.096105 -326.223126) (xy 84.080037 -326.276533) (xy 84.056365 -326.32703) (xy 84.025592 -326.373543)
			(xy 83.988375 -326.41508) (xy 83.945507 -326.450755) (xy 83.897901 -326.479809) (xy 83.846572 -326.501621)
			(xy 83.792615 -326.515727) (xy 83.737178 -326.521827) (xy 83.681444 -326.51979) (xy 83.626601 -326.50966)
			(xy 83.573817 -326.491653) (xy 83.524217 -326.466152) (xy 83.478859 -326.433701) (xy 83.43871 -326.394992)
			(xy 83.404624 -326.350849) (xy 83.377328 -326.302214) (xy 83.357405 -326.250123) (xy 83.345279 -326.195686)
			(xy 83.341208 -326.140064) (xy 28.067 -326.140064) (xy 28.067 -327.462134) (xy 82.91271 -327.462134)
			(xy 82.916781 -327.406512) (xy 82.928907 -327.352075) (xy 82.94883 -327.299984) (xy 82.976126 -327.251349)
			(xy 83.010212 -327.207206) (xy 83.050361 -327.168497) (xy 83.095719 -327.136046) (xy 83.145319 -327.110545)
			(xy 83.198103 -327.092538) (xy 83.252946 -327.082408) (xy 83.30868 -327.080371) (xy 83.364117 -327.086471)
			(xy 83.418074 -327.100577) (xy 83.469403 -327.122389) (xy 83.517009 -327.151443) (xy 83.559877 -327.187118)
			(xy 83.597094 -327.228655) (xy 83.627867 -327.275168) (xy 83.651539 -327.325665) (xy 83.667607 -327.379072)
			(xy 83.675727 -327.434248) (xy 83.676236 -327.462134) (xy 83.675727 -327.49002) (xy 83.667607 -327.545196)
			(xy 83.651539 -327.598603) (xy 83.627867 -327.6491) (xy 83.597094 -327.695613) (xy 83.559877 -327.73715)
			(xy 83.517009 -327.772825) (xy 83.469403 -327.801879) (xy 83.418074 -327.823691) (xy 83.364117 -327.837797)
			(xy 83.30868 -327.843897) (xy 83.252946 -327.84186) (xy 83.198103 -327.83173) (xy 83.145319 -327.813723)
			(xy 83.095719 -327.788222) (xy 83.050361 -327.755771) (xy 83.010212 -327.717062) (xy 82.976126 -327.672919)
			(xy 82.94883 -327.624284) (xy 82.928907 -327.572193) (xy 82.916781 -327.517756) (xy 82.91271 -327.462134)
			(xy 28.067 -327.462134) (xy 28.067 -329.146408) (xy 51.402996 -329.146408) (xy 53.055012 -329.146408)
			(xy 53.055012 -330.798424) (xy 51.402996 -330.798424) (xy 51.402996 -329.146408) (xy 28.067 -329.146408)
			(xy 28.067 -330.012971) (xy 47.903374 -330.012971) (xy 47.903374 -329.931861) (xy 47.911324 -329.851142)
			(xy 47.927147 -329.771591) (xy 47.950692 -329.693975) (xy 47.981731 -329.619039) (xy 48.019966 -329.547507)
			(xy 48.065028 -329.480067) (xy 48.116483 -329.417368) (xy 48.173836 -329.360015) (xy 48.236535 -329.30856)
			(xy 48.303975 -329.263498) (xy 48.375507 -329.225263) (xy 48.450443 -329.194224) (xy 48.528059 -329.170679)
			(xy 48.60761 -329.154856) (xy 48.688329 -329.146906) (xy 48.769439 -329.146906) (xy 48.850158 -329.154856)
			(xy 48.929709 -329.170679) (xy 49.007325 -329.194224) (xy 49.082261 -329.225263) (xy 49.153793 -329.263498)
			(xy 49.221233 -329.30856) (xy 49.283932 -329.360015) (xy 49.341285 -329.417368) (xy 49.39274 -329.480067)
			(xy 49.437802 -329.547507) (xy 49.476037 -329.619039) (xy 49.507076 -329.693975) (xy 49.530621 -329.771591)
			(xy 49.546444 -329.851142) (xy 49.554394 -329.931861) (xy 49.554892 -329.972416) (xy 49.554394 -330.012971)
			(xy 49.546444 -330.09369) (xy 49.530621 -330.173241) (xy 49.507076 -330.250857) (xy 49.476037 -330.325793)
			(xy 49.437802 -330.397325) (xy 49.39274 -330.464765) (xy 49.341285 -330.527464) (xy 49.283932 -330.584817)
			(xy 49.221233 -330.636272) (xy 49.153793 -330.681334) (xy 49.082261 -330.719569) (xy 49.007325 -330.750608)
			(xy 48.929709 -330.774153) (xy 48.850158 -330.789976) (xy 48.769439 -330.797926) (xy 48.688329 -330.797926)
			(xy 48.60761 -330.789976) (xy 48.528059 -330.774153) (xy 48.450443 -330.750608) (xy 48.375507 -330.719569)
			(xy 48.303975 -330.681334) (xy 48.236535 -330.636272) (xy 48.173836 -330.584817) (xy 48.116483 -330.527464)
			(xy 48.065028 -330.464765) (xy 48.019966 -330.397325) (xy 47.981731 -330.325793) (xy 47.950692 -330.250857)
			(xy 47.927147 -330.173241) (xy 47.911324 -330.09369) (xy 47.903374 -330.012971) (xy 28.067 -330.012971)
			(xy 28.067 -332.475586) (xy 71.578724 -332.475586) (xy 71.578724 -331.577188) (xy 71.579405 -331.541122)
			(xy 71.589734 -331.46973) (xy 71.599298 -331.434948) (xy 71.604124 -331.417422) (xy 71.604124 -331.04328)
			(xy 72.57034 -331.04328) (xy 72.57034 -331.417422) (xy 72.575166 -331.434948) (xy 72.584712 -331.469734)
			(xy 72.595036 -331.541123) (xy 72.59574 -331.577188) (xy 72.59574 -331.631036) (xy 72.950832 -331.631036)
			(xy 72.950832 -330.732638) (xy 72.951344 -330.699903) (xy 72.959781 -330.634978) (xy 72.976482 -330.571672)
			(xy 73.00117 -330.511034) (xy 73.033436 -330.454067) (xy 73.052686 -330.427584) (xy 73.077832 -330.393802)
			(xy 73.077832 -330.376784) (xy 73.093326 -330.376784) (xy 73.12914 -330.346304) (xy 73.154317 -330.325451)
			(xy 73.209049 -330.2897) (xy 73.267914 -330.261261) (xy 73.329939 -330.240606) (xy 73.394101 -330.228075)
			(xy 73.45934 -330.223875) (xy 73.524579 -330.228075) (xy 73.588741 -330.240606) (xy 73.650766 -330.261261)
			(xy 73.709631 -330.2897) (xy 73.764363 -330.325451) (xy 73.78954 -330.346304) (xy 73.825354 -330.376784)
			(xy 73.840848 -330.376784) (xy 73.840848 -330.393802) (xy 73.865994 -330.427584) (xy 73.876154 -330.441808)
			(xy 73.889266 -330.459756) (xy 73.920681 -330.491194) (xy 73.957081 -330.516697) (xy 73.997357 -330.535489)
			(xy 74.040286 -330.546997) (xy 74.084561 -330.550873) (xy 74.128836 -330.546997) (xy 74.171765 -330.535489)
			(xy 74.212041 -330.516697) (xy 74.248441 -330.491194) (xy 74.279856 -330.459756) (xy 74.292968 -330.441808)
			(xy 74.303128 -330.427584) (xy 74.328528 -330.393802) (xy 74.328528 -330.376784) (xy 74.343768 -330.376784)
			(xy 74.379582 -330.346304) (xy 74.404759 -330.325451) (xy 74.459491 -330.2897) (xy 74.518356 -330.261261)
			(xy 74.580381 -330.240606) (xy 74.644543 -330.228075) (xy 74.709782 -330.223875) (xy 74.775021 -330.228075)
			(xy 74.839183 -330.240606) (xy 74.901208 -330.261261) (xy 74.960073 -330.2897) (xy 75.014805 -330.325451)
			(xy 75.039982 -330.346304) (xy 75.075796 -330.376784) (xy 75.091036 -330.376784) (xy 75.091036 -330.393802)
			(xy 75.116436 -330.427584) (xy 75.135668 -330.454071) (xy 75.167896 -330.511043) (xy 75.192536 -330.571685)
			(xy 75.209179 -330.63499) (xy 75.217548 -330.699909) (xy 75.218036 -330.732638) (xy 75.218036 -331.16012)
			(xy 86.39887 -331.16012) (xy 86.402874 -330.960022) (xy 86.414881 -330.760244) (xy 86.434872 -330.561107)
			(xy 86.462814 -330.362929) (xy 86.498662 -330.166027) (xy 86.54236 -329.970718) (xy 86.593837 -329.777313)
			(xy 86.653011 -329.586123) (xy 86.719787 -329.397453) (xy 86.794059 -329.211606) (xy 86.875706 -329.028879)
			(xy 86.964599 -328.849566) (xy 87.060595 -328.673952) (xy 87.16354 -328.50232) (xy 87.27327 -328.334944)
			(xy 87.389608 -328.172093) (xy 87.512369 -328.014026) (xy 87.641356 -327.860998) (xy 87.776363 -327.713253)
			(xy 87.917172 -327.571027) (xy 88.063559 -327.43455) (xy 88.215289 -327.304038) (xy 88.37212 -327.179702)
			(xy 88.533799 -327.06174) (xy 88.700069 -326.950341) (xy 88.870662 -326.845684) (xy 89.045306 -326.747936)
			(xy 89.223722 -326.657253) (xy 89.405622 -326.573782) (xy 89.590717 -326.497655) (xy 89.778709 -326.428995)
			(xy 89.969298 -326.367911) (xy 90.162178 -326.314501) (xy 90.35704 -326.268852) (xy 90.553573 -326.231035)
			(xy 90.751462 -326.201111) (xy 90.950389 -326.179129) (xy 91.150037 -326.165124) (xy 91.350085 -326.159118)
			(xy 91.550213 -326.16112) (xy 91.750101 -326.171128) (xy 91.949428 -326.189125) (xy 92.147876 -326.215083)
			(xy 92.345126 -326.24896) (xy 92.540863 -326.290702) (xy 92.734773 -326.340241) (xy 92.926546 -326.397499)
			(xy 93.115875 -326.462384) (xy 93.302455 -326.534792) (xy 93.48599 -326.614608) (xy 93.666184 -326.701702)
			(xy 93.842749 -326.795936) (xy 94.015402 -326.897159) (xy 94.183867 -327.005209) (xy 94.347875 -327.119912)
			(xy 94.507162 -327.241086) (xy 94.661473 -327.368535) (xy 94.810561 -327.502056) (xy 94.954188 -327.641436)
			(xy 95.092124 -327.78645) (xy 95.224147 -327.936867) (xy 95.350046 -328.092445) (xy 95.46962 -328.252937)
			(xy 95.582676 -328.418083) (xy 95.689035 -328.587621) (xy 95.788526 -328.761279) (xy 95.880989 -328.938778)
			(xy 95.966276 -329.119834) (xy 96.044251 -329.304158) (xy 96.114788 -329.491454) (xy 96.177776 -329.681422)
			(xy 96.233113 -329.873758) (xy 96.28071 -330.068154) (xy 96.320491 -330.264299) (xy 96.352393 -330.461878)
			(xy 96.376364 -330.660575) (xy 96.392366 -330.860073) (xy 96.400373 -331.060051) (xy 96.400874 -331.16012)
			(xy 96.400373 -331.260189) (xy 96.392366 -331.460167) (xy 96.376364 -331.659665) (xy 96.352393 -331.858362)
			(xy 96.320491 -332.055941) (xy 96.28071 -332.252086) (xy 96.233113 -332.446482) (xy 96.177776 -332.638818)
			(xy 96.114788 -332.828786) (xy 96.044251 -333.016082) (xy 95.966276 -333.200406) (xy 95.880989 -333.381462)
			(xy 95.788526 -333.558961) (xy 95.689035 -333.732619) (xy 95.582676 -333.902157) (xy 95.46962 -334.067303)
			(xy 95.350046 -334.227795) (xy 95.224147 -334.383373) (xy 95.092124 -334.53379) (xy 94.954188 -334.678804)
			(xy 94.810561 -334.818184) (xy 94.661473 -334.951705) (xy 94.507162 -335.079154) (xy 94.347875 -335.200328)
			(xy 94.183867 -335.315031) (xy 94.015402 -335.423081) (xy 93.842749 -335.524304) (xy 93.666184 -335.618538)
			(xy 93.48599 -335.705632) (xy 93.302455 -335.785448) (xy 93.115875 -335.857856) (xy 92.926546 -335.922741)
			(xy 92.734773 -335.979999) (xy 92.540863 -336.029538) (xy 92.345126 -336.07128) (xy 92.147876 -336.105157)
			(xy 91.949428 -336.131115) (xy 91.750101 -336.149112) (xy 91.550213 -336.15912) (xy 91.350085 -336.161122)
			(xy 91.150037 -336.155116) (xy 90.950389 -336.141111) (xy 90.751462 -336.119129) (xy 90.553573 -336.089205)
			(xy 90.35704 -336.051388) (xy 90.162178 -336.005739) (xy 89.969298 -335.952329) (xy 89.778709 -335.891245)
			(xy 89.590717 -335.822585) (xy 89.405622 -335.746458) (xy 89.223722 -335.662987) (xy 89.045306 -335.572304)
			(xy 88.870662 -335.474556) (xy 88.700069 -335.369899) (xy 88.533799 -335.2585) (xy 88.37212 -335.140538)
			(xy 88.215289 -335.016202) (xy 88.063559 -334.88569) (xy 87.917172 -334.749213) (xy 87.776363 -334.606987)
			(xy 87.641356 -334.459242) (xy 87.512369 -334.306214) (xy 87.389608 -334.148147) (xy 87.27327 -333.985296)
			(xy 87.16354 -333.81792) (xy 87.060595 -333.646288) (xy 86.964599 -333.470674) (xy 86.875706 -333.291361)
			(xy 86.794059 -333.108634) (xy 86.719787 -332.922787) (xy 86.653011 -332.734117) (xy 86.593837 -332.542927)
			(xy 86.54236 -332.349522) (xy 86.498662 -332.154213) (xy 86.462814 -331.957311) (xy 86.434872 -331.759133)
			(xy 86.414881 -331.559996) (xy 86.402874 -331.360218) (xy 86.39887 -331.16012) (xy 75.218036 -331.16012)
			(xy 75.218036 -331.631036) (xy 75.217585 -331.663225) (xy 75.209451 -331.727088) (xy 75.193318 -331.789413)
			(xy 75.169443 -331.849201) (xy 75.138211 -331.905496) (xy 75.100119 -331.957397) (xy 75.055779 -332.004072)
			(xy 75.005899 -332.044774) (xy 74.951279 -332.078852) (xy 74.892794 -332.10576) (xy 74.831378 -332.125067)
			(xy 74.768016 -332.136465) (xy 74.703722 -332.13977) (xy 74.639526 -332.13493) (xy 74.576454 -332.122022)
			(xy 74.515518 -332.101253) (xy 74.457691 -332.072956) (xy 74.403901 -332.037583) (xy 74.355008 -331.995701)
			(xy 74.311795 -331.94798) (xy 74.292968 -331.921866) (xy 74.279875 -331.90389) (xy 74.248484 -331.872394)
			(xy 74.212091 -331.846841) (xy 74.171806 -331.82801) (xy 74.128859 -331.816477) (xy 74.084561 -331.812593)
			(xy 74.040263 -331.816477) (xy 73.997316 -331.82801) (xy 73.957031 -331.846841) (xy 73.920638 -331.872394)
			(xy 73.889247 -331.90389) (xy 73.876154 -331.921866) (xy 73.857265 -331.94794) (xy 73.814049 -331.995664)
			(xy 73.765152 -332.03755) (xy 73.711357 -332.072926) (xy 73.653527 -332.101227) (xy 73.592586 -332.122)
			(xy 73.52951 -332.134911) (xy 73.465308 -332.139755) (xy 73.401009 -332.136454) (xy 73.337641 -332.12506)
			(xy 73.276219 -332.105756) (xy 73.217726 -332.078852) (xy 73.163098 -332.044777) (xy 73.11321 -332.004078)
			(xy 73.06886 -331.957405) (xy 73.030758 -331.905505) (xy 72.999514 -331.84921) (xy 72.975628 -331.789421)
			(xy 72.959483 -331.727094) (xy 72.951336 -331.663228) (xy 72.950832 -331.631036) (xy 72.59574 -331.631036)
			(xy 72.59574 -332.475586) (xy 72.595238 -332.507547) (xy 72.587227 -332.570965) (xy 72.57133 -332.632879)
			(xy 72.547798 -332.692312) (xy 72.517004 -332.748327) (xy 72.479431 -332.800042) (xy 72.435674 -332.846639)
			(xy 72.386421 -332.887384) (xy 72.33245 -332.921635) (xy 72.274611 -332.948852) (xy 72.213818 -332.968605)
			(xy 72.151028 -332.980583) (xy 72.087232 -332.984597) (xy 72.023436 -332.980583) (xy 71.960646 -332.968605)
			(xy 71.899853 -332.948852) (xy 71.842014 -332.921635) (xy 71.788043 -332.887384) (xy 71.73879 -332.846639)
			(xy 71.695033 -332.800042) (xy 71.65746 -332.748327) (xy 71.626666 -332.692312) (xy 71.603134 -332.632879)
			(xy 71.587237 -332.570965) (xy 71.579226 -332.507547) (xy 71.578724 -332.475586) (xy 28.067 -332.475586)
			(xy 28.067 -340.182708) (xy 28.08351 -340.199218) (xy 28.08351 -341.250016) (xy 69.997584 -341.250016)
			(xy 70.001572 -340.997396) (xy 70.013533 -340.745028) (xy 70.033455 -340.493164) (xy 70.061319 -340.242054)
			(xy 70.097095 -339.991948) (xy 70.140749 -339.743097) (xy 70.192238 -339.495748) (xy 70.251509 -339.250147)
			(xy 70.318504 -339.00654) (xy 70.393155 -338.76517) (xy 70.47539 -338.526276) (xy 70.565124 -338.290098)
			(xy 70.66227 -338.05687) (xy 70.76673 -337.826824) (xy 70.878401 -337.600192) (xy 70.99717 -337.377197)
			(xy 71.122919 -337.158063) (xy 71.255524 -336.943008) (xy 71.394851 -336.732246) (xy 71.540763 -336.525988)
			(xy 71.693113 -336.324439) (xy 71.851749 -336.127799) (xy 72.016514 -335.936266) (xy 72.187244 -335.750029)
			(xy 72.363768 -335.569275) (xy 72.54591 -335.394184) (xy 72.733488 -335.22493) (xy 72.926316 -335.061681)
			(xy 73.124201 -334.904602) (xy 73.326947 -334.753847) (xy 73.534351 -334.609569) (xy 73.746206 -334.471909)
			(xy 73.962301 -334.341006) (xy 74.182421 -334.21699) (xy 74.406346 -334.099985) (xy 74.633853 -333.990107)
			(xy 74.864715 -333.887466) (xy 75.098703 -333.792164) (xy 75.335582 -333.704297) (xy 75.575118 -333.62395)
			(xy 75.81707 -333.551206) (xy 76.061198 -333.486136) (xy 76.307259 -333.428806) (xy 76.555007 -333.379272)
			(xy 76.804195 -333.337583) (xy 77.054575 -333.303782) (xy 77.305897 -333.277901) (xy 77.557911 -333.259968)
			(xy 77.810365 -333.249999) (xy 78.063009 -333.248005) (xy 78.315589 -333.253987) (xy 78.567855 -333.26794)
			(xy 78.819554 -333.28985) (xy 79.070437 -333.319694) (xy 79.320252 -333.357444) (xy 79.568751 -333.403061)
			(xy 79.815686 -333.4565) (xy 80.060811 -333.517708) (xy 80.303881 -333.586623) (xy 80.544655 -333.663178)
			(xy 80.782892 -333.747295) (xy 81.018355 -333.838892) (xy 81.250809 -333.937876) (xy 81.480023 -334.044148)
			(xy 81.705767 -334.157604) (xy 81.927817 -334.278129) (xy 82.145951 -334.405605) (xy 82.359953 -334.539903)
			(xy 82.569609 -334.680889) (xy 82.774709 -334.828424) (xy 82.975049 -334.98236) (xy 83.17043 -335.142544)
			(xy 83.360657 -335.308816) (xy 83.54554 -335.481011) (xy 83.724896 -335.658955) (xy 83.898544 -335.842474)
			(xy 84.066312 -336.031382) (xy 84.228033 -336.225493) (xy 84.383546 -336.424612) (xy 84.532695 -336.628541)
			(xy 84.675332 -336.837077) (xy 84.811315 -337.050012) (xy 84.940508 -337.267134) (xy 85.062783 -337.488226)
			(xy 85.178017 -337.713067) (xy 85.190846 -337.740174) (xy 88.87141 -337.740174) (xy 88.875302 -337.685822)
			(xy 88.886889 -337.632578) (xy 88.905936 -337.581524) (xy 88.932055 -337.533702) (xy 88.964715 -337.490083)
			(xy 89.00325 -337.451557) (xy 89.046876 -337.418907) (xy 89.094705 -337.392799) (xy 89.145763 -337.373764)
			(xy 89.19901 -337.362189) (xy 89.253362 -337.35831) (xy 89.307714 -337.362207) (xy 89.360957 -337.373799)
			(xy 89.412008 -337.392851) (xy 89.459829 -337.418975) (xy 89.481914 -337.434936) (xy 89.500926 -337.448532)
			(xy 89.542809 -337.469264) (xy 89.587777 -337.48199) (xy 89.634314 -337.48628) (xy 89.680851 -337.48199)
			(xy 89.725819 -337.469264) (xy 89.767702 -337.448532) (xy 89.786714 -337.434936) (xy 89.808761 -337.418918)
			(xy 89.856588 -337.392794) (xy 89.907646 -337.373742) (xy 89.960896 -337.362151) (xy 90.015254 -337.358257)
			(xy 90.069612 -337.362138) (xy 90.122865 -337.373716) (xy 90.173928 -337.392755) (xy 90.221761 -337.418868)
			(xy 90.265391 -337.451522) (xy 90.30393 -337.490053) (xy 90.336593 -337.533677) (xy 90.362715 -337.581506)
			(xy 90.381763 -337.632565) (xy 90.393352 -337.685816) (xy 90.397243 -337.740174) (xy 91.863003 -337.740174)
			(xy 91.866895 -337.68582) (xy 91.878482 -337.632574) (xy 91.89753 -337.58152) (xy 91.923651 -337.533696)
			(xy 91.956312 -337.490076) (xy 91.994848 -337.451549) (xy 92.038476 -337.418899) (xy 92.086307 -337.39279)
			(xy 92.137366 -337.373755) (xy 92.190615 -337.362181) (xy 92.244969 -337.358303) (xy 92.299322 -337.362201)
			(xy 92.352567 -337.373794) (xy 92.403619 -337.392848) (xy 92.45144 -337.418974) (xy 92.473526 -337.434936)
			(xy 92.492538 -337.448532) (xy 92.534421 -337.469264) (xy 92.579389 -337.48199) (xy 92.625926 -337.48628)
			(xy 92.672463 -337.48199) (xy 92.717431 -337.469264) (xy 92.759314 -337.448532) (xy 92.778326 -337.434936)
			(xy 92.800372 -337.418919) (xy 92.848199 -337.392797) (xy 92.899256 -337.373747) (xy 92.952504 -337.362157)
			(xy 93.00686 -337.358264) (xy 93.061217 -337.362146) (xy 93.114468 -337.373724) (xy 93.165529 -337.392764)
			(xy 93.213361 -337.418876) (xy 93.25699 -337.45153) (xy 93.295527 -337.49006) (xy 93.328188 -337.533683)
			(xy 93.354309 -337.581511) (xy 93.373357 -337.632568) (xy 93.384945 -337.685817) (xy 93.388836 -337.740174)
			(xy 93.384952 -337.79453) (xy 93.373372 -337.847781) (xy 93.354331 -337.898841) (xy 93.328217 -337.946672)
			(xy 93.295561 -337.9903) (xy 93.257029 -338.028836) (xy 93.213405 -338.061495) (xy 93.165577 -338.087614)
			(xy 93.114519 -338.106661) (xy 93.061269 -338.118247) (xy 93.006913 -338.122136) (xy 92.952557 -338.11825)
			(xy 92.899306 -338.106668) (xy 92.848247 -338.087625) (xy 92.800417 -338.06151) (xy 92.778326 -338.045552)
			(xy 92.759314 -338.031956) (xy 92.717431 -338.011224) (xy 92.672463 -337.998498) (xy 92.625926 -337.994208)
			(xy 92.579389 -337.998498) (xy 92.534421 -338.011224) (xy 92.492538 -338.031956) (xy 92.473526 -338.045552)
			(xy 92.451396 -338.061455) (xy 92.403571 -338.087574) (xy 92.352516 -338.106621) (xy 92.29927 -338.118207)
			(xy 92.244916 -338.122097) (xy 92.190563 -338.118212) (xy 92.137316 -338.10663) (xy 92.086259 -338.087588)
			(xy 92.038432 -338.061473) (xy 91.994808 -338.028816) (xy 91.956277 -337.990284) (xy 91.923622 -337.94666)
			(xy 91.897508 -337.898832) (xy 91.878467 -337.847775) (xy 91.866887 -337.794527) (xy 91.863003 -337.740174)
			(xy 90.397243 -337.740174) (xy 90.393359 -337.794532) (xy 90.381778 -337.847784) (xy 90.362737 -337.898846)
			(xy 90.336622 -337.946678) (xy 90.303965 -337.990307) (xy 90.265431 -338.028843) (xy 90.221806 -338.061504)
			(xy 90.173976 -338.087623) (xy 90.122915 -338.106669) (xy 90.069664 -338.118255) (xy 90.015306 -338.122143)
			(xy 89.960948 -338.118256) (xy 89.907697 -338.106673) (xy 89.856636 -338.087628) (xy 89.808805 -338.061511)
			(xy 89.786714 -338.045552) (xy 89.767702 -338.031956) (xy 89.725819 -338.011224) (xy 89.680851 -337.998498)
			(xy 89.634314 -337.994208) (xy 89.587777 -337.998498) (xy 89.542809 -338.011224) (xy 89.500926 -338.031956)
			(xy 89.481914 -338.045552) (xy 89.459784 -338.061454) (xy 89.41196 -338.087571) (xy 89.360906 -338.106616)
			(xy 89.307661 -338.118201) (xy 89.25331 -338.12209) (xy 89.198958 -338.118204) (xy 89.145712 -338.106621)
			(xy 89.094657 -338.087579) (xy 89.046832 -338.061464) (xy 89.00321 -338.028809) (xy 88.96468 -337.990277)
			(xy 88.932027 -337.946654) (xy 88.905914 -337.898828) (xy 88.886874 -337.847772) (xy 88.875294 -337.794526)
			(xy 88.87141 -337.740174) (xy 85.190846 -337.740174) (xy 85.286096 -337.941435) (xy 85.386911 -338.1731)
			(xy 85.480363 -338.407833) (xy 85.566358 -338.645398) (xy 85.644811 -338.88556) (xy 85.715643 -339.128079)
			(xy 85.778784 -339.372714) (xy 85.834171 -339.619219) (xy 85.881748 -339.86735) (xy 85.921468 -340.11686)
			(xy 85.953292 -340.367499) (xy 85.957437 -340.411128) (xy 88.871338 -340.411128) (xy 88.875223 -340.356765)
			(xy 88.886804 -340.303509) (xy 88.905848 -340.252444) (xy 88.931965 -340.204608) (xy 88.964625 -340.160977)
			(xy 89.003162 -340.122438) (xy 89.046792 -340.089776) (xy 89.094626 -340.063656) (xy 89.145691 -340.04461)
			(xy 89.198946 -340.033025) (xy 89.253308 -340.029138) (xy 89.30767 -340.033028) (xy 89.360925 -340.044615)
			(xy 89.411989 -340.063663) (xy 89.459822 -340.089785) (xy 89.481914 -340.105746) (xy 89.500926 -340.119342)
			(xy 89.542809 -340.140074) (xy 89.587777 -340.1528) (xy 89.634314 -340.15709) (xy 89.680851 -340.1528)
			(xy 89.725819 -340.140074) (xy 89.767702 -340.119342) (xy 89.786714 -340.105746) (xy 89.808845 -340.089849)
			(xy 89.856667 -340.063737) (xy 89.907718 -340.044696) (xy 89.96096 -340.033115) (xy 90.015308 -340.029229)
			(xy 90.069655 -340.033117) (xy 90.122896 -340.0447) (xy 90.173947 -340.063743) (xy 90.221768 -340.089857)
			(xy 90.265385 -340.122512) (xy 90.303911 -340.161041) (xy 90.336562 -340.204662) (xy 90.362672 -340.252485)
			(xy 90.38171 -340.303537) (xy 90.393288 -340.35678) (xy 90.397171 -340.411128) (xy 91.862931 -340.411128)
			(xy 91.866816 -340.356764) (xy 91.878398 -340.303506) (xy 91.897442 -340.252439) (xy 91.923561 -340.204602)
			(xy 91.956222 -340.16097) (xy 91.99476 -340.12243) (xy 92.038392 -340.089767) (xy 92.086228 -340.063647)
			(xy 92.137294 -340.044601) (xy 92.190551 -340.033017) (xy 92.244915 -340.029131) (xy 92.299279 -340.033022)
			(xy 92.352535 -340.04461) (xy 92.4036 -340.06366) (xy 92.451434 -340.089784) (xy 92.473526 -340.105746)
			(xy 92.492538 -340.119342) (xy 92.534421 -340.140074) (xy 92.579389 -340.1528) (xy 92.625926 -340.15709)
			(xy 92.672463 -340.1528) (xy 92.717431 -340.140074) (xy 92.759314 -340.119342) (xy 92.778326 -340.105746)
			(xy 92.800457 -340.08985) (xy 92.848278 -340.06374) (xy 92.899328 -340.044701) (xy 92.952568 -340.033121)
			(xy 93.006914 -340.029236) (xy 93.06126 -340.033125) (xy 93.1145 -340.044709) (xy 93.165548 -340.063752)
			(xy 93.213367 -340.089866) (xy 93.256983 -340.12252) (xy 93.295508 -340.161048) (xy 93.328157 -340.204668)
			(xy 93.354266 -340.25249) (xy 93.373303 -340.303541) (xy 93.384881 -340.356781) (xy 93.388764 -340.411128)
			(xy 93.384873 -340.465473) (xy 93.373287 -340.518712) (xy 93.354243 -340.56976) (xy 93.328127 -340.617579)
			(xy 93.295472 -340.661193) (xy 93.256941 -340.699716) (xy 93.213321 -340.732364) (xy 93.165498 -340.758471)
			(xy 93.114447 -340.777507) (xy 93.061206 -340.789083) (xy 93.006859 -340.792964) (xy 92.952513 -340.789071)
			(xy 92.899275 -340.777484) (xy 92.848227 -340.758437) (xy 92.80041 -340.73232) (xy 92.778326 -340.716362)
			(xy 92.759314 -340.702766) (xy 92.717431 -340.682034) (xy 92.672463 -340.669308) (xy 92.625926 -340.665018)
			(xy 92.579389 -340.669308) (xy 92.534421 -340.682034) (xy 92.492538 -340.702766) (xy 92.473526 -340.716362)
			(xy 92.45148 -340.732386) (xy 92.40365 -340.758517) (xy 92.352588 -340.777574) (xy 92.299333 -340.78917)
			(xy 92.24497 -340.793069) (xy 92.190606 -340.789191) (xy 92.137347 -340.777614) (xy 92.086278 -340.758576)
			(xy 92.038438 -340.732462) (xy 91.994802 -340.699806) (xy 91.956258 -340.661272) (xy 91.923591 -340.617644)
			(xy 91.897465 -340.569811) (xy 91.878413 -340.518747) (xy 91.866823 -340.465491) (xy 91.862931 -340.411128)
			(xy 90.397171 -340.411128) (xy 90.39328 -340.465475) (xy 90.381694 -340.518716) (xy 90.362649 -340.569765)
			(xy 90.336532 -340.617585) (xy 90.303875 -340.6612) (xy 90.265343 -340.699724) (xy 90.221721 -340.732372)
			(xy 90.173897 -340.75848) (xy 90.122843 -340.777515) (xy 90.069601 -340.789091) (xy 90.015252 -340.792971)
			(xy 89.960905 -340.789077) (xy 89.907665 -340.777488) (xy 89.856617 -340.75844) (xy 89.808799 -340.732321)
			(xy 89.786714 -340.716362) (xy 89.767702 -340.702766) (xy 89.725819 -340.682034) (xy 89.680851 -340.669308)
			(xy 89.634314 -340.665018) (xy 89.587777 -340.669308) (xy 89.542809 -340.682034) (xy 89.500926 -340.702766)
			(xy 89.481914 -340.716362) (xy 89.459869 -340.732385) (xy 89.412039 -340.758514) (xy 89.360978 -340.77757)
			(xy 89.307725 -340.789164) (xy 89.253364 -340.793062) (xy 89.199001 -340.789182) (xy 89.145744 -340.777606)
			(xy 89.094676 -340.758567) (xy 89.046838 -340.732454) (xy 89.003204 -340.699798) (xy 88.964661 -340.661265)
			(xy 88.931995 -340.617638) (xy 88.905871 -340.569807) (xy 88.88682 -340.518744) (xy 88.87523 -340.465489)
			(xy 88.871338 -340.411128) (xy 85.957437 -340.411128) (xy 85.977188 -340.619017) (xy 85.993132 -340.871165)
			(xy 86.001107 -341.12369) (xy 86.001606 -341.250016) (xy 86.001107 -341.376342) (xy 85.993132 -341.628867)
			(xy 85.977188 -341.881015) (xy 85.953292 -342.132533) (xy 85.921468 -342.383172) (xy 85.881748 -342.632682)
			(xy 85.834171 -342.880813) (xy 85.789576 -343.079286) (xy 88.871394 -343.079286) (xy 88.875284 -343.024932)
			(xy 88.88687 -342.971685) (xy 88.905916 -342.920629) (xy 88.932035 -342.872803) (xy 88.964695 -342.829182)
			(xy 89.003231 -342.790653) (xy 89.046858 -342.758) (xy 89.094688 -342.731889) (xy 89.145747 -342.712852)
			(xy 89.198996 -342.701275) (xy 89.25335 -342.697394) (xy 89.307704 -342.701289) (xy 89.36095 -342.71288)
			(xy 89.412004 -342.731931) (xy 89.459827 -342.758055) (xy 89.481914 -342.774016) (xy 89.500926 -342.787612)
			(xy 89.542809 -342.808344) (xy 89.587777 -342.82107) (xy 89.634314 -342.82536) (xy 89.680851 -342.82107)
			(xy 89.725819 -342.808344) (xy 89.767702 -342.787612) (xy 89.786714 -342.774016) (xy 89.808779 -342.758025)
			(xy 89.856605 -342.731903) (xy 89.907662 -342.712854) (xy 89.96091 -342.701265) (xy 90.015266 -342.697373)
			(xy 90.069622 -342.701255) (xy 90.122872 -342.712835) (xy 90.173932 -342.731875) (xy 90.221763 -342.757988)
			(xy 90.26539 -342.790642) (xy 90.303926 -342.829173) (xy 90.336586 -342.872796) (xy 90.362705 -342.920624)
			(xy 90.381752 -342.971681) (xy 90.393338 -343.02493) (xy 90.397227 -343.079286) (xy 91.862987 -343.079286)
			(xy 91.866877 -343.02493) (xy 91.878464 -342.971681) (xy 91.897511 -342.920624) (xy 91.923631 -342.872797)
			(xy 91.956292 -342.829175) (xy 91.994829 -342.790645) (xy 92.038457 -342.757992) (xy 92.086289 -342.731881)
			(xy 92.13735 -342.712843) (xy 92.190601 -342.701267) (xy 92.244957 -342.697387) (xy 92.299312 -342.701283)
			(xy 92.35256 -342.712876) (xy 92.403615 -342.731928) (xy 92.451439 -342.758054) (xy 92.473526 -342.774016)
			(xy 92.492538 -342.787612) (xy 92.534421 -342.808344) (xy 92.579389 -342.82107) (xy 92.625926 -342.82536)
			(xy 92.672463 -342.82107) (xy 92.717431 -342.808344) (xy 92.759314 -342.787612) (xy 92.778326 -342.774016)
			(xy 92.800391 -342.758026) (xy 92.848216 -342.731906) (xy 92.899272 -342.712859) (xy 92.952519 -342.701271)
			(xy 93.006872 -342.69738) (xy 93.061227 -342.701263) (xy 93.114475 -342.712843) (xy 93.165533 -342.731883)
			(xy 93.213362 -342.757996) (xy 93.256988 -342.79065) (xy 93.295523 -342.82918) (xy 93.328181 -342.872802)
			(xy 93.354299 -342.920628) (xy 93.373345 -342.971685) (xy 93.384931 -343.024932) (xy 93.38882 -343.079286)
			(xy 93.384935 -343.13364) (xy 93.373353 -343.186888) (xy 93.354311 -343.237946) (xy 93.328197 -343.285774)
			(xy 93.295541 -343.329398) (xy 93.25701 -343.367931) (xy 93.213387 -343.400588) (xy 93.16556 -343.426705)
			(xy 93.114503 -343.445749) (xy 93.061255 -343.457332) (xy 93.006901 -343.46122) (xy 92.952547 -343.457333)
			(xy 92.899299 -343.445749) (xy 92.848242 -343.426706) (xy 92.800415 -343.40059) (xy 92.778326 -343.384632)
			(xy 92.759314 -343.371036) (xy 92.717431 -343.350304) (xy 92.672463 -343.337578) (xy 92.625926 -343.333288)
			(xy 92.579389 -343.337578) (xy 92.534421 -343.350304) (xy 92.492538 -343.371036) (xy 92.473526 -343.384632)
			(xy 92.451415 -343.400562) (xy 92.403589 -343.426684) (xy 92.352532 -343.445733) (xy 92.299284 -343.457321)
			(xy 92.244928 -343.461213) (xy 92.190572 -343.457329) (xy 92.137323 -343.445749) (xy 92.086263 -343.426707)
			(xy 92.038433 -343.400593) (xy 91.994807 -343.367936) (xy 91.956273 -343.329404) (xy 91.923615 -343.285779)
			(xy 91.897499 -343.23795) (xy 91.878455 -343.186891) (xy 91.866873 -343.133641) (xy 91.862987 -343.079286)
			(xy 90.397227 -343.079286) (xy 90.393342 -343.133641) (xy 90.38176 -343.186891) (xy 90.362717 -343.23795)
			(xy 90.336602 -343.28578) (xy 90.303945 -343.329405) (xy 90.265412 -343.367939) (xy 90.221787 -343.400597)
			(xy 90.173958 -343.426713) (xy 90.122899 -343.445757) (xy 90.06965 -343.45734) (xy 90.015294 -343.461227)
			(xy 89.960939 -343.457339) (xy 89.90769 -343.445754) (xy 89.856632 -343.426709) (xy 89.808804 -343.400591)
			(xy 89.786714 -343.384632) (xy 89.767702 -343.371036) (xy 89.725819 -343.350304) (xy 89.680851 -343.337578)
			(xy 89.634314 -343.333288) (xy 89.587777 -343.337578) (xy 89.542809 -343.350304) (xy 89.500926 -343.371036)
			(xy 89.481914 -343.384632) (xy 89.459803 -343.400561) (xy 89.411978 -343.426681) (xy 89.360922 -343.445728)
			(xy 89.307675 -343.457315) (xy 89.253322 -343.461206) (xy 89.198967 -343.457321) (xy 89.145719 -343.44574)
			(xy 89.094661 -343.426699) (xy 89.046833 -343.400584) (xy 89.003209 -343.367929) (xy 88.964676 -343.329397)
			(xy 88.93202 -343.285773) (xy 88.905904 -343.237945) (xy 88.886862 -343.186888) (xy 88.87528 -343.13364)
			(xy 88.871394 -343.079286) (xy 85.789576 -343.079286) (xy 85.778784 -343.127318) (xy 85.715643 -343.371953)
			(xy 85.664461 -343.547192) (xy 94.503238 -343.547192) (xy 94.507309 -343.49157) (xy 94.519435 -343.437133)
			(xy 94.539358 -343.385042) (xy 94.566654 -343.336407) (xy 94.60074 -343.292264) (xy 94.640889 -343.253555)
			(xy 94.686247 -343.221104) (xy 94.735847 -343.195603) (xy 94.788631 -343.177596) (xy 94.843474 -343.167466)
			(xy 94.899208 -343.165429) (xy 94.954645 -343.171529) (xy 95.008602 -343.185635) (xy 95.059931 -343.207447)
			(xy 95.107537 -343.236501) (xy 95.150405 -343.272176) (xy 95.187622 -343.313713) (xy 95.218395 -343.360226)
			(xy 95.242067 -343.410723) (xy 95.258135 -343.46413) (xy 95.266255 -343.519306) (xy 95.266764 -343.547192)
			(xy 95.266255 -343.575078) (xy 95.258135 -343.630254) (xy 95.242067 -343.683661) (xy 95.218395 -343.734158)
			(xy 95.187622 -343.780671) (xy 95.150405 -343.822208) (xy 95.107537 -343.857883) (xy 95.059931 -343.886937)
			(xy 95.008602 -343.908749) (xy 94.954645 -343.922855) (xy 94.899208 -343.928955) (xy 94.843474 -343.926918)
			(xy 94.788631 -343.916788) (xy 94.735847 -343.898781) (xy 94.686247 -343.87328) (xy 94.640889 -343.840829)
			(xy 94.60074 -343.80212) (xy 94.566654 -343.757977) (xy 94.539358 -343.709342) (xy 94.519435 -343.657251)
			(xy 94.507309 -343.602814) (xy 94.503238 -343.547192) (xy 85.664461 -343.547192) (xy 85.644811 -343.614472)
			(xy 85.566358 -343.854634) (xy 85.480363 -344.092199) (xy 85.386911 -344.326932) (xy 85.286096 -344.558597)
			(xy 85.178017 -344.786965) (xy 85.062783 -345.011806) (xy 84.940508 -345.232898) (xy 84.811315 -345.45002)
			(xy 84.810761 -345.450887) (xy 88.871393 -345.450887) (xy 88.875282 -345.396533) (xy 88.886868 -345.343285)
			(xy 88.905914 -345.292229) (xy 88.932033 -345.244403) (xy 88.964693 -345.200782) (xy 89.003229 -345.162252)
			(xy 89.046856 -345.1296) (xy 89.094686 -345.103489) (xy 89.145745 -345.084451) (xy 89.198994 -345.072873)
			(xy 89.253349 -345.068993) (xy 89.307703 -345.072887) (xy 89.360949 -345.084478) (xy 89.412004 -345.103529)
			(xy 89.459827 -345.129653) (xy 89.481914 -345.145614) (xy 89.500926 -345.15921) (xy 89.542809 -345.179942)
			(xy 89.587777 -345.192668) (xy 89.634314 -345.196958) (xy 89.680851 -345.192668) (xy 89.725819 -345.179942)
			(xy 89.767702 -345.15921) (xy 89.786714 -345.145614) (xy 89.808781 -345.129626) (xy 89.856607 -345.103504)
			(xy 89.907664 -345.084455) (xy 89.960912 -345.072867) (xy 90.015267 -345.068974) (xy 90.069623 -345.072857)
			(xy 90.122872 -345.084437) (xy 90.173932 -345.103477) (xy 90.221763 -345.12959) (xy 90.26539 -345.162244)
			(xy 90.303926 -345.200775) (xy 90.336585 -345.244398) (xy 90.362704 -345.292225) (xy 90.38175 -345.343283)
			(xy 90.393336 -345.396531) (xy 90.397226 -345.450887) (xy 91.862986 -345.450887) (xy 91.866875 -345.396531)
			(xy 91.878462 -345.343282) (xy 91.897509 -345.292224) (xy 91.923629 -345.244397) (xy 91.95629 -345.200775)
			(xy 91.994827 -345.162244) (xy 92.038455 -345.129591) (xy 92.086287 -345.10348) (xy 92.137349 -345.084442)
			(xy 92.1906 -345.072865) (xy 92.244956 -345.068986) (xy 92.299311 -345.072881) (xy 92.352559 -345.084474)
			(xy 92.403615 -345.103526) (xy 92.451439 -345.129652) (xy 92.473526 -345.145614) (xy 92.492538 -345.15921)
			(xy 92.534421 -345.179942) (xy 92.579389 -345.192668) (xy 92.625926 -345.196958) (xy 92.672463 -345.192668)
			(xy 92.717431 -345.179942) (xy 92.759314 -345.15921) (xy 92.778326 -345.145614) (xy 92.800393 -345.129627)
			(xy 92.848218 -345.103507) (xy 92.899273 -345.08446) (xy 92.95252 -345.072873) (xy 93.006874 -345.068981)
			(xy 93.061228 -345.072865) (xy 93.114476 -345.084445) (xy 93.165534 -345.103485) (xy 93.213363 -345.129598)
			(xy 93.256988 -345.162252) (xy 93.295522 -345.200782) (xy 93.328181 -345.244404) (xy 93.354298 -345.29223)
			(xy 93.373344 -345.343286) (xy 93.384929 -345.396533) (xy 93.388819 -345.450887) (xy 93.384933 -345.505241)
			(xy 93.373351 -345.558489) (xy 93.354309 -345.609546) (xy 93.328195 -345.657374) (xy 93.295539 -345.700998)
			(xy 93.257008 -345.739531) (xy 93.213385 -345.772188) (xy 93.165558 -345.798304) (xy 93.114501 -345.817348)
			(xy 93.061254 -345.828931) (xy 93.0069 -345.832819) (xy 92.952546 -345.828931) (xy 92.899299 -345.817347)
			(xy 92.848242 -345.798304) (xy 92.800415 -345.772188) (xy 92.778326 -345.75623) (xy 92.759314 -345.742634)
			(xy 92.717431 -345.721902) (xy 92.672463 -345.709176) (xy 92.625926 -345.704886) (xy 92.579389 -345.709176)
			(xy 92.534421 -345.721902) (xy 92.492538 -345.742634) (xy 92.473526 -345.75623) (xy 92.451417 -345.772162)
			(xy 92.403591 -345.798284) (xy 92.352534 -345.817334) (xy 92.299285 -345.828922) (xy 92.24493 -345.832814)
			(xy 92.190573 -345.828931) (xy 92.137323 -345.81735) (xy 92.086263 -345.798309) (xy 92.038433 -345.772195)
			(xy 91.994807 -345.739538) (xy 91.956272 -345.701006) (xy 91.923614 -345.657381) (xy 91.897498 -345.609552)
			(xy 91.878454 -345.558493) (xy 91.866872 -345.505243) (xy 91.862986 -345.450887) (xy 90.397226 -345.450887)
			(xy 90.39334 -345.505242) (xy 90.381758 -345.558492) (xy 90.362715 -345.609551) (xy 90.3366 -345.65738)
			(xy 90.303943 -345.701005) (xy 90.26541 -345.739539) (xy 90.221785 -345.772196) (xy 90.173956 -345.798312)
			(xy 90.122898 -345.817356) (xy 90.069649 -345.828939) (xy 90.015293 -345.832826) (xy 89.960938 -345.828937)
			(xy 89.907689 -345.817352) (xy 89.856631 -345.798307) (xy 89.808803 -345.772189) (xy 89.786714 -345.75623)
			(xy 89.767702 -345.742634) (xy 89.725819 -345.721902) (xy 89.680851 -345.709176) (xy 89.634314 -345.704886)
			(xy 89.587777 -345.709176) (xy 89.542809 -345.721902) (xy 89.500926 -345.742634) (xy 89.481914 -345.75623)
			(xy 89.459805 -345.772161) (xy 89.41198 -345.798282) (xy 89.360924 -345.817329) (xy 89.307677 -345.828916)
			(xy 89.253323 -345.832807) (xy 89.198968 -345.828923) (xy 89.14572 -345.817342) (xy 89.094662 -345.7983)
			(xy 89.046833 -345.772186) (xy 89.003209 -345.73953) (xy 88.964676 -345.700998) (xy 88.932019 -345.657375)
			(xy 88.905903 -345.609547) (xy 88.886861 -345.558489) (xy 88.875279 -345.505241) (xy 88.871393 -345.450887)
			(xy 84.810761 -345.450887) (xy 84.675332 -345.662955) (xy 84.532695 -345.871491) (xy 84.383546 -346.07542)
			(xy 84.228033 -346.274539) (xy 84.066312 -346.46865) (xy 83.898544 -346.657558) (xy 83.724896 -346.841077)
			(xy 83.698283 -346.86748) (xy 94.786956 -346.86748) (xy 94.791027 -346.811858) (xy 94.803153 -346.757421)
			(xy 94.823076 -346.70533) (xy 94.850372 -346.656695) (xy 94.884458 -346.612552) (xy 94.924607 -346.573843)
			(xy 94.969965 -346.541392) (xy 95.019565 -346.515891) (xy 95.072349 -346.497884) (xy 95.127192 -346.487754)
			(xy 95.182926 -346.485717) (xy 95.238363 -346.491817) (xy 95.29232 -346.505923) (xy 95.343649 -346.527735)
			(xy 95.391255 -346.556789) (xy 95.434123 -346.592464) (xy 95.47134 -346.634001) (xy 95.502113 -346.680514)
			(xy 95.525785 -346.731011) (xy 95.541853 -346.784418) (xy 95.549973 -346.839594) (xy 95.550482 -346.86748)
			(xy 95.549973 -346.895366) (xy 95.541853 -346.950542) (xy 95.525785 -347.003949) (xy 95.502113 -347.054446)
			(xy 95.47134 -347.100959) (xy 95.434123 -347.142496) (xy 95.391255 -347.178171) (xy 95.343649 -347.207225)
			(xy 95.29232 -347.229037) (xy 95.238363 -347.243143) (xy 95.182926 -347.249243) (xy 95.127192 -347.247206)
			(xy 95.072349 -347.237076) (xy 95.019565 -347.219069) (xy 94.969965 -347.193568) (xy 94.924607 -347.161117)
			(xy 94.884458 -347.122408) (xy 94.850372 -347.078265) (xy 94.823076 -347.02963) (xy 94.803153 -346.977539)
			(xy 94.791027 -346.923102) (xy 94.786956 -346.86748) (xy 83.698283 -346.86748) (xy 83.54554 -347.019021)
			(xy 83.360657 -347.191216) (xy 83.17043 -347.357488) (xy 83.101769 -347.41378) (xy 88.871402 -347.41378)
			(xy 88.875293 -347.359427) (xy 88.886879 -347.306181) (xy 88.905926 -347.255126) (xy 88.932045 -347.207302)
			(xy 88.964705 -347.163682) (xy 89.00324 -347.125155) (xy 89.046867 -347.092504) (xy 89.094696 -347.066394)
			(xy 89.145755 -347.047358) (xy 89.199003 -347.035782) (xy 89.253356 -347.031902) (xy 89.307709 -347.035798)
			(xy 89.360953 -347.04739) (xy 89.412006 -347.066441) (xy 89.459828 -347.092565) (xy 89.481914 -347.108526)
			(xy 89.500926 -347.122122) (xy 89.542809 -347.142854) (xy 89.587777 -347.15558) (xy 89.634314 -347.15987)
			(xy 89.680851 -347.15558) (xy 89.725819 -347.142854) (xy 89.767702 -347.122122) (xy 89.786714 -347.108526)
			(xy 89.80877 -347.092521) (xy 89.856597 -347.066398) (xy 89.907654 -347.047348) (xy 89.960903 -347.035758)
			(xy 90.01526 -347.031865) (xy 90.069617 -347.035747) (xy 90.122868 -347.047325) (xy 90.17393 -347.066365)
			(xy 90.221762 -347.092478) (xy 90.265391 -347.125132) (xy 90.303928 -347.163663) (xy 90.336589 -347.207287)
			(xy 90.36271 -347.255115) (xy 90.381758 -347.306173) (xy 90.393345 -347.359423) (xy 90.397235 -347.41378)
			(xy 91.862995 -347.41378) (xy 91.866886 -347.359425) (xy 91.878473 -347.306178) (xy 91.89752 -347.255122)
			(xy 91.923641 -347.207296) (xy 91.956302 -347.163675) (xy 91.994839 -347.125147) (xy 92.038467 -347.092495)
			(xy 92.086298 -347.066386) (xy 92.137358 -347.047349) (xy 92.190608 -347.035774) (xy 92.244963 -347.031895)
			(xy 92.299317 -347.035792) (xy 92.352563 -347.047385) (xy 92.403617 -347.066438) (xy 92.45144 -347.092564)
			(xy 92.473526 -347.108526) (xy 92.492538 -347.122122) (xy 92.534421 -347.142854) (xy 92.579389 -347.15558)
			(xy 92.625926 -347.15987) (xy 92.672463 -347.15558) (xy 92.717431 -347.142854) (xy 92.759314 -347.122122)
			(xy 92.778326 -347.108526) (xy 92.800382 -347.092522) (xy 92.848207 -347.066401) (xy 92.899264 -347.047353)
			(xy 92.952511 -347.035764) (xy 93.006866 -347.031872) (xy 93.061222 -347.035755) (xy 93.114472 -347.047334)
			(xy 93.165531 -347.066373) (xy 93.213362 -347.092486) (xy 93.256989 -347.12514) (xy 93.295525 -347.16367)
			(xy 93.328185 -347.207293) (xy 93.354304 -347.255119) (xy 93.373351 -347.306177) (xy 93.384938 -347.359425)
			(xy 93.388828 -347.41378) (xy 93.384943 -347.468135) (xy 93.373362 -347.521384) (xy 93.354321 -347.572443)
			(xy 93.328207 -347.620273) (xy 93.295551 -347.663899) (xy 93.25702 -347.702433) (xy 93.213396 -347.735092)
			(xy 93.165568 -347.76121) (xy 93.114511 -347.780255) (xy 93.061262 -347.791839) (xy 93.006907 -347.795728)
			(xy 92.952552 -347.791842) (xy 92.899303 -347.780259) (xy 92.848245 -347.761216) (xy 92.800416 -347.7351)
			(xy 92.778326 -347.719142) (xy 92.759314 -347.705546) (xy 92.717431 -347.684814) (xy 92.672463 -347.672088)
			(xy 92.625926 -347.667798) (xy 92.579389 -347.672088) (xy 92.534421 -347.684814) (xy 92.492538 -347.705546)
			(xy 92.473526 -347.719142) (xy 92.451405 -347.735058) (xy 92.40358 -347.761179) (xy 92.352524 -347.780227)
			(xy 92.299277 -347.791814) (xy 92.244922 -347.795705) (xy 92.190568 -347.79182) (xy 92.137319 -347.780239)
			(xy 92.086261 -347.761197) (xy 92.038432 -347.735083) (xy 91.994808 -347.702426) (xy 91.956275 -347.663894)
			(xy 91.923619 -347.620269) (xy 91.897503 -347.572441) (xy 91.878461 -347.521383) (xy 91.86688 -347.468134)
			(xy 91.862995 -347.41378) (xy 90.397235 -347.41378) (xy 90.39335 -347.468137) (xy 90.381769 -347.521388)
			(xy 90.362727 -347.572448) (xy 90.336612 -347.620279) (xy 90.303955 -347.663906) (xy 90.265422 -347.702441)
			(xy 90.221796 -347.7351) (xy 90.173967 -347.761218) (xy 90.122907 -347.780263) (xy 90.069657 -347.791847)
			(xy 90.0153 -347.795735) (xy 89.960943 -347.791848) (xy 89.907693 -347.780263) (xy 89.856634 -347.761218)
			(xy 89.808804 -347.735101) (xy 89.786714 -347.719142) (xy 89.767702 -347.705546) (xy 89.725819 -347.684814)
			(xy 89.680851 -347.672088) (xy 89.634314 -347.667798) (xy 89.587777 -347.672088) (xy 89.542809 -347.684814)
			(xy 89.500926 -347.705546) (xy 89.481914 -347.719142) (xy 89.459794 -347.735057) (xy 89.411969 -347.761176)
			(xy 89.360914 -347.780222) (xy 89.307668 -347.791808) (xy 89.253316 -347.795698) (xy 89.198962 -347.791812)
			(xy 89.145716 -347.780231) (xy 89.094659 -347.761189) (xy 89.046833 -347.735074) (xy 89.00321 -347.702419)
			(xy 88.964678 -347.663887) (xy 88.932023 -347.620263) (xy 88.905909 -347.572436) (xy 88.886868 -347.52138)
			(xy 88.875287 -347.468133) (xy 88.871402 -347.41378) (xy 83.101769 -347.41378) (xy 82.975049 -347.517672)
			(xy 82.774709 -347.671608) (xy 82.569609 -347.819143) (xy 82.359953 -347.960129) (xy 82.145951 -348.094427)
			(xy 81.927817 -348.221903) (xy 81.705767 -348.342428) (xy 81.480023 -348.455884) (xy 81.250809 -348.562156)
			(xy 81.018355 -348.66114) (xy 80.782892 -348.752737) (xy 80.544655 -348.836854) (xy 80.303881 -348.913409)
			(xy 80.060811 -348.982324) (xy 79.815686 -349.043532) (xy 79.568751 -349.096971) (xy 79.320252 -349.142588)
			(xy 79.070437 -349.180338) (xy 78.819554 -349.210182) (xy 78.567855 -349.232092) (xy 78.315589 -349.246045)
			(xy 78.063009 -349.252027) (xy 77.810365 -349.250033) (xy 77.557911 -349.240064) (xy 77.305897 -349.222131)
			(xy 77.054575 -349.19625) (xy 76.804195 -349.162449) (xy 76.555007 -349.12076) (xy 76.307259 -349.071226)
			(xy 76.061198 -349.013896) (xy 75.81707 -348.948826) (xy 75.575118 -348.876082) (xy 75.335582 -348.795735)
			(xy 75.098703 -348.707868) (xy 74.864715 -348.612566) (xy 74.633853 -348.509925) (xy 74.406346 -348.400047)
			(xy 74.182421 -348.283042) (xy 73.962301 -348.159026) (xy 73.746206 -348.028123) (xy 73.534351 -347.890463)
			(xy 73.326947 -347.746185) (xy 73.124201 -347.59543) (xy 72.926316 -347.438351) (xy 72.733488 -347.275102)
			(xy 72.54591 -347.105848) (xy 72.363768 -346.930757) (xy 72.187244 -346.750003) (xy 72.016514 -346.563766)
			(xy 71.851749 -346.372233) (xy 71.693113 -346.175593) (xy 71.540763 -345.974044) (xy 71.394851 -345.767786)
			(xy 71.255524 -345.557024) (xy 71.122919 -345.341969) (xy 70.99717 -345.122835) (xy 70.878401 -344.89984)
			(xy 70.76673 -344.673208) (xy 70.66227 -344.443162) (xy 70.565124 -344.209934) (xy 70.47539 -343.973756)
			(xy 70.393155 -343.734862) (xy 70.318504 -343.493492) (xy 70.251509 -343.249885) (xy 70.192238 -343.004284)
			(xy 70.140749 -342.756935) (xy 70.097095 -342.508084) (xy 70.061319 -342.257978) (xy 70.033455 -342.006868)
			(xy 70.013533 -341.755004) (xy 70.001572 -341.502636) (xy 69.997584 -341.250016) (xy 28.08351 -341.250016)
			(xy 28.08351 -349.939356) (xy 51.07432 -349.939356) (xy 52.726336 -349.939356) (xy 52.726336 -350.098614)
			(xy 68.218812 -350.098614) (xy 68.218812 -349.155004) (xy 68.219298 -349.122459) (xy 68.227581 -349.057897)
			(xy 68.244039 -348.994922) (xy 68.268401 -348.934563) (xy 68.300269 -348.877808) (xy 68.339122 -348.825585)
			(xy 68.384324 -348.77875) (xy 68.435135 -348.738068) (xy 68.490724 -348.704205) (xy 68.55018 -348.677717)
			(xy 68.612532 -348.659035) (xy 68.676759 -348.648465) (xy 68.741809 -348.646181) (xy 68.806618 -348.652221)
			(xy 68.870127 -348.666484) (xy 68.931295 -348.688738) (xy 68.989121 -348.718619) (xy 69.04266 -348.755637)
			(xy 69.091035 -348.799187) (xy 69.112638 -348.823534) (xy 69.12854 -348.841184) (xy 69.165635 -348.870853)
			(xy 69.207598 -348.893108) (xy 69.252968 -348.907176) (xy 69.300161 -348.912564) (xy 69.347533 -348.909086)
			(xy 69.393434 -348.896863) (xy 69.436262 -348.87632) (xy 69.474525 -348.848174) (xy 69.491098 -348.831154)
			(xy 69.513103 -348.808275) (xy 69.561795 -348.767549) (xy 69.615179 -348.733201) (xy 69.672424 -348.705767)
			(xy 69.732639 -348.685674) (xy 69.794887 -348.673233) (xy 69.8582 -348.668639) (xy 69.921592 -348.671963)
			(xy 69.984077 -348.683154) (xy 70.044682 -348.702036) (xy 70.102466 -348.728317) (xy 70.156527 -348.761588)
			(xy 70.206026 -348.80133) (xy 70.22846 -348.823788) (xy 70.245368 -348.840444) (xy 70.284102 -348.86786)
			(xy 70.327256 -348.887601) (xy 70.373325 -348.89898) (xy 70.420707 -348.901601) (xy 70.467751 -348.895372)
			(xy 70.512818 -348.880512) (xy 70.55434 -348.857536) (xy 70.590869 -348.827246) (xy 70.606412 -348.80931)
			(xy 70.627485 -348.784705) (xy 70.674865 -348.740521) (xy 70.727472 -348.702711) (xy 70.784455 -348.671888)
			(xy 70.84489 -348.648551) (xy 70.9078 -348.633077) (xy 70.972166 -348.625718) (xy 71.036945 -348.626592)
			(xy 71.101088 -348.635685) (xy 71.163558 -348.652851) (xy 71.223342 -348.67781) (xy 71.279472 -348.710159)
			(xy 71.33104 -348.749375) (xy 71.37721 -348.794821) (xy 71.397622 -348.819978) (xy 71.412221 -348.837766)
			(xy 71.446673 -348.868267) (xy 71.486052 -348.892068) (xy 71.529072 -348.908392) (xy 71.574328 -348.916704)
			(xy 71.620341 -348.916734) (xy 71.665608 -348.908481) (xy 71.708649 -348.892214) (xy 71.748059 -348.868464)
			(xy 71.78255 -348.838008) (xy 71.797164 -348.820232) (xy 71.816991 -348.795771) (xy 71.861685 -348.751417)
			(xy 71.911514 -348.712923) (xy 71.965716 -348.680877) (xy 72.023461 -348.655771) (xy 72.083865 -348.637988)
			(xy 72.146002 -348.627802) (xy 72.208921 -348.625367) (xy 72.27166 -348.630721) (xy 72.333257 -348.643783)
			(xy 72.392769 -348.664352) (xy 72.449285 -348.692114) (xy 72.50194 -348.726643) (xy 72.549928 -348.76741)
			(xy 72.592514 -348.813792) (xy 72.629045 -348.865078) (xy 72.658962 -348.920483) (xy 72.681809 -348.979159)
			(xy 72.697233 -349.040207) (xy 72.705 -349.102693) (xy 72.705468 -349.134176) (xy 72.705468 -349.557276)
			(xy 88.871407 -349.557276) (xy 88.875298 -349.502924) (xy 88.886885 -349.449679) (xy 88.905932 -349.398625)
			(xy 88.932051 -349.350802) (xy 88.964711 -349.307183) (xy 89.003246 -349.268656) (xy 89.046873 -349.236006)
			(xy 89.094702 -349.209897) (xy 89.14576 -349.190861) (xy 89.199007 -349.179286) (xy 89.25336 -349.175407)
			(xy 89.307712 -349.179303) (xy 89.360956 -349.190895) (xy 89.412008 -349.209947) (xy 89.459828 -349.236071)
			(xy 89.481914 -349.252032) (xy 89.500926 -349.265628) (xy 89.542809 -349.28636) (xy 89.587777 -349.299086)
			(xy 89.634314 -349.303376) (xy 89.680851 -349.299086) (xy 89.725819 -349.28636) (xy 89.767702 -349.265628)
			(xy 89.786714 -349.252032) (xy 89.808764 -349.236019) (xy 89.856591 -349.209896) (xy 89.907649 -349.190845)
			(xy 89.960899 -349.179254) (xy 90.015256 -349.17536) (xy 90.069614 -349.179241) (xy 90.122866 -349.19082)
			(xy 90.173929 -349.209859) (xy 90.221761 -349.235972) (xy 90.265391 -349.268626) (xy 90.303929 -349.307157)
			(xy 90.336592 -349.350781) (xy 90.362713 -349.39861) (xy 90.381761 -349.449668) (xy 90.393349 -349.502919)
			(xy 90.39724 -349.557276) (xy 91.863 -349.557276) (xy 91.866891 -349.502922) (xy 91.878479 -349.449676)
			(xy 91.897526 -349.398621) (xy 91.923647 -349.350796) (xy 91.956308 -349.307176) (xy 91.994844 -349.268648)
			(xy 92.038472 -349.235997) (xy 92.086303 -349.209889) (xy 92.137363 -349.190853) (xy 92.190612 -349.179278)
			(xy 92.244967 -349.1754) (xy 92.29932 -349.179297) (xy 92.352565 -349.190891) (xy 92.403618 -349.209944)
			(xy 92.45144 -349.23607) (xy 92.473526 -349.252032) (xy 92.492538 -349.265628) (xy 92.534421 -349.28636)
			(xy 92.579389 -349.299086) (xy 92.625926 -349.303376) (xy 92.672463 -349.299086) (xy 92.717431 -349.28636)
			(xy 92.759314 -349.265628) (xy 92.778326 -349.252032) (xy 92.800376 -349.23602) (xy 92.848202 -349.209899)
			(xy 92.899259 -349.190849) (xy 92.952507 -349.17926) (xy 93.006863 -349.175367) (xy 93.061219 -349.179249)
			(xy 93.11447 -349.190828) (xy 93.16553 -349.209868) (xy 93.213361 -349.23598) (xy 93.256989 -349.268634)
			(xy 93.295526 -349.307164) (xy 93.328187 -349.350787) (xy 93.354307 -349.398614) (xy 93.373355 -349.449672)
			(xy 93.384942 -349.50292) (xy 93.388833 -349.557276) (xy 93.384949 -349.611632) (xy 93.373368 -349.664882)
			(xy 93.354327 -349.715942) (xy 93.328213 -349.763772) (xy 93.295557 -349.807399) (xy 93.257026 -349.845935)
			(xy 93.213402 -349.878594) (xy 93.165574 -349.904712) (xy 93.114516 -349.923758) (xy 93.061267 -349.935344)
			(xy 93.006911 -349.939233) (xy 92.952555 -349.935347) (xy 92.899305 -349.923764) (xy 92.848246 -349.904721)
			(xy 92.800416 -349.878606) (xy 92.778326 -349.862648) (xy 92.759314 -349.849052) (xy 92.717431 -349.82832)
			(xy 92.672463 -349.815594) (xy 92.625926 -349.811304) (xy 92.579389 -349.815594) (xy 92.534421 -349.82832)
			(xy 92.492538 -349.849052) (xy 92.473526 -349.862648) (xy 92.4514 -349.878556) (xy 92.403575 -349.904676)
			(xy 92.352519 -349.923723) (xy 92.299273 -349.93531) (xy 92.244919 -349.9392) (xy 92.190565 -349.935315)
			(xy 92.137317 -349.923734) (xy 92.086259 -349.904692) (xy 92.038432 -349.878577) (xy 91.994808 -349.84592)
			(xy 91.956276 -349.807388) (xy 91.923621 -349.763764) (xy 91.897506 -349.715936) (xy 91.878465 -349.664878)
			(xy 91.866884 -349.61163) (xy 91.863 -349.557276) (xy 90.39724 -349.557276) (xy 90.393356 -349.611634)
			(xy 90.381775 -349.664885) (xy 90.362733 -349.715947) (xy 90.336618 -349.763778) (xy 90.303961 -349.807406)
			(xy 90.265427 -349.845943) (xy 90.221802 -349.878602) (xy 90.173972 -349.904721) (xy 90.122912 -349.923767)
			(xy 90.069661 -349.935352) (xy 90.015304 -349.93924) (xy 89.960946 -349.935353) (xy 89.907695 -349.923769)
			(xy 89.856635 -349.904724) (xy 89.808805 -349.878607) (xy 89.786714 -349.862648) (xy 89.767702 -349.849052)
			(xy 89.725819 -349.82832) (xy 89.680851 -349.815594) (xy 89.634314 -349.811304) (xy 89.587777 -349.815594)
			(xy 89.542809 -349.82832) (xy 89.500926 -349.849052) (xy 89.481914 -349.862648) (xy 89.459788 -349.878555)
			(xy 89.411964 -349.904673) (xy 89.360909 -349.923718) (xy 89.307664 -349.935304) (xy 89.253312 -349.939193)
			(xy 89.19896 -349.935307) (xy 89.145714 -349.923725) (xy 89.094658 -349.904683) (xy 89.046832 -349.878568)
			(xy 89.00321 -349.845913) (xy 88.96468 -349.807381) (xy 88.932025 -349.763758) (xy 88.905912 -349.715931)
			(xy 88.886872 -349.664875) (xy 88.875291 -349.611629) (xy 88.871407 -349.557276) (xy 72.705468 -349.557276)
			(xy 72.705468 -350.098868) (xy 72.704959 -350.131603) (xy 72.696521 -350.196529) (xy 72.67982 -350.259834)
			(xy 72.655131 -350.320472) (xy 72.622864 -350.37744) (xy 72.603614 -350.403922) (xy 72.578468 -350.437704)
			(xy 72.578468 -350.454976) (xy 72.562974 -350.454976) (xy 72.52716 -350.485202) (xy 72.501983 -350.506055)
			(xy 72.447251 -350.541806) (xy 72.388386 -350.570245) (xy 72.326361 -350.5909) (xy 72.262199 -350.603431)
			(xy 72.19696 -350.607631) (xy 72.131721 -350.603431) (xy 72.067559 -350.5909) (xy 72.005534 -350.570245)
			(xy 71.946669 -350.541806) (xy 71.891937 -350.506055) (xy 71.86676 -350.485202) (xy 71.830946 -350.454976)
			(xy 71.815452 -350.454976) (xy 71.815452 -350.437704) (xy 71.790306 -350.403922) (xy 71.767494 -350.372239)
			(xy 71.730756 -350.303357) (xy 71.717154 -350.266762) (xy 71.711533 -350.252094) (xy 71.69424 -350.225883)
			(xy 71.671066 -350.204694) (xy 71.643416 -350.18981) (xy 71.612967 -350.182136) (xy 71.581565 -350.182136)
			(xy 71.551116 -350.18981) (xy 71.523466 -350.204694) (xy 71.500292 -350.225883) (xy 71.482999 -350.252094)
			(xy 71.477378 -350.266762) (xy 71.463806 -350.30331) (xy 71.427065 -350.372071) (xy 71.404226 -350.403668)
			(xy 71.37908 -350.43745) (xy 71.37908 -350.454468) (xy 71.363586 -350.454468) (xy 71.327772 -350.484948)
			(xy 71.302595 -350.505801) (xy 71.247863 -350.541552) (xy 71.188998 -350.569991) (xy 71.126973 -350.590646)
			(xy 71.062811 -350.603177) (xy 70.997572 -350.607377) (xy 70.932333 -350.603177) (xy 70.868171 -350.590646)
			(xy 70.806146 -350.569991) (xy 70.747281 -350.541552) (xy 70.692549 -350.505801) (xy 70.667372 -350.484948)
			(xy 70.631558 -350.454468) (xy 70.616064 -350.454468) (xy 70.616064 -350.43745) (xy 70.590918 -350.403668)
			(xy 70.577659 -350.385621) (xy 70.554004 -350.347591) (xy 70.543674 -350.327722) (xy 70.536252 -350.314015)
			(xy 70.515881 -350.290433) (xy 70.490395 -350.272503) (xy 70.461318 -350.261297) (xy 70.43039 -350.257485)
			(xy 70.399462 -350.261297) (xy 70.370385 -350.272503) (xy 70.344899 -350.290433) (xy 70.324528 -350.314015)
			(xy 70.317106 -350.327722) (xy 70.30678 -350.347594) (xy 70.283125 -350.385623) (xy 70.269862 -350.403668)
			(xy 70.244716 -350.43745) (xy 70.244716 -350.454468) (xy 70.229222 -350.454468) (xy 70.193408 -350.484948)
			(xy 70.168231 -350.505801) (xy 70.113499 -350.541552) (xy 70.054634 -350.569991) (xy 69.992609 -350.590646)
			(xy 69.928447 -350.603177) (xy 69.863208 -350.607377) (xy 69.797969 -350.603177) (xy 69.733807 -350.590646)
			(xy 69.671782 -350.569991) (xy 69.612917 -350.541552) (xy 69.558185 -350.505801) (xy 69.533008 -350.484948)
			(xy 69.497194 -350.454468) (xy 69.4817 -350.454468) (xy 69.4817 -350.43745) (xy 69.456554 -350.403668)
			(xy 69.443116 -350.385332) (xy 69.419206 -350.346665) (xy 69.408802 -350.326452) (xy 69.4014 -350.312642)
			(xy 69.381008 -350.288865) (xy 69.355435 -350.270776) (xy 69.326224 -350.259467) (xy 69.295137 -350.25562)
			(xy 69.26405 -350.259467) (xy 69.234839 -350.270776) (xy 69.209266 -350.288865) (xy 69.188874 -350.312642)
			(xy 69.181472 -350.326452) (xy 69.171064 -350.346662) (xy 69.147151 -350.385327) (xy 69.13372 -350.403668)
			(xy 69.10832 -350.43745) (xy 69.10832 -350.454468) (xy 69.09308 -350.454468) (xy 69.057266 -350.484948)
			(xy 69.032089 -350.505801) (xy 68.977357 -350.541552) (xy 68.918492 -350.569991) (xy 68.856467 -350.590646)
			(xy 68.792305 -350.603177) (xy 68.727066 -350.607377) (xy 68.661827 -350.603177) (xy 68.597665 -350.590646)
			(xy 68.53564 -350.569991) (xy 68.476775 -350.541552) (xy 68.422043 -350.505801) (xy 68.396866 -350.484948)
			(xy 68.361052 -350.454468) (xy 68.345812 -350.454468) (xy 68.345812 -350.43745) (xy 68.320412 -350.403668)
			(xy 68.301196 -350.37717) (xy 68.268966 -350.3202) (xy 68.244324 -350.259561) (xy 68.227677 -350.196259)
			(xy 68.219303 -350.131342) (xy 68.218812 -350.098614) (xy 52.726336 -350.098614) (xy 52.726336 -351.591372)
			(xy 51.07432 -351.591372) (xy 51.07432 -349.939356) (xy 28.08351 -349.939356) (xy 28.08351 -350.805919)
			(xy 47.574698 -350.805919) (xy 47.574698 -350.724809) (xy 47.582648 -350.64409) (xy 47.598471 -350.564539)
			(xy 47.622016 -350.486923) (xy 47.653055 -350.411987) (xy 47.69129 -350.340455) (xy 47.736352 -350.273015)
			(xy 47.787807 -350.210316) (xy 47.84516 -350.152963) (xy 47.907859 -350.101508) (xy 47.975299 -350.056446)
			(xy 48.046831 -350.018211) (xy 48.121767 -349.987172) (xy 48.199383 -349.963627) (xy 48.278934 -349.947804)
			(xy 48.359653 -349.939854) (xy 48.440763 -349.939854) (xy 48.521482 -349.947804) (xy 48.601033 -349.963627)
			(xy 48.678649 -349.987172) (xy 48.753585 -350.018211) (xy 48.825117 -350.056446) (xy 48.892557 -350.101508)
			(xy 48.955256 -350.152963) (xy 49.012609 -350.210316) (xy 49.064064 -350.273015) (xy 49.109126 -350.340455)
			(xy 49.147361 -350.411987) (xy 49.1784 -350.486923) (xy 49.201945 -350.564539) (xy 49.217768 -350.64409)
			(xy 49.225718 -350.724809) (xy 49.226216 -350.765364) (xy 49.225718 -350.805919) (xy 49.217768 -350.886638)
			(xy 49.201945 -350.966189) (xy 49.1784 -351.043805) (xy 49.147361 -351.118741) (xy 49.109126 -351.190273)
			(xy 49.064064 -351.257713) (xy 49.012609 -351.320412) (xy 48.955256 -351.377765) (xy 48.892557 -351.42922)
			(xy 48.825117 -351.474282) (xy 48.753585 -351.512517) (xy 48.678649 -351.543556) (xy 48.601033 -351.567101)
			(xy 48.521482 -351.582924) (xy 48.440763 -351.590874) (xy 48.359653 -351.590874) (xy 48.278934 -351.582924)
			(xy 48.199383 -351.567101) (xy 48.121767 -351.543556) (xy 48.046831 -351.512517) (xy 47.975299 -351.474282)
			(xy 47.907859 -351.42922) (xy 47.84516 -351.377765) (xy 47.787807 -351.320412) (xy 47.736352 -351.257713)
			(xy 47.69129 -351.190273) (xy 47.653055 -351.118741) (xy 47.622016 -351.043805) (xy 47.598471 -350.966189)
			(xy 47.582648 -350.886638) (xy 47.574698 -350.805919) (xy 28.08351 -350.805919) (xy 28.08351 -352.845116)
			(xy 28.127452 -352.889058) (xy 28.127452 -354.132896) (xy 28.447746 -354.45319) (xy 31.82747 -354.45319)
			(xy 32.834072 -355.459792) (xy 39.906954 -355.459792) (xy 39.911025 -355.40417) (xy 39.923151 -355.349733)
			(xy 39.943074 -355.297642) (xy 39.97037 -355.249007) (xy 40.004456 -355.204864) (xy 40.044605 -355.166155)
			(xy 40.089963 -355.133704) (xy 40.139563 -355.108203) (xy 40.192347 -355.090196) (xy 40.24719 -355.080066)
			(xy 40.302924 -355.078029) (xy 40.358361 -355.084129) (xy 40.412318 -355.098235) (xy 40.463647 -355.120047)
			(xy 40.511253 -355.149101) (xy 40.554121 -355.184776) (xy 40.591338 -355.226313) (xy 40.622111 -355.272826)
			(xy 40.645783 -355.323323) (xy 40.661851 -355.37673) (xy 40.669971 -355.431906) (xy 40.67048 -355.459792)
			(xy 40.669971 -355.487678) (xy 40.661851 -355.542854) (xy 40.645783 -355.596261) (xy 40.622111 -355.646758)
			(xy 40.615068 -355.657404) (xy 41.28338 -355.657404) (xy 41.287451 -355.601782) (xy 41.299577 -355.547345)
			(xy 41.3195 -355.495254) (xy 41.346796 -355.446619) (xy 41.380882 -355.402476) (xy 41.421031 -355.363767)
			(xy 41.466389 -355.331316) (xy 41.515989 -355.305815) (xy 41.568773 -355.287808) (xy 41.623616 -355.277678)
			(xy 41.67935 -355.275641) (xy 41.734787 -355.281741) (xy 41.788744 -355.295847) (xy 41.840073 -355.317659)
			(xy 41.887679 -355.346713) (xy 41.921617 -355.374956) (xy 82.329526 -355.374956) (xy 82.333597 -355.319334)
			(xy 82.345723 -355.264897) (xy 82.365646 -355.212806) (xy 82.392942 -355.164171) (xy 82.427028 -355.120028)
			(xy 82.467177 -355.081319) (xy 82.512535 -355.048868) (xy 82.562135 -355.023367) (xy 82.614919 -355.00536)
			(xy 82.669762 -354.99523) (xy 82.725496 -354.993193) (xy 82.780933 -354.999293) (xy 82.83489 -355.013399)
			(xy 82.886219 -355.035211) (xy 82.933825 -355.064265) (xy 82.976693 -355.09994) (xy 83.01391 -355.141477)
			(xy 83.044683 -355.18799) (xy 83.068355 -355.238487) (xy 83.084423 -355.291894) (xy 83.092543 -355.34707)
			(xy 83.093052 -355.374956) (xy 83.092543 -355.402842) (xy 83.084423 -355.458018) (xy 83.068355 -355.511425)
			(xy 83.044683 -355.561922) (xy 83.01391 -355.608435) (xy 82.976693 -355.649972) (xy 82.933825 -355.685647)
			(xy 82.886219 -355.714701) (xy 82.83489 -355.736513) (xy 82.780933 -355.750619) (xy 82.725496 -355.756719)
			(xy 82.669762 -355.754682) (xy 82.614919 -355.744552) (xy 82.562135 -355.726545) (xy 82.512535 -355.701044)
			(xy 82.467177 -355.668593) (xy 82.427028 -355.629884) (xy 82.392942 -355.585741) (xy 82.365646 -355.537106)
			(xy 82.345723 -355.485015) (xy 82.333597 -355.430578) (xy 82.329526 -355.374956) (xy 41.921617 -355.374956)
			(xy 41.930547 -355.382388) (xy 41.967764 -355.423925) (xy 41.998537 -355.470438) (xy 42.022209 -355.520935)
			(xy 42.038277 -355.574342) (xy 42.046397 -355.629518) (xy 42.046906 -355.657404) (xy 42.046397 -355.68529)
			(xy 42.038277 -355.740466) (xy 42.022209 -355.793873) (xy 41.998537 -355.84437) (xy 41.967764 -355.890883)
			(xy 41.930547 -355.93242) (xy 41.925889 -355.936296) (xy 42.887136 -355.936296) (xy 42.891207 -355.880674)
			(xy 42.903333 -355.826237) (xy 42.923256 -355.774146) (xy 42.950552 -355.725511) (xy 42.984638 -355.681368)
			(xy 43.024787 -355.642659) (xy 43.070145 -355.610208) (xy 43.119745 -355.584707) (xy 43.172529 -355.5667)
			(xy 43.227372 -355.55657) (xy 43.283106 -355.554533) (xy 43.338543 -355.560633) (xy 43.3925 -355.574739)
			(xy 43.443829 -355.596551) (xy 43.491435 -355.625605) (xy 43.534303 -355.66128) (xy 43.57152 -355.702817)
			(xy 43.602293 -355.74933) (xy 43.625965 -355.799827) (xy 43.627285 -355.804216) (xy 84.618066 -355.804216)
			(xy 84.622137 -355.748594) (xy 84.634263 -355.694157) (xy 84.654186 -355.642066) (xy 84.681482 -355.593431)
			(xy 84.715568 -355.549288) (xy 84.755717 -355.510579) (xy 84.801075 -355.478128) (xy 84.850675 -355.452627)
			(xy 84.903459 -355.43462) (xy 84.958302 -355.42449) (xy 85.014036 -355.422453) (xy 85.069473 -355.428553)
			(xy 85.12343 -355.442659) (xy 85.174759 -355.464471) (xy 85.222365 -355.493525) (xy 85.265233 -355.5292)
			(xy 85.30245 -355.570737) (xy 85.333223 -355.61725) (xy 85.356895 -355.667747) (xy 85.372963 -355.721154)
			(xy 85.381083 -355.77633) (xy 85.381592 -355.804216) (xy 85.381083 -355.832102) (xy 85.372963 -355.887278)
			(xy 85.356895 -355.940685) (xy 85.333223 -355.991182) (xy 85.311392 -356.02418) (xy 87.027002 -356.02418)
			(xy 87.031073 -355.968558) (xy 87.043199 -355.914121) (xy 87.063122 -355.86203) (xy 87.090418 -355.813395)
			(xy 87.124504 -355.769252) (xy 87.164653 -355.730543) (xy 87.210011 -355.698092) (xy 87.259611 -355.672591)
			(xy 87.312395 -355.654584) (xy 87.367238 -355.644454) (xy 87.422972 -355.642417) (xy 87.478409 -355.648517)
			(xy 87.532366 -355.662623) (xy 87.583695 -355.684435) (xy 87.631301 -355.713489) (xy 87.674169 -355.749164)
			(xy 87.711386 -355.790701) (xy 87.742159 -355.837214) (xy 87.765831 -355.887711) (xy 87.781899 -355.941118)
			(xy 87.790019 -355.996294) (xy 87.790528 -356.02418) (xy 87.790019 -356.052066) (xy 87.781899 -356.107242)
			(xy 87.765831 -356.160649) (xy 87.742159 -356.211146) (xy 87.711386 -356.257659) (xy 87.674169 -356.299196)
			(xy 87.631301 -356.334871) (xy 87.583695 -356.363925) (xy 87.532366 -356.385737) (xy 87.478409 -356.399843)
			(xy 87.422972 -356.405943) (xy 87.367238 -356.403906) (xy 87.312395 -356.393776) (xy 87.259611 -356.375769)
			(xy 87.210011 -356.350268) (xy 87.164653 -356.317817) (xy 87.124504 -356.279108) (xy 87.090418 -356.234965)
			(xy 87.063122 -356.18633) (xy 87.043199 -356.134239) (xy 87.031073 -356.079802) (xy 87.027002 -356.02418)
			(xy 85.311392 -356.02418) (xy 85.30245 -356.037695) (xy 85.265233 -356.079232) (xy 85.222365 -356.114907)
			(xy 85.174759 -356.143961) (xy 85.12343 -356.165773) (xy 85.069473 -356.179879) (xy 85.014036 -356.185979)
			(xy 84.958302 -356.183942) (xy 84.903459 -356.173812) (xy 84.850675 -356.155805) (xy 84.801075 -356.130304)
			(xy 84.755717 -356.097853) (xy 84.715568 -356.059144) (xy 84.681482 -356.015001) (xy 84.654186 -355.966366)
			(xy 84.634263 -355.914275) (xy 84.622137 -355.859838) (xy 84.618066 -355.804216) (xy 43.627285 -355.804216)
			(xy 43.642033 -355.853234) (xy 43.650153 -355.90841) (xy 43.650662 -355.936296) (xy 43.650153 -355.964182)
			(xy 43.642033 -356.019358) (xy 43.625965 -356.072765) (xy 43.602293 -356.123262) (xy 43.57152 -356.169775)
			(xy 43.553816 -356.189534) (xy 44.343064 -356.189534) (xy 44.347135 -356.133912) (xy 44.359261 -356.079475)
			(xy 44.379184 -356.027384) (xy 44.40648 -355.978749) (xy 44.440566 -355.934606) (xy 44.480715 -355.895897)
			(xy 44.526073 -355.863446) (xy 44.575673 -355.837945) (xy 44.628457 -355.819938) (xy 44.6833 -355.809808)
			(xy 44.739034 -355.807771) (xy 44.794471 -355.813871) (xy 44.848428 -355.827977) (xy 44.899757 -355.849789)
			(xy 44.947363 -355.878843) (xy 44.990231 -355.914518) (xy 45.027448 -355.956055) (xy 45.058221 -356.002568)
			(xy 45.081893 -356.053065) (xy 45.097961 -356.106472) (xy 45.106081 -356.161648) (xy 45.10659 -356.189534)
			(xy 45.106081 -356.21742) (xy 45.097961 -356.272596) (xy 45.081893 -356.326003) (xy 45.058221 -356.3765)
			(xy 45.027448 -356.423013) (xy 44.990231 -356.46455) (xy 44.984353 -356.469442) (xy 79.420464 -356.469442)
			(xy 79.424535 -356.41382) (xy 79.436661 -356.359383) (xy 79.456584 -356.307292) (xy 79.48388 -356.258657)
			(xy 79.517966 -356.214514) (xy 79.558115 -356.175805) (xy 79.603473 -356.143354) (xy 79.653073 -356.117853)
			(xy 79.705857 -356.099846) (xy 79.7607 -356.089716) (xy 79.816434 -356.087679) (xy 79.871871 -356.093779)
			(xy 79.925828 -356.107885) (xy 79.977157 -356.129697) (xy 80.024763 -356.158751) (xy 80.067631 -356.194426)
			(xy 80.104848 -356.235963) (xy 80.135621 -356.282476) (xy 80.159293 -356.332973) (xy 80.175361 -356.38638)
			(xy 80.180856 -356.423722) (xy 88.693242 -356.423722) (xy 88.697313 -356.3681) (xy 88.709439 -356.313663)
			(xy 88.729362 -356.261572) (xy 88.756658 -356.212937) (xy 88.790744 -356.168794) (xy 88.830893 -356.130085)
			(xy 88.876251 -356.097634) (xy 88.925851 -356.072133) (xy 88.978635 -356.054126) (xy 89.033478 -356.043996)
			(xy 89.089212 -356.041959) (xy 89.144649 -356.048059) (xy 89.198606 -356.062165) (xy 89.249935 -356.083977)
			(xy 89.297541 -356.113031) (xy 89.340409 -356.148706) (xy 89.377626 -356.190243) (xy 89.408399 -356.236756)
			(xy 89.432071 -356.287253) (xy 89.448139 -356.34066) (xy 89.456259 -356.395836) (xy 89.456768 -356.423722)
			(xy 89.456259 -356.451608) (xy 89.448139 -356.506784) (xy 89.432071 -356.560191) (xy 89.408399 -356.610688)
			(xy 89.377626 -356.657201) (xy 89.340409 -356.698738) (xy 89.297541 -356.734413) (xy 89.249935 -356.763467)
			(xy 89.198606 -356.785279) (xy 89.144649 -356.799385) (xy 89.089212 -356.805485) (xy 89.033478 -356.803448)
			(xy 88.978635 -356.793318) (xy 88.925851 -356.775311) (xy 88.876251 -356.74981) (xy 88.830893 -356.717359)
			(xy 88.790744 -356.67865) (xy 88.756658 -356.634507) (xy 88.729362 -356.585872) (xy 88.709439 -356.533781)
			(xy 88.697313 -356.479344) (xy 88.693242 -356.423722) (xy 80.180856 -356.423722) (xy 80.183481 -356.441556)
			(xy 80.18399 -356.469442) (xy 80.183481 -356.497328) (xy 80.175361 -356.552504) (xy 80.159293 -356.605911)
			(xy 80.135621 -356.656408) (xy 80.104848 -356.702921) (xy 80.067631 -356.744458) (xy 80.024763 -356.780133)
			(xy 79.977157 -356.809187) (xy 79.925828 -356.830999) (xy 79.871871 -356.845105) (xy 79.816434 -356.851205)
			(xy 79.7607 -356.849168) (xy 79.705857 -356.839038) (xy 79.653073 -356.821031) (xy 79.603473 -356.79553)
			(xy 79.558115 -356.763079) (xy 79.517966 -356.72437) (xy 79.48388 -356.680227) (xy 79.456584 -356.631592)
			(xy 79.436661 -356.579501) (xy 79.424535 -356.525064) (xy 79.420464 -356.469442) (xy 44.984353 -356.469442)
			(xy 44.947363 -356.500225) (xy 44.899757 -356.529279) (xy 44.848428 -356.551091) (xy 44.794471 -356.565197)
			(xy 44.739034 -356.571297) (xy 44.6833 -356.56926) (xy 44.628457 -356.55913) (xy 44.575673 -356.541123)
			(xy 44.526073 -356.515622) (xy 44.480715 -356.483171) (xy 44.440566 -356.444462) (xy 44.40648 -356.400319)
			(xy 44.379184 -356.351684) (xy 44.359261 -356.299593) (xy 44.347135 -356.245156) (xy 44.343064 -356.189534)
			(xy 43.553816 -356.189534) (xy 43.534303 -356.211312) (xy 43.491435 -356.246987) (xy 43.443829 -356.276041)
			(xy 43.3925 -356.297853) (xy 43.338543 -356.311959) (xy 43.283106 -356.318059) (xy 43.227372 -356.316022)
			(xy 43.172529 -356.305892) (xy 43.119745 -356.287885) (xy 43.070145 -356.262384) (xy 43.024787 -356.229933)
			(xy 42.984638 -356.191224) (xy 42.950552 -356.147081) (xy 42.923256 -356.098446) (xy 42.903333 -356.046355)
			(xy 42.891207 -355.991918) (xy 42.887136 -355.936296) (xy 41.925889 -355.936296) (xy 41.887679 -355.968095)
			(xy 41.840073 -355.997149) (xy 41.788744 -356.018961) (xy 41.734787 -356.033067) (xy 41.67935 -356.039167)
			(xy 41.623616 -356.03713) (xy 41.568773 -356.027) (xy 41.515989 -356.008993) (xy 41.466389 -355.983492)
			(xy 41.421031 -355.951041) (xy 41.380882 -355.912332) (xy 41.346796 -355.868189) (xy 41.3195 -355.819554)
			(xy 41.299577 -355.767463) (xy 41.287451 -355.713026) (xy 41.28338 -355.657404) (xy 40.615068 -355.657404)
			(xy 40.591338 -355.693271) (xy 40.554121 -355.734808) (xy 40.511253 -355.770483) (xy 40.463647 -355.799537)
			(xy 40.412318 -355.821349) (xy 40.358361 -355.835455) (xy 40.302924 -355.841555) (xy 40.24719 -355.839518)
			(xy 40.192347 -355.829388) (xy 40.139563 -355.811381) (xy 40.089963 -355.78588) (xy 40.044605 -355.753429)
			(xy 40.004456 -355.71472) (xy 39.97037 -355.670577) (xy 39.943074 -355.621942) (xy 39.923151 -355.569851)
			(xy 39.911025 -355.515414) (xy 39.906954 -355.459792) (xy 32.834072 -355.459792) (xy 34.1757 -356.80142)
			(xy 34.1757 -358.233488) (xy 34.599874 -358.233488) (xy 34.599874 -358.146588) (xy 34.607892 -358.060059)
			(xy 34.62386 -357.974639) (xy 34.647641 -357.891057) (xy 34.679033 -357.810025) (xy 34.717767 -357.732236)
			(xy 34.763514 -357.658352) (xy 34.815883 -357.589005) (xy 34.874427 -357.524785) (xy 34.938647 -357.466241)
			(xy 35.007994 -357.413872) (xy 35.081878 -357.368125) (xy 35.159667 -357.329391) (xy 35.240699 -357.297999)
			(xy 35.324281 -357.274218) (xy 35.409701 -357.25825) (xy 35.49623 -357.250232) (xy 35.58313 -357.250232)
			(xy 35.669659 -357.25825) (xy 35.755079 -357.274218) (xy 35.838661 -357.297999) (xy 35.919693 -357.329391)
			(xy 35.997482 -357.368125) (xy 36.071366 -357.413872) (xy 36.140713 -357.466241) (xy 36.204933 -357.524785)
			(xy 36.263477 -357.589005) (xy 36.315846 -357.658352) (xy 36.361593 -357.732236) (xy 36.400327 -357.810025)
			(xy 36.431719 -357.891057) (xy 36.4555 -357.974639) (xy 36.471468 -358.060059) (xy 36.479486 -358.146588)
			(xy 36.479988 -358.190038) (xy 36.479486 -358.233488) (xy 36.471468 -358.320017) (xy 36.4555 -358.405437)
			(xy 36.431719 -358.489019) (xy 36.400327 -358.570051) (xy 36.361593 -358.64784) (xy 36.315846 -358.721724)
			(xy 36.263477 -358.791071) (xy 36.204933 -358.855291) (xy 36.140713 -358.913835) (xy 36.071366 -358.966204)
			(xy 35.997482 -359.011951) (xy 35.919693 -359.050685) (xy 35.838661 -359.082077) (xy 35.755079 -359.105858)
			(xy 35.669659 -359.121826) (xy 35.58313 -359.129844) (xy 35.49623 -359.129844) (xy 35.409701 -359.121826)
			(xy 35.324281 -359.105858) (xy 35.240699 -359.082077) (xy 35.159667 -359.050685) (xy 35.081878 -359.011951)
			(xy 35.007994 -358.966204) (xy 34.938647 -358.913835) (xy 34.874427 -358.855291) (xy 34.815883 -358.791071)
			(xy 34.763514 -358.721724) (xy 34.717767 -358.64784) (xy 34.679033 -358.570051) (xy 34.647641 -358.489019)
			(xy 34.62386 -358.405437) (xy 34.607892 -358.320017) (xy 34.599874 -358.233488) (xy 34.1757 -358.233488)
			(xy 34.1757 -360.773488) (xy 34.599874 -360.773488) (xy 34.599874 -360.686588) (xy 34.607892 -360.600059)
			(xy 34.62386 -360.514639) (xy 34.647641 -360.431057) (xy 34.679033 -360.350025) (xy 34.717767 -360.272236)
			(xy 34.763514 -360.198352) (xy 34.815883 -360.129005) (xy 34.874427 -360.064785) (xy 34.938647 -360.006241)
			(xy 35.007994 -359.953872) (xy 35.081878 -359.908125) (xy 35.159667 -359.869391) (xy 35.240699 -359.837999)
			(xy 35.324281 -359.814218) (xy 35.409701 -359.79825) (xy 35.49623 -359.790232) (xy 35.58313 -359.790232)
			(xy 35.669659 -359.79825) (xy 35.755079 -359.814218) (xy 35.838661 -359.837999) (xy 35.919693 -359.869391)
			(xy 35.997482 -359.908125) (xy 36.071366 -359.953872) (xy 36.140713 -360.006241) (xy 36.204933 -360.064785)
			(xy 36.263477 -360.129005) (xy 36.315846 -360.198352) (xy 36.361593 -360.272236) (xy 36.400327 -360.350025)
			(xy 36.431719 -360.431057) (xy 36.4555 -360.514639) (xy 36.471468 -360.600059) (xy 36.479486 -360.686588)
			(xy 36.479988 -360.730038) (xy 36.479486 -360.773488) (xy 36.471468 -360.860017) (xy 36.4555 -360.945437)
			(xy 36.431719 -361.029019) (xy 36.400327 -361.110051) (xy 36.361593 -361.18784) (xy 36.315846 -361.261724)
			(xy 36.263477 -361.331071) (xy 36.204933 -361.395291) (xy 36.140713 -361.453835) (xy 36.071366 -361.506204)
			(xy 35.997482 -361.551951) (xy 35.919693 -361.590685) (xy 35.838661 -361.622077) (xy 35.755079 -361.645858)
			(xy 35.669659 -361.661826) (xy 35.58313 -361.669844) (xy 35.49623 -361.669844) (xy 35.409701 -361.661826)
			(xy 35.324281 -361.645858) (xy 35.240699 -361.622077) (xy 35.159667 -361.590685) (xy 35.081878 -361.551951)
			(xy 35.007994 -361.506204) (xy 34.938647 -361.453835) (xy 34.874427 -361.395291) (xy 34.815883 -361.331071)
			(xy 34.763514 -361.261724) (xy 34.717767 -361.18784) (xy 34.679033 -361.110051) (xy 34.647641 -361.029019)
			(xy 34.62386 -360.945437) (xy 34.607892 -360.860017) (xy 34.599874 -360.773488) (xy 34.1757 -360.773488)
			(xy 34.1757 -363.313488) (xy 34.599874 -363.313488) (xy 34.599874 -363.226588) (xy 34.607892 -363.140059)
			(xy 34.62386 -363.054639) (xy 34.647641 -362.971057) (xy 34.679033 -362.890025) (xy 34.717767 -362.812236)
			(xy 34.763514 -362.738352) (xy 34.815883 -362.669005) (xy 34.874427 -362.604785) (xy 34.938647 -362.546241)
			(xy 35.007994 -362.493872) (xy 35.081878 -362.448125) (xy 35.159667 -362.409391) (xy 35.240699 -362.377999)
			(xy 35.324281 -362.354218) (xy 35.409701 -362.33825) (xy 35.49623 -362.330232) (xy 35.58313 -362.330232)
			(xy 35.669659 -362.33825) (xy 35.755079 -362.354218) (xy 35.838661 -362.377999) (xy 35.919693 -362.409391)
			(xy 35.997482 -362.448125) (xy 36.071366 -362.493872) (xy 36.092815 -362.51007) (xy 39.818564 -362.51007)
			(xy 39.819058 -362.452661) (xy 39.826902 -362.338113) (xy 39.842544 -362.224366) (xy 39.865911 -362.111952)
			(xy 39.896896 -362.001394) (xy 39.935352 -361.893209) (xy 39.981101 -361.7879) (xy 40.03393 -361.685958)
			(xy 40.093592 -361.587859) (xy 40.159809 -361.49406) (xy 40.232272 -361.404998) (xy 40.310645 -361.321089)
			(xy 40.39456 -361.242723) (xy 40.483627 -361.170266) (xy 40.577431 -361.104056) (xy 40.675535 -361.044402)
			(xy 40.777481 -360.991581) (xy 40.882793 -360.945839) (xy 40.990981 -360.907391) (xy 41.101541 -360.876415)
			(xy 41.213957 -360.853056) (xy 41.327705 -360.837423) (xy 41.442254 -360.829588) (xy 41.557072 -360.829588)
			(xy 41.671621 -360.837423) (xy 41.785369 -360.853056) (xy 41.897785 -360.876415) (xy 42.008345 -360.907391)
			(xy 42.116533 -360.945839) (xy 42.221845 -360.991581) (xy 42.323791 -361.044402) (xy 42.421895 -361.104056)
			(xy 42.501239 -361.16006) (xy 43.327577 -361.16006) (xy 43.331612 -361.084356) (xy 43.343671 -361.009511)
			(xy 43.363617 -360.93637) (xy 43.391224 -360.865765) (xy 43.42618 -360.798494) (xy 43.468088 -360.735319)
			(xy 43.516474 -360.676957) (xy 43.57079 -360.624069) (xy 43.630419 -360.577254) (xy 43.694687 -360.537042)
			(xy 43.762864 -360.50389) (xy 43.83418 -360.478172) (xy 43.907825 -360.46018) (xy 43.982965 -360.450118)
			(xy 44.058749 -360.448099) (xy 44.134319 -360.454148) (xy 44.208817 -360.468195) (xy 44.2814 -360.490081)
			(xy 44.351246 -360.519558) (xy 44.417563 -360.556293) (xy 44.479599 -360.599868) (xy 44.536652 -360.64979)
			(xy 44.588076 -360.705494) (xy 44.633287 -360.766349) (xy 44.671774 -360.831664) (xy 44.7031 -360.9007)
			(xy 44.72691 -360.972675) (xy 44.742935 -361.046773) (xy 44.750994 -361.122154) (xy 44.751498 -361.16006)
			(xy 45.867577 -361.16006) (xy 45.871612 -361.084356) (xy 45.883671 -361.009511) (xy 45.903617 -360.93637)
			(xy 45.931224 -360.865765) (xy 45.96618 -360.798494) (xy 46.008088 -360.735319) (xy 46.056474 -360.676957)
			(xy 46.11079 -360.624069) (xy 46.170419 -360.577254) (xy 46.234687 -360.537042) (xy 46.302864 -360.50389)
			(xy 46.37418 -360.478172) (xy 46.447825 -360.46018) (xy 46.522965 -360.450118) (xy 46.598749 -360.448099)
			(xy 46.674319 -360.454148) (xy 46.748817 -360.468195) (xy 46.8214 -360.490081) (xy 46.891246 -360.519558)
			(xy 46.957563 -360.556293) (xy 47.019599 -360.599868) (xy 47.076652 -360.64979) (xy 47.128076 -360.705494)
			(xy 47.173287 -360.766349) (xy 47.211774 -360.831664) (xy 47.2431 -360.9007) (xy 47.26691 -360.972675)
			(xy 47.282935 -361.046773) (xy 47.290994 -361.122154) (xy 47.291498 -361.16006) (xy 48.407577 -361.16006)
			(xy 48.411612 -361.084356) (xy 48.423671 -361.009511) (xy 48.443617 -360.93637) (xy 48.471224 -360.865765)
			(xy 48.50618 -360.798494) (xy 48.548088 -360.735319) (xy 48.596474 -360.676957) (xy 48.65079 -360.624069)
			(xy 48.710419 -360.577254) (xy 48.774687 -360.537042) (xy 48.842864 -360.50389) (xy 48.91418 -360.478172)
			(xy 48.987825 -360.46018) (xy 49.062965 -360.450118) (xy 49.138749 -360.448099) (xy 49.214319 -360.454148)
			(xy 49.288817 -360.468195) (xy 49.3614 -360.490081) (xy 49.431246 -360.519558) (xy 49.497563 -360.556293)
			(xy 49.559599 -360.599868) (xy 49.616652 -360.64979) (xy 49.668076 -360.705494) (xy 49.713287 -360.766349)
			(xy 49.751774 -360.831664) (xy 49.7831 -360.9007) (xy 49.80691 -360.972675) (xy 49.822935 -361.046773)
			(xy 49.830994 -361.122154) (xy 49.831498 -361.16006) (xy 50.947577 -361.16006) (xy 50.951612 -361.084356)
			(xy 50.963671 -361.009511) (xy 50.983617 -360.93637) (xy 51.011224 -360.865765) (xy 51.04618 -360.798494)
			(xy 51.088088 -360.735319) (xy 51.136474 -360.676957) (xy 51.19079 -360.624069) (xy 51.250419 -360.577254)
			(xy 51.314687 -360.537042) (xy 51.382864 -360.50389) (xy 51.45418 -360.478172) (xy 51.527825 -360.46018)
			(xy 51.602965 -360.450118) (xy 51.678749 -360.448099) (xy 51.754319 -360.454148) (xy 51.828817 -360.468195)
			(xy 51.9014 -360.490081) (xy 51.971246 -360.519558) (xy 52.037563 -360.556293) (xy 52.099599 -360.599868)
			(xy 52.156652 -360.64979) (xy 52.208076 -360.705494) (xy 52.253287 -360.766349) (xy 52.291774 -360.831664)
			(xy 52.3231 -360.9007) (xy 52.34691 -360.972675) (xy 52.362935 -361.046773) (xy 52.370994 -361.122154)
			(xy 52.371498 -361.16006) (xy 53.487577 -361.16006) (xy 53.491612 -361.084356) (xy 53.503671 -361.009511)
			(xy 53.523617 -360.93637) (xy 53.551224 -360.865765) (xy 53.58618 -360.798494) (xy 53.628088 -360.735319)
			(xy 53.676474 -360.676957) (xy 53.73079 -360.624069) (xy 53.790419 -360.577254) (xy 53.854687 -360.537042)
			(xy 53.922864 -360.50389) (xy 53.99418 -360.478172) (xy 54.067825 -360.46018) (xy 54.142965 -360.450118)
			(xy 54.218749 -360.448099) (xy 54.294319 -360.454148) (xy 54.368817 -360.468195) (xy 54.4414 -360.490081)
			(xy 54.511246 -360.519558) (xy 54.577563 -360.556293) (xy 54.639599 -360.599868) (xy 54.696652 -360.64979)
			(xy 54.748076 -360.705494) (xy 54.793287 -360.766349) (xy 54.831774 -360.831664) (xy 54.8631 -360.9007)
			(xy 54.88691 -360.972675) (xy 54.902935 -361.046773) (xy 54.910994 -361.122154) (xy 54.911498 -361.16006)
			(xy 56.027577 -361.16006) (xy 56.031612 -361.084356) (xy 56.043671 -361.009511) (xy 56.063617 -360.93637)
			(xy 56.091224 -360.865765) (xy 56.12618 -360.798494) (xy 56.168088 -360.735319) (xy 56.216474 -360.676957)
			(xy 56.27079 -360.624069) (xy 56.330419 -360.577254) (xy 56.394687 -360.537042) (xy 56.462864 -360.50389)
			(xy 56.53418 -360.478172) (xy 56.607825 -360.46018) (xy 56.682965 -360.450118) (xy 56.758749 -360.448099)
			(xy 56.834319 -360.454148) (xy 56.908817 -360.468195) (xy 56.9814 -360.490081) (xy 57.051246 -360.519558)
			(xy 57.117563 -360.556293) (xy 57.179599 -360.599868) (xy 57.236652 -360.64979) (xy 57.288076 -360.705494)
			(xy 57.333287 -360.766349) (xy 57.371774 -360.831664) (xy 57.4031 -360.9007) (xy 57.42691 -360.972675)
			(xy 57.442935 -361.046773) (xy 57.450994 -361.122154) (xy 57.451498 -361.16006) (xy 58.567577 -361.16006)
			(xy 58.571612 -361.084356) (xy 58.583671 -361.009511) (xy 58.603617 -360.93637) (xy 58.631224 -360.865765)
			(xy 58.66618 -360.798494) (xy 58.708088 -360.735319) (xy 58.756474 -360.676957) (xy 58.81079 -360.624069)
			(xy 58.870419 -360.577254) (xy 58.934687 -360.537042) (xy 59.002864 -360.50389) (xy 59.07418 -360.478172)
			(xy 59.147825 -360.46018) (xy 59.222965 -360.450118) (xy 59.298749 -360.448099) (xy 59.374319 -360.454148)
			(xy 59.448817 -360.468195) (xy 59.5214 -360.490081) (xy 59.591246 -360.519558) (xy 59.657563 -360.556293)
			(xy 59.719599 -360.599868) (xy 59.776652 -360.64979) (xy 59.828076 -360.705494) (xy 59.873287 -360.766349)
			(xy 59.911774 -360.831664) (xy 59.9431 -360.9007) (xy 59.96691 -360.972675) (xy 59.982935 -361.046773)
			(xy 59.990994 -361.122154) (xy 59.991498 -361.16006) (xy 61.107577 -361.16006) (xy 61.111612 -361.084356)
			(xy 61.123671 -361.009511) (xy 61.143617 -360.93637) (xy 61.171224 -360.865765) (xy 61.20618 -360.798494)
			(xy 61.248088 -360.735319) (xy 61.296474 -360.676957) (xy 61.35079 -360.624069) (xy 61.410419 -360.577254)
			(xy 61.474687 -360.537042) (xy 61.542864 -360.50389) (xy 61.61418 -360.478172) (xy 61.687825 -360.46018)
			(xy 61.762965 -360.450118) (xy 61.838749 -360.448099) (xy 61.914319 -360.454148) (xy 61.988817 -360.468195)
			(xy 62.0614 -360.490081) (xy 62.131246 -360.519558) (xy 62.197563 -360.556293) (xy 62.259599 -360.599868)
			(xy 62.265544 -360.60507) (xy 86.197697 -360.60507) (xy 86.201732 -360.529366) (xy 86.213791 -360.454521)
			(xy 86.233737 -360.38138) (xy 86.261344 -360.310775) (xy 86.2963 -360.243504) (xy 86.338208 -360.180329)
			(xy 86.386594 -360.121967) (xy 86.44091 -360.069079) (xy 86.500539 -360.022264) (xy 86.564807 -359.982052)
			(xy 86.632984 -359.9489) (xy 86.7043 -359.923182) (xy 86.777945 -359.90519) (xy 86.853085 -359.895128)
			(xy 86.928869 -359.893109) (xy 87.004439 -359.899158) (xy 87.078937 -359.913205) (xy 87.15152 -359.935091)
			(xy 87.221366 -359.964568) (xy 87.287683 -360.001303) (xy 87.349719 -360.044878) (xy 87.406772 -360.0948)
			(xy 87.458196 -360.150504) (xy 87.503407 -360.211359) (xy 87.541894 -360.276674) (xy 87.57322 -360.34571)
			(xy 87.59703 -360.417685) (xy 87.613055 -360.491783) (xy 87.621114 -360.567164) (xy 87.621618 -360.60507)
			(xy 88.737697 -360.60507) (xy 88.741732 -360.529366) (xy 88.753791 -360.454521) (xy 88.773737 -360.38138)
			(xy 88.801344 -360.310775) (xy 88.8363 -360.243504) (xy 88.878208 -360.180329) (xy 88.926594 -360.121967)
			(xy 88.98091 -360.069079) (xy 89.040539 -360.022264) (xy 89.104807 -359.982052) (xy 89.172984 -359.9489)
			(xy 89.2443 -359.923182) (xy 89.317945 -359.90519) (xy 89.393085 -359.895128) (xy 89.468869 -359.893109)
			(xy 89.544439 -359.899158) (xy 89.618937 -359.913205) (xy 89.69152 -359.935091) (xy 89.761366 -359.964568)
			(xy 89.827683 -360.001303) (xy 89.889719 -360.044878) (xy 89.946772 -360.0948) (xy 89.998196 -360.150504)
			(xy 90.043407 -360.211359) (xy 90.081894 -360.276674) (xy 90.11322 -360.34571) (xy 90.13703 -360.417685)
			(xy 90.153055 -360.491783) (xy 90.161114 -360.567164) (xy 90.161618 -360.60507) (xy 91.277697 -360.60507)
			(xy 91.281732 -360.529366) (xy 91.293791 -360.454521) (xy 91.313737 -360.38138) (xy 91.341344 -360.310775)
			(xy 91.3763 -360.243504) (xy 91.418208 -360.180329) (xy 91.466594 -360.121967) (xy 91.52091 -360.069079)
			(xy 91.580539 -360.022264) (xy 91.644807 -359.982052) (xy 91.712984 -359.9489) (xy 91.7843 -359.923182)
			(xy 91.857945 -359.90519) (xy 91.933085 -359.895128) (xy 92.008869 -359.893109) (xy 92.084439 -359.899158)
			(xy 92.158937 -359.913205) (xy 92.23152 -359.935091) (xy 92.301366 -359.964568) (xy 92.367683 -360.001303)
			(xy 92.429719 -360.044878) (xy 92.486772 -360.0948) (xy 92.538196 -360.150504) (xy 92.583407 -360.211359)
			(xy 92.621894 -360.276674) (xy 92.65322 -360.34571) (xy 92.67703 -360.417685) (xy 92.693055 -360.491783)
			(xy 92.701114 -360.567164) (xy 92.701618 -360.60507) (xy 92.701114 -360.642976) (xy 92.693055 -360.718357)
			(xy 92.67703 -360.792455) (xy 92.65322 -360.86443) (xy 92.621894 -360.933466) (xy 92.583407 -360.998781)
			(xy 92.538196 -361.059636) (xy 92.486772 -361.11534) (xy 92.429719 -361.165262) (xy 92.367683 -361.208837)
			(xy 92.301366 -361.245572) (xy 92.23152 -361.275049) (xy 92.158937 -361.296935) (xy 92.084439 -361.310982)
			(xy 92.008869 -361.317031) (xy 91.933085 -361.315012) (xy 91.857945 -361.30495) (xy 91.7843 -361.286958)
			(xy 91.712984 -361.26124) (xy 91.644807 -361.228088) (xy 91.580539 -361.187876) (xy 91.52091 -361.141061)
			(xy 91.466594 -361.088173) (xy 91.418208 -361.029811) (xy 91.3763 -360.966636) (xy 91.341344 -360.899365)
			(xy 91.313737 -360.82876) (xy 91.293791 -360.755619) (xy 91.281732 -360.680774) (xy 91.277697 -360.60507)
			(xy 90.161618 -360.60507) (xy 90.161114 -360.642976) (xy 90.153055 -360.718357) (xy 90.13703 -360.792455)
			(xy 90.11322 -360.86443) (xy 90.081894 -360.933466) (xy 90.043407 -360.998781) (xy 89.998196 -361.059636)
			(xy 89.946772 -361.11534) (xy 89.889719 -361.165262) (xy 89.827683 -361.208837) (xy 89.761366 -361.245572)
			(xy 89.69152 -361.275049) (xy 89.618937 -361.296935) (xy 89.544439 -361.310982) (xy 89.468869 -361.317031)
			(xy 89.393085 -361.315012) (xy 89.317945 -361.30495) (xy 89.2443 -361.286958) (xy 89.172984 -361.26124)
			(xy 89.104807 -361.228088) (xy 89.040539 -361.187876) (xy 88.98091 -361.141061) (xy 88.926594 -361.088173)
			(xy 88.878208 -361.029811) (xy 88.8363 -360.966636) (xy 88.801344 -360.899365) (xy 88.773737 -360.82876)
			(xy 88.753791 -360.755619) (xy 88.741732 -360.680774) (xy 88.737697 -360.60507) (xy 87.621618 -360.60507)
			(xy 87.621114 -360.642976) (xy 87.613055 -360.718357) (xy 87.59703 -360.792455) (xy 87.57322 -360.86443)
			(xy 87.541894 -360.933466) (xy 87.503407 -360.998781) (xy 87.458196 -361.059636) (xy 87.406772 -361.11534)
			(xy 87.349719 -361.165262) (xy 87.287683 -361.208837) (xy 87.221366 -361.245572) (xy 87.15152 -361.275049)
			(xy 87.078937 -361.296935) (xy 87.004439 -361.310982) (xy 86.928869 -361.317031) (xy 86.853085 -361.315012)
			(xy 86.777945 -361.30495) (xy 86.7043 -361.286958) (xy 86.632984 -361.26124) (xy 86.564807 -361.228088)
			(xy 86.500539 -361.187876) (xy 86.44091 -361.141061) (xy 86.386594 -361.088173) (xy 86.338208 -361.029811)
			(xy 86.2963 -360.966636) (xy 86.261344 -360.899365) (xy 86.233737 -360.82876) (xy 86.213791 -360.755619)
			(xy 86.201732 -360.680774) (xy 86.197697 -360.60507) (xy 62.265544 -360.60507) (xy 62.316652 -360.64979)
			(xy 62.368076 -360.705494) (xy 62.413287 -360.766349) (xy 62.451774 -360.831664) (xy 62.4831 -360.9007)
			(xy 62.50691 -360.972675) (xy 62.522935 -361.046773) (xy 62.530994 -361.122154) (xy 62.531498 -361.16006)
			(xy 62.530994 -361.197966) (xy 62.522935 -361.273347) (xy 62.50691 -361.347445) (xy 62.4831 -361.41942)
			(xy 62.451774 -361.488456) (xy 62.413287 -361.553771) (xy 62.368076 -361.614626) (xy 62.316652 -361.67033)
			(xy 62.259599 -361.720252) (xy 62.197563 -361.763827) (xy 62.131246 -361.800562) (xy 62.0614 -361.830039)
			(xy 61.988817 -361.851925) (xy 61.914319 -361.865972) (xy 61.838749 -361.872021) (xy 61.762965 -361.870002)
			(xy 61.687825 -361.85994) (xy 61.61418 -361.841948) (xy 61.542864 -361.81623) (xy 61.474687 -361.783078)
			(xy 61.410419 -361.742866) (xy 61.35079 -361.696051) (xy 61.296474 -361.643163) (xy 61.248088 -361.584801)
			(xy 61.20618 -361.521626) (xy 61.171224 -361.454355) (xy 61.143617 -361.38375) (xy 61.123671 -361.310609)
			(xy 61.111612 -361.235764) (xy 61.107577 -361.16006) (xy 59.991498 -361.16006) (xy 59.990994 -361.197966)
			(xy 59.982935 -361.273347) (xy 59.96691 -361.347445) (xy 59.9431 -361.41942) (xy 59.911774 -361.488456)
			(xy 59.873287 -361.553771) (xy 59.828076 -361.614626) (xy 59.776652 -361.67033) (xy 59.719599 -361.720252)
			(xy 59.657563 -361.763827) (xy 59.591246 -361.800562) (xy 59.5214 -361.830039) (xy 59.448817 -361.851925)
			(xy 59.374319 -361.865972) (xy 59.298749 -361.872021) (xy 59.222965 -361.870002) (xy 59.147825 -361.85994)
			(xy 59.07418 -361.841948) (xy 59.002864 -361.81623) (xy 58.934687 -361.783078) (xy 58.870419 -361.742866)
			(xy 58.81079 -361.696051) (xy 58.756474 -361.643163) (xy 58.708088 -361.584801) (xy 58.66618 -361.521626)
			(xy 58.631224 -361.454355) (xy 58.603617 -361.38375) (xy 58.583671 -361.310609) (xy 58.571612 -361.235764)
			(xy 58.567577 -361.16006) (xy 57.451498 -361.16006) (xy 57.450994 -361.197966) (xy 57.442935 -361.273347)
			(xy 57.42691 -361.347445) (xy 57.4031 -361.41942) (xy 57.371774 -361.488456) (xy 57.333287 -361.553771)
			(xy 57.288076 -361.614626) (xy 57.236652 -361.67033) (xy 57.179599 -361.720252) (xy 57.117563 -361.763827)
			(xy 57.051246 -361.800562) (xy 56.9814 -361.830039) (xy 56.908817 -361.851925) (xy 56.834319 -361.865972)
			(xy 56.758749 -361.872021) (xy 56.682965 -361.870002) (xy 56.607825 -361.85994) (xy 56.53418 -361.841948)
			(xy 56.462864 -361.81623) (xy 56.394687 -361.783078) (xy 56.330419 -361.742866) (xy 56.27079 -361.696051)
			(xy 56.216474 -361.643163) (xy 56.168088 -361.584801) (xy 56.12618 -361.521626) (xy 56.091224 -361.454355)
			(xy 56.063617 -361.38375) (xy 56.043671 -361.310609) (xy 56.031612 -361.235764) (xy 56.027577 -361.16006)
			(xy 54.911498 -361.16006) (xy 54.910994 -361.197966) (xy 54.902935 -361.273347) (xy 54.88691 -361.347445)
			(xy 54.8631 -361.41942) (xy 54.831774 -361.488456) (xy 54.793287 -361.553771) (xy 54.748076 -361.614626)
			(xy 54.696652 -361.67033) (xy 54.639599 -361.720252) (xy 54.577563 -361.763827) (xy 54.511246 -361.800562)
			(xy 54.4414 -361.830039) (xy 54.368817 -361.851925) (xy 54.294319 -361.865972) (xy 54.218749 -361.872021)
			(xy 54.142965 -361.870002) (xy 54.067825 -361.85994) (xy 53.99418 -361.841948) (xy 53.922864 -361.81623)
			(xy 53.854687 -361.783078) (xy 53.790419 -361.742866) (xy 53.73079 -361.696051) (xy 53.676474 -361.643163)
			(xy 53.628088 -361.584801) (xy 53.58618 -361.521626) (xy 53.551224 -361.454355) (xy 53.523617 -361.38375)
			(xy 53.503671 -361.310609) (xy 53.491612 -361.235764) (xy 53.487577 -361.16006) (xy 52.371498 -361.16006)
			(xy 52.370994 -361.197966) (xy 52.362935 -361.273347) (xy 52.34691 -361.347445) (xy 52.3231 -361.41942)
			(xy 52.291774 -361.488456) (xy 52.253287 -361.553771) (xy 52.208076 -361.614626) (xy 52.156652 -361.67033)
			(xy 52.099599 -361.720252) (xy 52.037563 -361.763827) (xy 51.971246 -361.800562) (xy 51.9014 -361.830039)
			(xy 51.828817 -361.851925) (xy 51.754319 -361.865972) (xy 51.678749 -361.872021) (xy 51.602965 -361.870002)
			(xy 51.527825 -361.85994) (xy 51.45418 -361.841948) (xy 51.382864 -361.81623) (xy 51.314687 -361.783078)
			(xy 51.250419 -361.742866) (xy 51.19079 -361.696051) (xy 51.136474 -361.643163) (xy 51.088088 -361.584801)
			(xy 51.04618 -361.521626) (xy 51.011224 -361.454355) (xy 50.983617 -361.38375) (xy 50.963671 -361.310609)
			(xy 50.951612 -361.235764) (xy 50.947577 -361.16006) (xy 49.831498 -361.16006) (xy 49.830994 -361.197966)
			(xy 49.822935 -361.273347) (xy 49.80691 -361.347445) (xy 49.7831 -361.41942) (xy 49.751774 -361.488456)
			(xy 49.713287 -361.553771) (xy 49.668076 -361.614626) (xy 49.616652 -361.67033) (xy 49.559599 -361.720252)
			(xy 49.497563 -361.763827) (xy 49.431246 -361.800562) (xy 49.3614 -361.830039) (xy 49.288817 -361.851925)
			(xy 49.214319 -361.865972) (xy 49.138749 -361.872021) (xy 49.062965 -361.870002) (xy 48.987825 -361.85994)
			(xy 48.91418 -361.841948) (xy 48.842864 -361.81623) (xy 48.774687 -361.783078) (xy 48.710419 -361.742866)
			(xy 48.65079 -361.696051) (xy 48.596474 -361.643163) (xy 48.548088 -361.584801) (xy 48.50618 -361.521626)
			(xy 48.471224 -361.454355) (xy 48.443617 -361.38375) (xy 48.423671 -361.310609) (xy 48.411612 -361.235764)
			(xy 48.407577 -361.16006) (xy 47.291498 -361.16006) (xy 47.290994 -361.197966) (xy 47.282935 -361.273347)
			(xy 47.26691 -361.347445) (xy 47.2431 -361.41942) (xy 47.211774 -361.488456) (xy 47.173287 -361.553771)
			(xy 47.128076 -361.614626) (xy 47.076652 -361.67033) (xy 47.019599 -361.720252) (xy 46.957563 -361.763827)
			(xy 46.891246 -361.800562) (xy 46.8214 -361.830039) (xy 46.748817 -361.851925) (xy 46.674319 -361.865972)
			(xy 46.598749 -361.872021) (xy 46.522965 -361.870002) (xy 46.447825 -361.85994) (xy 46.37418 -361.841948)
			(xy 46.302864 -361.81623) (xy 46.234687 -361.783078) (xy 46.170419 -361.742866) (xy 46.11079 -361.696051)
			(xy 46.056474 -361.643163) (xy 46.008088 -361.584801) (xy 45.96618 -361.521626) (xy 45.931224 -361.454355)
			(xy 45.903617 -361.38375) (xy 45.883671 -361.310609) (xy 45.871612 -361.235764) (xy 45.867577 -361.16006)
			(xy 44.751498 -361.16006) (xy 44.750994 -361.197966) (xy 44.742935 -361.273347) (xy 44.72691 -361.347445)
			(xy 44.7031 -361.41942) (xy 44.671774 -361.488456) (xy 44.633287 -361.553771) (xy 44.588076 -361.614626)
			(xy 44.536652 -361.67033) (xy 44.479599 -361.720252) (xy 44.417563 -361.763827) (xy 44.351246 -361.800562)
			(xy 44.2814 -361.830039) (xy 44.208817 -361.851925) (xy 44.134319 -361.865972) (xy 44.058749 -361.872021)
			(xy 43.982965 -361.870002) (xy 43.907825 -361.85994) (xy 43.83418 -361.841948) (xy 43.762864 -361.81623)
			(xy 43.694687 -361.783078) (xy 43.630419 -361.742866) (xy 43.57079 -361.696051) (xy 43.516474 -361.643163)
			(xy 43.468088 -361.584801) (xy 43.42618 -361.521626) (xy 43.391224 -361.454355) (xy 43.363617 -361.38375)
			(xy 43.343671 -361.310609) (xy 43.331612 -361.235764) (xy 43.327577 -361.16006) (xy 42.501239 -361.16006)
			(xy 42.515699 -361.170266) (xy 42.604766 -361.242723) (xy 42.688681 -361.321089) (xy 42.767054 -361.404998)
			(xy 42.839517 -361.49406) (xy 42.905734 -361.587859) (xy 42.965396 -361.685958) (xy 43.018225 -361.7879)
			(xy 43.056094 -361.87507) (xy 84.927697 -361.87507) (xy 84.931732 -361.799366) (xy 84.943791 -361.724521)
			(xy 84.963737 -361.65138) (xy 84.991344 -361.580775) (xy 85.0263 -361.513504) (xy 85.068208 -361.450329)
			(xy 85.116594 -361.391967) (xy 85.17091 -361.339079) (xy 85.230539 -361.292264) (xy 85.294807 -361.252052)
			(xy 85.362984 -361.2189) (xy 85.4343 -361.193182) (xy 85.507945 -361.17519) (xy 85.583085 -361.165128)
			(xy 85.658869 -361.163109) (xy 85.734439 -361.169158) (xy 85.808937 -361.183205) (xy 85.88152 -361.205091)
			(xy 85.951366 -361.234568) (xy 86.017683 -361.271303) (xy 86.079719 -361.314878) (xy 86.136772 -361.3648)
			(xy 86.188196 -361.420504) (xy 86.233407 -361.481359) (xy 86.271894 -361.546674) (xy 86.30322 -361.61571)
			(xy 86.32703 -361.687685) (xy 86.343055 -361.761783) (xy 86.351114 -361.837164) (xy 86.351618 -361.87507)
			(xy 87.467697 -361.87507) (xy 87.471732 -361.799366) (xy 87.483791 -361.724521) (xy 87.503737 -361.65138)
			(xy 87.531344 -361.580775) (xy 87.5663 -361.513504) (xy 87.608208 -361.450329) (xy 87.656594 -361.391967)
			(xy 87.71091 -361.339079) (xy 87.770539 -361.292264) (xy 87.834807 -361.252052) (xy 87.902984 -361.2189)
			(xy 87.9743 -361.193182) (xy 88.047945 -361.17519) (xy 88.123085 -361.165128) (xy 88.198869 -361.163109)
			(xy 88.274439 -361.169158) (xy 88.348937 -361.183205) (xy 88.42152 -361.205091) (xy 88.491366 -361.234568)
			(xy 88.557683 -361.271303) (xy 88.619719 -361.314878) (xy 88.676772 -361.3648) (xy 88.728196 -361.420504)
			(xy 88.773407 -361.481359) (xy 88.811894 -361.546674) (xy 88.84322 -361.61571) (xy 88.86703 -361.687685)
			(xy 88.883055 -361.761783) (xy 88.891114 -361.837164) (xy 88.891618 -361.87507) (xy 90.007697 -361.87507)
			(xy 90.011732 -361.799366) (xy 90.023791 -361.724521) (xy 90.043737 -361.65138) (xy 90.071344 -361.580775)
			(xy 90.1063 -361.513504) (xy 90.148208 -361.450329) (xy 90.196594 -361.391967) (xy 90.25091 -361.339079)
			(xy 90.310539 -361.292264) (xy 90.374807 -361.252052) (xy 90.442984 -361.2189) (xy 90.5143 -361.193182)
			(xy 90.587945 -361.17519) (xy 90.663085 -361.165128) (xy 90.738869 -361.163109) (xy 90.814439 -361.169158)
			(xy 90.888937 -361.183205) (xy 90.96152 -361.205091) (xy 91.031366 -361.234568) (xy 91.097683 -361.271303)
			(xy 91.159719 -361.314878) (xy 91.216772 -361.3648) (xy 91.268196 -361.420504) (xy 91.313407 -361.481359)
			(xy 91.351894 -361.546674) (xy 91.38322 -361.61571) (xy 91.40703 -361.687685) (xy 91.423055 -361.761783)
			(xy 91.431114 -361.837164) (xy 91.431618 -361.87507) (xy 91.431114 -361.912976) (xy 91.423055 -361.988357)
			(xy 91.40703 -362.062455) (xy 91.38322 -362.13443) (xy 91.351894 -362.203466) (xy 91.313407 -362.268781)
			(xy 91.268196 -362.329636) (xy 91.216772 -362.38534) (xy 91.159719 -362.435262) (xy 91.097683 -362.478837)
			(xy 91.031366 -362.515572) (xy 90.96152 -362.545049) (xy 90.888937 -362.566935) (xy 90.814439 -362.580982)
			(xy 90.738869 -362.587031) (xy 90.663085 -362.585012) (xy 90.587945 -362.57495) (xy 90.5143 -362.556958)
			(xy 90.442984 -362.53124) (xy 90.374807 -362.498088) (xy 90.310539 -362.457876) (xy 90.25091 -362.411061)
			(xy 90.196594 -362.358173) (xy 90.148208 -362.299811) (xy 90.1063 -362.236636) (xy 90.071344 -362.169365)
			(xy 90.043737 -362.09876) (xy 90.023791 -362.025619) (xy 90.011732 -361.950774) (xy 90.007697 -361.87507)
			(xy 88.891618 -361.87507) (xy 88.891114 -361.912976) (xy 88.883055 -361.988357) (xy 88.86703 -362.062455)
			(xy 88.84322 -362.13443) (xy 88.811894 -362.203466) (xy 88.773407 -362.268781) (xy 88.728196 -362.329636)
			(xy 88.676772 -362.38534) (xy 88.619719 -362.435262) (xy 88.557683 -362.478837) (xy 88.491366 -362.515572)
			(xy 88.42152 -362.545049) (xy 88.348937 -362.566935) (xy 88.274439 -362.580982) (xy 88.198869 -362.587031)
			(xy 88.123085 -362.585012) (xy 88.047945 -362.57495) (xy 87.9743 -362.556958) (xy 87.902984 -362.53124)
			(xy 87.834807 -362.498088) (xy 87.770539 -362.457876) (xy 87.71091 -362.411061) (xy 87.656594 -362.358173)
			(xy 87.608208 -362.299811) (xy 87.5663 -362.236636) (xy 87.531344 -362.169365) (xy 87.503737 -362.09876)
			(xy 87.483791 -362.025619) (xy 87.471732 -361.950774) (xy 87.467697 -361.87507) (xy 86.351618 -361.87507)
			(xy 86.351114 -361.912976) (xy 86.343055 -361.988357) (xy 86.32703 -362.062455) (xy 86.30322 -362.13443)
			(xy 86.271894 -362.203466) (xy 86.233407 -362.268781) (xy 86.188196 -362.329636) (xy 86.136772 -362.38534)
			(xy 86.079719 -362.435262) (xy 86.017683 -362.478837) (xy 85.951366 -362.515572) (xy 85.88152 -362.545049)
			(xy 85.808937 -362.566935) (xy 85.734439 -362.580982) (xy 85.658869 -362.587031) (xy 85.583085 -362.585012)
			(xy 85.507945 -362.57495) (xy 85.4343 -362.556958) (xy 85.362984 -362.53124) (xy 85.294807 -362.498088)
			(xy 85.230539 -362.457876) (xy 85.17091 -362.411061) (xy 85.116594 -362.358173) (xy 85.068208 -362.299811)
			(xy 85.0263 -362.236636) (xy 84.991344 -362.169365) (xy 84.963737 -362.09876) (xy 84.943791 -362.025619)
			(xy 84.931732 -361.950774) (xy 84.927697 -361.87507) (xy 43.056094 -361.87507) (xy 43.063974 -361.893209)
			(xy 43.10243 -362.001394) (xy 43.133415 -362.111952) (xy 43.156782 -362.224366) (xy 43.172424 -362.338113)
			(xy 43.180268 -362.452661) (xy 43.180762 -362.51007) (xy 43.180576 -362.543253) (xy 43.177909 -362.609567)
			(xy 43.175428 -362.642658) (xy 43.170272 -362.700942) (xy 43.152948 -362.816671) (xy 43.127616 -362.930914)
			(xy 43.094401 -363.043119) (xy 43.056327 -363.14507) (xy 86.197697 -363.14507) (xy 86.201732 -363.069366)
			(xy 86.213791 -362.994521) (xy 86.233737 -362.92138) (xy 86.261344 -362.850775) (xy 86.2963 -362.783504)
			(xy 86.338208 -362.720329) (xy 86.386594 -362.661967) (xy 86.44091 -362.609079) (xy 86.500539 -362.562264)
			(xy 86.564807 -362.522052) (xy 86.632984 -362.4889) (xy 86.7043 -362.463182) (xy 86.777945 -362.44519)
			(xy 86.853085 -362.435128) (xy 86.928869 -362.433109) (xy 87.004439 -362.439158) (xy 87.078937 -362.453205)
			(xy 87.15152 -362.475091) (xy 87.221366 -362.504568) (xy 87.287683 -362.541303) (xy 87.349719 -362.584878)
			(xy 87.406772 -362.6348) (xy 87.458196 -362.690504) (xy 87.503407 -362.751359) (xy 87.541894 -362.816674)
			(xy 87.57322 -362.88571) (xy 87.59703 -362.957685) (xy 87.613055 -363.031783) (xy 87.621114 -363.107164)
			(xy 87.621618 -363.14507) (xy 88.737697 -363.14507) (xy 88.741732 -363.069366) (xy 88.753791 -362.994521)
			(xy 88.773737 -362.92138) (xy 88.801344 -362.850775) (xy 88.8363 -362.783504) (xy 88.878208 -362.720329)
			(xy 88.926594 -362.661967) (xy 88.98091 -362.609079) (xy 89.040539 -362.562264) (xy 89.104807 -362.522052)
			(xy 89.172984 -362.4889) (xy 89.2443 -362.463182) (xy 89.317945 -362.44519) (xy 89.393085 -362.435128)
			(xy 89.468869 -362.433109) (xy 89.544439 -362.439158) (xy 89.618937 -362.453205) (xy 89.69152 -362.475091)
			(xy 89.761366 -362.504568) (xy 89.827683 -362.541303) (xy 89.889719 -362.584878) (xy 89.946772 -362.6348)
			(xy 89.998196 -362.690504) (xy 90.043407 -362.751359) (xy 90.081894 -362.816674) (xy 90.11322 -362.88571)
			(xy 90.13703 -362.957685) (xy 90.153055 -363.031783) (xy 90.161114 -363.107164) (xy 90.161618 -363.14507)
			(xy 91.277697 -363.14507) (xy 91.281732 -363.069366) (xy 91.293791 -362.994521) (xy 91.313737 -362.92138)
			(xy 91.341344 -362.850775) (xy 91.3763 -362.783504) (xy 91.418208 -362.720329) (xy 91.466594 -362.661967)
			(xy 91.52091 -362.609079) (xy 91.580539 -362.562264) (xy 91.644807 -362.522052) (xy 91.712984 -362.4889)
			(xy 91.7843 -362.463182) (xy 91.857945 -362.44519) (xy 91.933085 -362.435128) (xy 92.008869 -362.433109)
			(xy 92.084439 -362.439158) (xy 92.158937 -362.453205) (xy 92.23152 -362.475091) (xy 92.301366 -362.504568)
			(xy 92.367683 -362.541303) (xy 92.429719 -362.584878) (xy 92.486772 -362.6348) (xy 92.538196 -362.690504)
			(xy 92.583407 -362.751359) (xy 92.621894 -362.816674) (xy 92.65322 -362.88571) (xy 92.67703 -362.957685)
			(xy 92.693055 -363.031783) (xy 92.701114 -363.107164) (xy 92.701618 -363.14507) (xy 92.701114 -363.182976)
			(xy 92.693055 -363.258357) (xy 92.67703 -363.332455) (xy 92.65322 -363.40443) (xy 92.621894 -363.473466)
			(xy 92.583407 -363.538781) (xy 92.538196 -363.599636) (xy 92.486772 -363.65534) (xy 92.429719 -363.705262)
			(xy 92.367683 -363.748837) (xy 92.301366 -363.785572) (xy 92.23152 -363.815049) (xy 92.158937 -363.836935)
			(xy 92.084439 -363.850982) (xy 92.008869 -363.857031) (xy 91.933085 -363.855012) (xy 91.857945 -363.84495)
			(xy 91.7843 -363.826958) (xy 91.712984 -363.80124) (xy 91.644807 -363.768088) (xy 91.580539 -363.727876)
			(xy 91.52091 -363.681061) (xy 91.466594 -363.628173) (xy 91.418208 -363.569811) (xy 91.3763 -363.506636)
			(xy 91.341344 -363.439365) (xy 91.313737 -363.36876) (xy 91.293791 -363.295619) (xy 91.281732 -363.220774)
			(xy 91.277697 -363.14507) (xy 90.161618 -363.14507) (xy 90.161114 -363.182976) (xy 90.153055 -363.258357)
			(xy 90.13703 -363.332455) (xy 90.11322 -363.40443) (xy 90.081894 -363.473466) (xy 90.043407 -363.538781)
			(xy 89.998196 -363.599636) (xy 89.946772 -363.65534) (xy 89.889719 -363.705262) (xy 89.827683 -363.748837)
			(xy 89.761366 -363.785572) (xy 89.69152 -363.815049) (xy 89.618937 -363.836935) (xy 89.544439 -363.850982)
			(xy 89.468869 -363.857031) (xy 89.393085 -363.855012) (xy 89.317945 -363.84495) (xy 89.2443 -363.826958)
			(xy 89.172984 -363.80124) (xy 89.104807 -363.768088) (xy 89.040539 -363.727876) (xy 88.98091 -363.681061)
			(xy 88.926594 -363.628173) (xy 88.878208 -363.569811) (xy 88.8363 -363.506636) (xy 88.801344 -363.439365)
			(xy 88.773737 -363.36876) (xy 88.753791 -363.295619) (xy 88.741732 -363.220774) (xy 88.737697 -363.14507)
			(xy 87.621618 -363.14507) (xy 87.621114 -363.182976) (xy 87.613055 -363.258357) (xy 87.59703 -363.332455)
			(xy 87.57322 -363.40443) (xy 87.541894 -363.473466) (xy 87.503407 -363.538781) (xy 87.458196 -363.599636)
			(xy 87.406772 -363.65534) (xy 87.349719 -363.705262) (xy 87.287683 -363.748837) (xy 87.221366 -363.785572)
			(xy 87.15152 -363.815049) (xy 87.078937 -363.836935) (xy 87.004439 -363.850982) (xy 86.928869 -363.857031)
			(xy 86.853085 -363.855012) (xy 86.777945 -363.84495) (xy 86.7043 -363.826958) (xy 86.632984 -363.80124)
			(xy 86.564807 -363.768088) (xy 86.500539 -363.727876) (xy 86.44091 -363.681061) (xy 86.386594 -363.628173)
			(xy 86.338208 -363.569811) (xy 86.2963 -363.506636) (xy 86.261344 -363.439365) (xy 86.233737 -363.36876)
			(xy 86.213791 -363.295619) (xy 86.201732 -363.220774) (xy 86.197697 -363.14507) (xy 43.056327 -363.14507)
			(xy 43.055094 -363.148372) (xy 43.328336 -363.148372) (xy 44.751244 -363.148372) (xy 44.751244 -363.86008)
			(xy 45.867577 -363.86008) (xy 45.871612 -363.784376) (xy 45.883671 -363.709531) (xy 45.903617 -363.63639)
			(xy 45.931224 -363.565785) (xy 45.96618 -363.498514) (xy 46.008088 -363.435339) (xy 46.056474 -363.376977)
			(xy 46.11079 -363.324089) (xy 46.170419 -363.277274) (xy 46.234687 -363.237062) (xy 46.302864 -363.20391)
			(xy 46.37418 -363.178192) (xy 46.447825 -363.1602) (xy 46.522965 -363.150138) (xy 46.598749 -363.148119)
			(xy 46.674319 -363.154168) (xy 46.748817 -363.168215) (xy 46.8214 -363.190101) (xy 46.891246 -363.219578)
			(xy 46.957563 -363.256313) (xy 47.019599 -363.299888) (xy 47.076652 -363.34981) (xy 47.128076 -363.405514)
			(xy 47.173287 -363.466369) (xy 47.211774 -363.531684) (xy 47.2431 -363.60072) (xy 47.26691 -363.672695)
			(xy 47.282935 -363.746793) (xy 47.290994 -363.822174) (xy 47.291498 -363.86008) (xy 48.407577 -363.86008)
			(xy 48.411612 -363.784376) (xy 48.423671 -363.709531) (xy 48.443617 -363.63639) (xy 48.471224 -363.565785)
			(xy 48.50618 -363.498514) (xy 48.548088 -363.435339) (xy 48.596474 -363.376977) (xy 48.65079 -363.324089)
			(xy 48.710419 -363.277274) (xy 48.774687 -363.237062) (xy 48.842864 -363.20391) (xy 48.91418 -363.178192)
			(xy 48.987825 -363.1602) (xy 49.062965 -363.150138) (xy 49.138749 -363.148119) (xy 49.214319 -363.154168)
			(xy 49.288817 -363.168215) (xy 49.3614 -363.190101) (xy 49.431246 -363.219578) (xy 49.497563 -363.256313)
			(xy 49.559599 -363.299888) (xy 49.616652 -363.34981) (xy 49.668076 -363.405514) (xy 49.713287 -363.466369)
			(xy 49.751774 -363.531684) (xy 49.7831 -363.60072) (xy 49.80691 -363.672695) (xy 49.822935 -363.746793)
			(xy 49.830994 -363.822174) (xy 49.831498 -363.86008) (xy 50.947577 -363.86008) (xy 50.951612 -363.784376)
			(xy 50.963671 -363.709531) (xy 50.983617 -363.63639) (xy 51.011224 -363.565785) (xy 51.04618 -363.498514)
			(xy 51.088088 -363.435339) (xy 51.136474 -363.376977) (xy 51.19079 -363.324089) (xy 51.250419 -363.277274)
			(xy 51.314687 -363.237062) (xy 51.382864 -363.20391) (xy 51.45418 -363.178192) (xy 51.527825 -363.1602)
			(xy 51.602965 -363.150138) (xy 51.678749 -363.148119) (xy 51.754319 -363.154168) (xy 51.828817 -363.168215)
			(xy 51.9014 -363.190101) (xy 51.971246 -363.219578) (xy 52.037563 -363.256313) (xy 52.099599 -363.299888)
			(xy 52.156652 -363.34981) (xy 52.208076 -363.405514) (xy 52.253287 -363.466369) (xy 52.291774 -363.531684)
			(xy 52.3231 -363.60072) (xy 52.34691 -363.672695) (xy 52.362935 -363.746793) (xy 52.370994 -363.822174)
			(xy 52.371498 -363.86008) (xy 53.487577 -363.86008) (xy 53.491612 -363.784376) (xy 53.503671 -363.709531)
			(xy 53.523617 -363.63639) (xy 53.551224 -363.565785) (xy 53.58618 -363.498514) (xy 53.628088 -363.435339)
			(xy 53.676474 -363.376977) (xy 53.73079 -363.324089) (xy 53.790419 -363.277274) (xy 53.854687 -363.237062)
			(xy 53.922864 -363.20391) (xy 53.99418 -363.178192) (xy 54.067825 -363.1602) (xy 54.142965 -363.150138)
			(xy 54.218749 -363.148119) (xy 54.294319 -363.154168) (xy 54.368817 -363.168215) (xy 54.4414 -363.190101)
			(xy 54.511246 -363.219578) (xy 54.577563 -363.256313) (xy 54.639599 -363.299888) (xy 54.696652 -363.34981)
			(xy 54.748076 -363.405514) (xy 54.793287 -363.466369) (xy 54.831774 -363.531684) (xy 54.8631 -363.60072)
			(xy 54.88691 -363.672695) (xy 54.902935 -363.746793) (xy 54.910994 -363.822174) (xy 54.911498 -363.86008)
			(xy 56.027577 -363.86008) (xy 56.031612 -363.784376) (xy 56.043671 -363.709531) (xy 56.063617 -363.63639)
			(xy 56.091224 -363.565785) (xy 56.12618 -363.498514) (xy 56.168088 -363.435339) (xy 56.216474 -363.376977)
			(xy 56.27079 -363.324089) (xy 56.330419 -363.277274) (xy 56.394687 -363.237062) (xy 56.462864 -363.20391)
			(xy 56.53418 -363.178192) (xy 56.607825 -363.1602) (xy 56.682965 -363.150138) (xy 56.758749 -363.148119)
			(xy 56.834319 -363.154168) (xy 56.908817 -363.168215) (xy 56.9814 -363.190101) (xy 57.051246 -363.219578)
			(xy 57.117563 -363.256313) (xy 57.179599 -363.299888) (xy 57.236652 -363.34981) (xy 57.288076 -363.405514)
			(xy 57.333287 -363.466369) (xy 57.371774 -363.531684) (xy 57.4031 -363.60072) (xy 57.42691 -363.672695)
			(xy 57.442935 -363.746793) (xy 57.450994 -363.822174) (xy 57.451498 -363.86008) (xy 58.567577 -363.86008)
			(xy 58.571612 -363.784376) (xy 58.583671 -363.709531) (xy 58.603617 -363.63639) (xy 58.631224 -363.565785)
			(xy 58.66618 -363.498514) (xy 58.708088 -363.435339) (xy 58.756474 -363.376977) (xy 58.81079 -363.324089)
			(xy 58.870419 -363.277274) (xy 58.934687 -363.237062) (xy 59.002864 -363.20391) (xy 59.07418 -363.178192)
			(xy 59.147825 -363.1602) (xy 59.222965 -363.150138) (xy 59.298749 -363.148119) (xy 59.374319 -363.154168)
			(xy 59.448817 -363.168215) (xy 59.5214 -363.190101) (xy 59.591246 -363.219578) (xy 59.657563 -363.256313)
			(xy 59.719599 -363.299888) (xy 59.776652 -363.34981) (xy 59.828076 -363.405514) (xy 59.873287 -363.466369)
			(xy 59.911774 -363.531684) (xy 59.9431 -363.60072) (xy 59.96691 -363.672695) (xy 59.982935 -363.746793)
			(xy 59.990994 -363.822174) (xy 59.991498 -363.86008) (xy 61.107577 -363.86008) (xy 61.111612 -363.784376)
			(xy 61.123671 -363.709531) (xy 61.143617 -363.63639) (xy 61.171224 -363.565785) (xy 61.20618 -363.498514)
			(xy 61.248088 -363.435339) (xy 61.296474 -363.376977) (xy 61.35079 -363.324089) (xy 61.410419 -363.277274)
			(xy 61.474687 -363.237062) (xy 61.542864 -363.20391) (xy 61.61418 -363.178192) (xy 61.687825 -363.1602)
			(xy 61.762965 -363.150138) (xy 61.838749 -363.148119) (xy 61.914319 -363.154168) (xy 61.988817 -363.168215)
			(xy 62.0614 -363.190101) (xy 62.131246 -363.219578) (xy 62.197563 -363.256313) (xy 62.259599 -363.299888)
			(xy 62.316652 -363.34981) (xy 62.368076 -363.405514) (xy 62.413287 -363.466369) (xy 62.451774 -363.531684)
			(xy 62.4831 -363.60072) (xy 62.50691 -363.672695) (xy 62.522935 -363.746793) (xy 62.530994 -363.822174)
			(xy 62.531498 -363.86008) (xy 62.530994 -363.897986) (xy 62.522935 -363.973367) (xy 62.50691 -364.047465)
			(xy 62.4831 -364.11944) (xy 62.451774 -364.188476) (xy 62.413287 -364.253791) (xy 62.368076 -364.314646)
			(xy 62.316652 -364.37035) (xy 62.265544 -364.41507) (xy 84.927697 -364.41507) (xy 84.931732 -364.339366)
			(xy 84.943791 -364.264521) (xy 84.963737 -364.19138) (xy 84.991344 -364.120775) (xy 85.0263 -364.053504)
			(xy 85.068208 -363.990329) (xy 85.116594 -363.931967) (xy 85.17091 -363.879079) (xy 85.230539 -363.832264)
			(xy 85.294807 -363.792052) (xy 85.362984 -363.7589) (xy 85.4343 -363.733182) (xy 85.507945 -363.71519)
			(xy 85.583085 -363.705128) (xy 85.658869 -363.703109) (xy 85.734439 -363.709158) (xy 85.808937 -363.723205)
			(xy 85.88152 -363.745091) (xy 85.951366 -363.774568) (xy 86.017683 -363.811303) (xy 86.079719 -363.854878)
			(xy 86.136772 -363.9048) (xy 86.188196 -363.960504) (xy 86.233407 -364.021359) (xy 86.271894 -364.086674)
			(xy 86.30322 -364.15571) (xy 86.32703 -364.227685) (xy 86.343055 -364.301783) (xy 86.351114 -364.377164)
			(xy 86.351618 -364.41507) (xy 87.467697 -364.41507) (xy 87.471732 -364.339366) (xy 87.483791 -364.264521)
			(xy 87.503737 -364.19138) (xy 87.531344 -364.120775) (xy 87.5663 -364.053504) (xy 87.608208 -363.990329)
			(xy 87.656594 -363.931967) (xy 87.71091 -363.879079) (xy 87.770539 -363.832264) (xy 87.834807 -363.792052)
			(xy 87.902984 -363.7589) (xy 87.9743 -363.733182) (xy 88.047945 -363.71519) (xy 88.123085 -363.705128)
			(xy 88.198869 -363.703109) (xy 88.274439 -363.709158) (xy 88.348937 -363.723205) (xy 88.42152 -363.745091)
			(xy 88.491366 -363.774568) (xy 88.557683 -363.811303) (xy 88.619719 -363.854878) (xy 88.676772 -363.9048)
			(xy 88.728196 -363.960504) (xy 88.773407 -364.021359) (xy 88.811894 -364.086674) (xy 88.84322 -364.15571)
			(xy 88.86703 -364.227685) (xy 88.883055 -364.301783) (xy 88.891114 -364.377164) (xy 88.891618 -364.41507)
			(xy 90.007697 -364.41507) (xy 90.011732 -364.339366) (xy 90.023791 -364.264521) (xy 90.043737 -364.19138)
			(xy 90.071344 -364.120775) (xy 90.1063 -364.053504) (xy 90.148208 -363.990329) (xy 90.196594 -363.931967)
			(xy 90.25091 -363.879079) (xy 90.310539 -363.832264) (xy 90.374807 -363.792052) (xy 90.442984 -363.7589)
			(xy 90.5143 -363.733182) (xy 90.587945 -363.71519) (xy 90.663085 -363.705128) (xy 90.738869 -363.703109)
			(xy 90.814439 -363.709158) (xy 90.888937 -363.723205) (xy 90.96152 -363.745091) (xy 91.031366 -363.774568)
			(xy 91.097683 -363.811303) (xy 91.159719 -363.854878) (xy 91.165664 -363.86008) (xy 93.154506 -363.86008)
			(xy 93.158522 -363.74381) (xy 93.170549 -363.628095) (xy 93.190531 -363.513485) (xy 93.218373 -363.400526)
			(xy 93.253942 -363.289758) (xy 93.297068 -363.181707) (xy 93.347545 -363.076889) (xy 93.405134 -362.975804)
			(xy 93.46956 -362.878932) (xy 93.540515 -362.786736) (xy 93.617662 -362.699655) (xy 93.700633 -362.618104)
			(xy 93.789033 -362.542472) (xy 93.88244 -362.473118) (xy 93.980409 -362.410375) (xy 94.082473 -362.354539)
			(xy 94.188147 -362.305878) (xy 94.296926 -362.264624) (xy 94.408291 -362.230973) (xy 94.521714 -362.205085)
			(xy 94.636651 -362.187084) (xy 94.752557 -362.177055) (xy 94.868879 -362.175047) (xy 94.985062 -362.181069)
			(xy 95.100553 -362.195092) (xy 95.214801 -362.21705) (xy 95.327262 -362.246837) (xy 95.4374 -362.284312)
			(xy 95.54469 -362.329297) (xy 95.648621 -362.381576) (xy 95.748697 -362.440901) (xy 95.844443 -362.506989)
			(xy 95.9354 -362.579525) (xy 96.021136 -362.658164) (xy 96.101243 -362.74253) (xy 96.175339 -362.832222)
			(xy 96.243069 -362.926812) (xy 96.304113 -363.02585) (xy 96.358178 -363.128863) (xy 96.405008 -363.23536)
			(xy 96.444379 -363.344835) (xy 96.476103 -363.456765) (xy 96.500029 -363.570617) (xy 96.516043 -363.685849)
			(xy 96.52407 -363.801911) (xy 96.524572 -363.86008) (xy 96.52407 -363.918249) (xy 96.516043 -364.034311)
			(xy 96.500029 -364.149543) (xy 96.476103 -364.263395) (xy 96.444379 -364.375325) (xy 96.405008 -364.4848)
			(xy 96.358178 -364.591297) (xy 96.304113 -364.69431) (xy 96.243069 -364.793348) (xy 96.175339 -364.887938)
			(xy 96.101243 -364.97763) (xy 96.021136 -365.061996) (xy 95.9354 -365.140635) (xy 95.844443 -365.213171)
			(xy 95.748697 -365.279259) (xy 95.648621 -365.338584) (xy 95.54469 -365.390863) (xy 95.4374 -365.435848)
			(xy 95.327262 -365.473323) (xy 95.214801 -365.50311) (xy 95.100553 -365.525068) (xy 94.985062 -365.539091)
			(xy 94.868879 -365.545113) (xy 94.752557 -365.543105) (xy 94.636651 -365.533076) (xy 94.521714 -365.515075)
			(xy 94.408291 -365.489187) (xy 94.296926 -365.455536) (xy 94.188147 -365.414282) (xy 94.082473 -365.365621)
			(xy 93.980409 -365.309785) (xy 93.88244 -365.247042) (xy 93.789033 -365.177688) (xy 93.700633 -365.102056)
			(xy 93.617662 -365.020505) (xy 93.540515 -364.933424) (xy 93.46956 -364.841228) (xy 93.405134 -364.744356)
			(xy 93.347545 -364.643271) (xy 93.297068 -364.538453) (xy 93.253942 -364.430402) (xy 93.218373 -364.319634)
			(xy 93.190531 -364.206675) (xy 93.170549 -364.092065) (xy 93.158522 -363.97635) (xy 93.154506 -363.86008)
			(xy 91.165664 -363.86008) (xy 91.216772 -363.9048) (xy 91.268196 -363.960504) (xy 91.313407 -364.021359)
			(xy 91.351894 -364.086674) (xy 91.38322 -364.15571) (xy 91.40703 -364.227685) (xy 91.423055 -364.301783)
			(xy 91.431114 -364.377164) (xy 91.431618 -364.41507) (xy 91.431114 -364.452976) (xy 91.423055 -364.528357)
			(xy 91.40703 -364.602455) (xy 91.38322 -364.67443) (xy 91.351894 -364.743466) (xy 91.313407 -364.808781)
			(xy 91.268196 -364.869636) (xy 91.216772 -364.92534) (xy 91.159719 -364.975262) (xy 91.097683 -365.018837)
			(xy 91.031366 -365.055572) (xy 90.96152 -365.085049) (xy 90.888937 -365.106935) (xy 90.814439 -365.120982)
			(xy 90.738869 -365.127031) (xy 90.663085 -365.125012) (xy 90.587945 -365.11495) (xy 90.5143 -365.096958)
			(xy 90.442984 -365.07124) (xy 90.374807 -365.038088) (xy 90.310539 -364.997876) (xy 90.25091 -364.951061)
			(xy 90.196594 -364.898173) (xy 90.148208 -364.839811) (xy 90.1063 -364.776636) (xy 90.071344 -364.709365)
			(xy 90.043737 -364.63876) (xy 90.023791 -364.565619) (xy 90.011732 -364.490774) (xy 90.007697 -364.41507)
			(xy 88.891618 -364.41507) (xy 88.891114 -364.452976) (xy 88.883055 -364.528357) (xy 88.86703 -364.602455)
			(xy 88.84322 -364.67443) (xy 88.811894 -364.743466) (xy 88.773407 -364.808781) (xy 88.728196 -364.869636)
			(xy 88.676772 -364.92534) (xy 88.619719 -364.975262) (xy 88.557683 -365.018837) (xy 88.491366 -365.055572)
			(xy 88.42152 -365.085049) (xy 88.348937 -365.106935) (xy 88.274439 -365.120982) (xy 88.198869 -365.127031)
			(xy 88.123085 -365.125012) (xy 88.047945 -365.11495) (xy 87.9743 -365.096958) (xy 87.902984 -365.07124)
			(xy 87.834807 -365.038088) (xy 87.770539 -364.997876) (xy 87.71091 -364.951061) (xy 87.656594 -364.898173)
			(xy 87.608208 -364.839811) (xy 87.5663 -364.776636) (xy 87.531344 -364.709365) (xy 87.503737 -364.63876)
			(xy 87.483791 -364.565619) (xy 87.471732 -364.490774) (xy 87.467697 -364.41507) (xy 86.351618 -364.41507)
			(xy 86.351114 -364.452976) (xy 86.343055 -364.528357) (xy 86.32703 -364.602455) (xy 86.30322 -364.67443)
			(xy 86.271894 -364.743466) (xy 86.233407 -364.808781) (xy 86.188196 -364.869636) (xy 86.136772 -364.92534)
			(xy 86.079719 -364.975262) (xy 86.017683 -365.018837) (xy 85.951366 -365.055572) (xy 85.88152 -365.085049)
			(xy 85.808937 -365.106935) (xy 85.734439 -365.120982) (xy 85.658869 -365.127031) (xy 85.583085 -365.125012)
			(xy 85.507945 -365.11495) (xy 85.4343 -365.096958) (xy 85.362984 -365.07124) (xy 85.294807 -365.038088)
			(xy 85.230539 -364.997876) (xy 85.17091 -364.951061) (xy 85.116594 -364.898173) (xy 85.068208 -364.839811)
			(xy 85.0263 -364.776636) (xy 84.991344 -364.709365) (xy 84.963737 -364.63876) (xy 84.943791 -364.565619)
			(xy 84.931732 -364.490774) (xy 84.927697 -364.41507) (xy 62.265544 -364.41507) (xy 62.259599 -364.420272)
			(xy 62.197563 -364.463847) (xy 62.131246 -364.500582) (xy 62.0614 -364.530059) (xy 61.988817 -364.551945)
			(xy 61.914319 -364.565992) (xy 61.838749 -364.572041) (xy 61.762965 -364.570022) (xy 61.687825 -364.55996)
			(xy 61.61418 -364.541968) (xy 61.542864 -364.51625) (xy 61.474687 -364.483098) (xy 61.410419 -364.442886)
			(xy 61.35079 -364.396071) (xy 61.296474 -364.343183) (xy 61.248088 -364.284821) (xy 61.20618 -364.221646)
			(xy 61.171224 -364.154375) (xy 61.143617 -364.08377) (xy 61.123671 -364.010629) (xy 61.111612 -363.935784)
			(xy 61.107577 -363.86008) (xy 59.991498 -363.86008) (xy 59.990994 -363.897986) (xy 59.982935 -363.973367)
			(xy 59.96691 -364.047465) (xy 59.9431 -364.11944) (xy 59.911774 -364.188476) (xy 59.873287 -364.253791)
			(xy 59.828076 -364.314646) (xy 59.776652 -364.37035) (xy 59.719599 -364.420272) (xy 59.657563 -364.463847)
			(xy 59.591246 -364.500582) (xy 59.5214 -364.530059) (xy 59.448817 -364.551945) (xy 59.374319 -364.565992)
			(xy 59.298749 -364.572041) (xy 59.222965 -364.570022) (xy 59.147825 -364.55996) (xy 59.07418 -364.541968)
			(xy 59.002864 -364.51625) (xy 58.934687 -364.483098) (xy 58.870419 -364.442886) (xy 58.81079 -364.396071)
			(xy 58.756474 -364.343183) (xy 58.708088 -364.284821) (xy 58.66618 -364.221646) (xy 58.631224 -364.154375)
			(xy 58.603617 -364.08377) (xy 58.583671 -364.010629) (xy 58.571612 -363.935784) (xy 58.567577 -363.86008)
			(xy 57.451498 -363.86008) (xy 57.450994 -363.897986) (xy 57.442935 -363.973367) (xy 57.42691 -364.047465)
			(xy 57.4031 -364.11944) (xy 57.371774 -364.188476) (xy 57.333287 -364.253791) (xy 57.288076 -364.314646)
			(xy 57.236652 -364.37035) (xy 57.179599 -364.420272) (xy 57.117563 -364.463847) (xy 57.051246 -364.500582)
			(xy 56.9814 -364.530059) (xy 56.908817 -364.551945) (xy 56.834319 -364.565992) (xy 56.758749 -364.572041)
			(xy 56.682965 -364.570022) (xy 56.607825 -364.55996) (xy 56.53418 -364.541968) (xy 56.462864 -364.51625)
			(xy 56.394687 -364.483098) (xy 56.330419 -364.442886) (xy 56.27079 -364.396071) (xy 56.216474 -364.343183)
			(xy 56.168088 -364.284821) (xy 56.12618 -364.221646) (xy 56.091224 -364.154375) (xy 56.063617 -364.08377)
			(xy 56.043671 -364.010629) (xy 56.031612 -363.935784) (xy 56.027577 -363.86008) (xy 54.911498 -363.86008)
			(xy 54.910994 -363.897986) (xy 54.902935 -363.973367) (xy 54.88691 -364.047465) (xy 54.8631 -364.11944)
			(xy 54.831774 -364.188476) (xy 54.793287 -364.253791) (xy 54.748076 -364.314646) (xy 54.696652 -364.37035)
			(xy 54.639599 -364.420272) (xy 54.577563 -364.463847) (xy 54.511246 -364.500582) (xy 54.4414 -364.530059)
			(xy 54.368817 -364.551945) (xy 54.294319 -364.565992) (xy 54.218749 -364.572041) (xy 54.142965 -364.570022)
			(xy 54.067825 -364.55996) (xy 53.99418 -364.541968) (xy 53.922864 -364.51625) (xy 53.854687 -364.483098)
			(xy 53.790419 -364.442886) (xy 53.73079 -364.396071) (xy 53.676474 -364.343183) (xy 53.628088 -364.284821)
			(xy 53.58618 -364.221646) (xy 53.551224 -364.154375) (xy 53.523617 -364.08377) (xy 53.503671 -364.010629)
			(xy 53.491612 -363.935784) (xy 53.487577 -363.86008) (xy 52.371498 -363.86008) (xy 52.370994 -363.897986)
			(xy 52.362935 -363.973367) (xy 52.34691 -364.047465) (xy 52.3231 -364.11944) (xy 52.291774 -364.188476)
			(xy 52.253287 -364.253791) (xy 52.208076 -364.314646) (xy 52.156652 -364.37035) (xy 52.099599 -364.420272)
			(xy 52.037563 -364.463847) (xy 51.971246 -364.500582) (xy 51.9014 -364.530059) (xy 51.828817 -364.551945)
			(xy 51.754319 -364.565992) (xy 51.678749 -364.572041) (xy 51.602965 -364.570022) (xy 51.527825 -364.55996)
			(xy 51.45418 -364.541968) (xy 51.382864 -364.51625) (xy 51.314687 -364.483098) (xy 51.250419 -364.442886)
			(xy 51.19079 -364.396071) (xy 51.136474 -364.343183) (xy 51.088088 -364.284821) (xy 51.04618 -364.221646)
			(xy 51.011224 -364.154375) (xy 50.983617 -364.08377) (xy 50.963671 -364.010629) (xy 50.951612 -363.935784)
			(xy 50.947577 -363.86008) (xy 49.831498 -363.86008) (xy 49.830994 -363.897986) (xy 49.822935 -363.973367)
			(xy 49.80691 -364.047465) (xy 49.7831 -364.11944) (xy 49.751774 -364.188476) (xy 49.713287 -364.253791)
			(xy 49.668076 -364.314646) (xy 49.616652 -364.37035) (xy 49.559599 -364.420272) (xy 49.497563 -364.463847)
			(xy 49.431246 -364.500582) (xy 49.3614 -364.530059) (xy 49.288817 -364.551945) (xy 49.214319 -364.565992)
			(xy 49.138749 -364.572041) (xy 49.062965 -364.570022) (xy 48.987825 -364.55996) (xy 48.91418 -364.541968)
			(xy 48.842864 -364.51625) (xy 48.774687 -364.483098) (xy 48.710419 -364.442886) (xy 48.65079 -364.396071)
			(xy 48.596474 -364.343183) (xy 48.548088 -364.284821) (xy 48.50618 -364.221646) (xy 48.471224 -364.154375)
			(xy 48.443617 -364.08377) (xy 48.423671 -364.010629) (xy 48.411612 -363.935784) (xy 48.407577 -363.86008)
			(xy 47.291498 -363.86008) (xy 47.290994 -363.897986) (xy 47.282935 -363.973367) (xy 47.26691 -364.047465)
			(xy 47.2431 -364.11944) (xy 47.211774 -364.188476) (xy 47.173287 -364.253791) (xy 47.128076 -364.314646)
			(xy 47.076652 -364.37035) (xy 47.019599 -364.420272) (xy 46.957563 -364.463847) (xy 46.891246 -364.500582)
			(xy 46.8214 -364.530059) (xy 46.748817 -364.551945) (xy 46.674319 -364.565992) (xy 46.598749 -364.572041)
			(xy 46.522965 -364.570022) (xy 46.447825 -364.55996) (xy 46.37418 -364.541968) (xy 46.302864 -364.51625)
			(xy 46.234687 -364.483098) (xy 46.170419 -364.442886) (xy 46.11079 -364.396071) (xy 46.056474 -364.343183)
			(xy 46.008088 -364.284821) (xy 45.96618 -364.221646) (xy 45.931224 -364.154375) (xy 45.903617 -364.08377)
			(xy 45.883671 -364.010629) (xy 45.871612 -363.935784) (xy 45.867577 -363.86008) (xy 44.751244 -363.86008)
			(xy 44.751244 -364.571788) (xy 43.328336 -364.571788) (xy 43.328336 -363.148372) (xy 43.055094 -363.148372)
			(xy 43.053462 -363.152742) (xy 43.004999 -363.259253) (xy 42.949245 -363.362135) (xy 42.886471 -363.460891)
			(xy 42.816981 -363.555042) (xy 42.741111 -363.644132) (xy 42.659229 -363.727729) (xy 42.571732 -363.80543)
			(xy 42.479042 -363.876857) (xy 42.381609 -363.941665) (xy 42.279905 -363.99954) (xy 42.174422 -364.050202)
			(xy 42.065671 -364.093404) (xy 41.954179 -364.128939) (xy 41.840485 -364.156634) (xy 41.725141 -364.176354)
			(xy 41.608704 -364.188005) (xy 41.491739 -364.19153) (xy 41.374812 -364.186912) (xy 41.258489 -364.174173)
			(xy 41.143334 -364.153375) (xy 41.029905 -364.124618) (xy 40.91875 -364.088042) (xy 40.810407 -364.043825)
			(xy 40.705403 -363.992179) (xy 40.604244 -363.933356) (xy 40.507421 -363.86764) (xy 40.415403 -363.795349)
			(xy 40.328636 -363.716834) (xy 40.247539 -363.632474) (xy 40.172506 -363.542679) (xy 40.103899 -363.447883)
			(xy 40.042051 -363.348544) (xy 39.987262 -363.245145) (xy 39.939796 -363.138186) (xy 39.899884 -363.028185)
			(xy 39.86772 -362.915674) (xy 39.843457 -362.801199) (xy 39.827215 -362.685313) (xy 39.819072 -362.568579)
			(xy 39.818564 -362.51007) (xy 36.092815 -362.51007) (xy 36.140713 -362.546241) (xy 36.204933 -362.604785)
			(xy 36.263477 -362.669005) (xy 36.315846 -362.738352) (xy 36.361593 -362.812236) (xy 36.400327 -362.890025)
			(xy 36.431719 -362.971057) (xy 36.4555 -363.054639) (xy 36.471468 -363.140059) (xy 36.479486 -363.226588)
			(xy 36.479988 -363.270038) (xy 36.479486 -363.313488) (xy 36.471468 -363.400017) (xy 36.4555 -363.485437)
			(xy 36.431719 -363.569019) (xy 36.400327 -363.650051) (xy 36.361593 -363.72784) (xy 36.315846 -363.801724)
			(xy 36.263477 -363.871071) (xy 36.204933 -363.935291) (xy 36.140713 -363.993835) (xy 36.071366 -364.046204)
			(xy 35.997482 -364.091951) (xy 35.919693 -364.130685) (xy 35.838661 -364.162077) (xy 35.755079 -364.185858)
			(xy 35.669659 -364.201826) (xy 35.58313 -364.209844) (xy 35.49623 -364.209844) (xy 35.409701 -364.201826)
			(xy 35.324281 -364.185858) (xy 35.240699 -364.162077) (xy 35.159667 -364.130685) (xy 35.081878 -364.091951)
			(xy 35.007994 -364.046204) (xy 34.938647 -363.993835) (xy 34.874427 -363.935291) (xy 34.815883 -363.871071)
			(xy 34.763514 -363.801724) (xy 34.717767 -363.72784) (xy 34.679033 -363.650051) (xy 34.647641 -363.569019)
			(xy 34.62386 -363.485437) (xy 34.607892 -363.400017) (xy 34.599874 -363.313488) (xy 34.1757 -363.313488)
			(xy 34.1757 -363.845856) (xy 35.2171 -364.887256) (xy 35.281616 -364.90529) (xy 35.313874 -364.897162)
			(xy 35.3554 -364.887381) (xy 35.439739 -364.874476) (xy 35.524899 -364.869266) (xy 35.610182 -364.871794)
			(xy 35.694884 -364.882039) (xy 35.77831 -364.899917) (xy 35.859773 -364.92528) (xy 35.938603 -364.95792)
			(xy 36.01415 -364.997569) (xy 36.05022 -365.020352) (xy 38.33876 -365.020352) (xy 42.127932 -368.809524)
			(xy 42.127932 -373.61114) (xy 50.797968 -373.61114) (xy 52.449476 -373.61114) (xy 52.449476 -375.263156)
			(xy 50.797968 -375.263156) (xy 50.797968 -373.61114) (xy 42.127932 -373.61114) (xy 42.127932 -374.477703)
			(xy 47.298092 -374.477703) (xy 47.298092 -374.396593) (xy 47.306042 -374.315874) (xy 47.321865 -374.236323)
			(xy 47.34541 -374.158707) (xy 47.376449 -374.083771) (xy 47.414684 -374.012239) (xy 47.459746 -373.944799)
			(xy 47.511201 -373.8821) (xy 47.568554 -373.824747) (xy 47.631253 -373.773292) (xy 47.698693 -373.72823)
			(xy 47.770225 -373.689995) (xy 47.845161 -373.658956) (xy 47.922777 -373.635411) (xy 48.002328 -373.619588)
			(xy 48.083047 -373.611638) (xy 48.164157 -373.611638) (xy 48.244876 -373.619588) (xy 48.324427 -373.635411)
			(xy 48.402043 -373.658956) (xy 48.476979 -373.689995) (xy 48.548511 -373.72823) (xy 48.615951 -373.773292)
			(xy 48.67865 -373.824747) (xy 48.736003 -373.8821) (xy 48.787458 -373.944799) (xy 48.83252 -374.012239)
			(xy 48.870755 -374.083771) (xy 48.901794 -374.158707) (xy 48.925339 -374.236323) (xy 48.941162 -374.315874)
			(xy 48.949112 -374.396593) (xy 48.94961 -374.437148) (xy 48.949112 -374.477703) (xy 48.941162 -374.558422)
			(xy 48.925339 -374.637973) (xy 48.901794 -374.715589) (xy 48.870755 -374.790525) (xy 48.83252 -374.862057)
			(xy 48.787458 -374.929497) (xy 48.736003 -374.992196) (xy 48.67865 -375.049549) (xy 48.615951 -375.101004)
			(xy 48.548511 -375.146066) (xy 48.476979 -375.184301) (xy 48.402043 -375.21534) (xy 48.324427 -375.238885)
			(xy 48.244876 -375.254708) (xy 48.164157 -375.262658) (xy 48.083047 -375.262658) (xy 48.002328 -375.254708)
			(xy 47.922777 -375.238885) (xy 47.845161 -375.21534) (xy 47.770225 -375.184301) (xy 47.698693 -375.146066)
			(xy 47.631253 -375.101004) (xy 47.568554 -375.049549) (xy 47.511201 -374.992196) (xy 47.459746 -374.929497)
			(xy 47.414684 -374.862057) (xy 47.376449 -374.790525) (xy 47.34541 -374.715589) (xy 47.321865 -374.637973)
			(xy 47.306042 -374.558422) (xy 47.298092 -374.477703) (xy 42.127932 -374.477703) (xy 42.127932 -374.804178)
			(xy 41.27373 -375.65838) (xy 40.558212 -375.65838) (xy 40.54475 -375.661428) (xy 40.519166 -375.666685)
			(xy 40.467235 -375.672282) (xy 40.441118 -375.672604) (xy 40.235886 -375.672604) (xy 40.219239 -375.673149)
			(xy 40.18708 -375.681769) (xy 40.158248 -375.698419) (xy 40.134708 -375.721963) (xy 40.118062 -375.750797)
			(xy 40.109447 -375.782957) (xy 40.108886 -375.799604) (xy 40.108886 -376.210068) (xy 40.202358 -376.30354)
			(xy 40.789606 -376.30354) (xy 41.020746 -376.53468) (xy 41.020746 -376.62104) (xy 68.130928 -376.62104)
			(xy 68.130928 -375.656348) (xy 68.131622 -375.620282) (xy 68.141943 -375.548891) (xy 68.151502 -375.514108)
			(xy 68.156328 -375.496582) (xy 68.156328 -375.12244) (xy 69.122544 -375.12244) (xy 69.122544 -375.496582)
			(xy 69.12737 -375.514108) (xy 69.136908 -375.548896) (xy 69.147238 -375.620284) (xy 69.147944 -375.656348)
			(xy 69.147944 -375.77649) (xy 69.47408 -375.77649) (xy 69.47408 -374.811798) (xy 69.474577 -374.779072)
			(xy 69.482972 -374.714159) (xy 69.499623 -374.65086) (xy 69.524255 -374.590219) (xy 69.556461 -374.533238)
			(xy 69.57568 -374.506744) (xy 69.60108 -374.472962) (xy 69.60108 -374.455944) (xy 69.61632 -374.455944)
			(xy 69.652134 -374.425464) (xy 69.677311 -374.404611) (xy 69.732043 -374.36886) (xy 69.790908 -374.340421)
			(xy 69.852933 -374.319766) (xy 69.917095 -374.307235) (xy 69.982334 -374.303035) (xy 70.047573 -374.307235)
			(xy 70.111735 -374.319766) (xy 70.17376 -374.340421) (xy 70.232625 -374.36886) (xy 70.287357 -374.404611)
			(xy 70.312534 -374.425464) (xy 70.348348 -374.455944) (xy 70.363588 -374.455944) (xy 70.363588 -374.472962)
			(xy 70.388988 -374.506744) (xy 70.402323 -374.524911) (xy 70.426107 -374.563194) (xy 70.436486 -374.583198)
			(xy 70.443926 -374.596908) (xy 70.464329 -374.620491) (xy 70.489844 -374.638421) (xy 70.518946 -374.649625)
			(xy 70.549897 -374.653436) (xy 70.580848 -374.649625) (xy 70.60995 -374.638421) (xy 70.635465 -374.620491)
			(xy 70.655868 -374.596908) (xy 70.663308 -374.583198) (xy 70.673667 -374.563183) (xy 70.697455 -374.524901)
			(xy 70.710806 -374.506744) (xy 70.735952 -374.472962) (xy 70.735952 -374.455944) (xy 70.751446 -374.455944)
			(xy 70.78726 -374.425464) (xy 70.812437 -374.404611) (xy 70.867169 -374.36886) (xy 70.926034 -374.340421)
			(xy 70.988059 -374.319766) (xy 71.052221 -374.307235) (xy 71.11746 -374.303035) (xy 71.182699 -374.307235)
			(xy 71.246861 -374.319766) (xy 71.308886 -374.340421) (xy 71.367751 -374.36886) (xy 71.422483 -374.404611)
			(xy 71.44766 -374.425464) (xy 71.483474 -374.455944) (xy 71.498968 -374.455944) (xy 71.498968 -374.472962)
			(xy 71.524114 -374.506744) (xy 71.543335 -374.533246) (xy 71.575604 -374.590209) (xy 71.600295 -374.650842)
			(xy 71.616999 -374.714143) (xy 71.62544 -374.779064) (xy 71.625968 -374.811798) (xy 71.625968 -375.61012)
			(xy 86.39887 -375.61012) (xy 86.402874 -375.410022) (xy 86.414881 -375.210244) (xy 86.434872 -375.011107)
			(xy 86.462814 -374.812929) (xy 86.498662 -374.616027) (xy 86.54236 -374.420718) (xy 86.593837 -374.227313)
			(xy 86.653011 -374.036123) (xy 86.719787 -373.847453) (xy 86.794059 -373.661606) (xy 86.875706 -373.478879)
			(xy 86.964599 -373.299566) (xy 87.060595 -373.123952) (xy 87.16354 -372.95232) (xy 87.27327 -372.784944)
			(xy 87.389608 -372.622093) (xy 87.512369 -372.464026) (xy 87.641356 -372.310998) (xy 87.776363 -372.163253)
			(xy 87.917172 -372.021027) (xy 88.063559 -371.88455) (xy 88.215289 -371.754038) (xy 88.37212 -371.629702)
			(xy 88.533799 -371.51174) (xy 88.700069 -371.400341) (xy 88.870662 -371.295684) (xy 89.045306 -371.197936)
			(xy 89.223722 -371.107253) (xy 89.405622 -371.023782) (xy 89.590717 -370.947655) (xy 89.778709 -370.878995)
			(xy 89.969298 -370.817911) (xy 90.162178 -370.764501) (xy 90.35704 -370.718852) (xy 90.553573 -370.681035)
			(xy 90.751462 -370.651111) (xy 90.950389 -370.629129) (xy 91.150037 -370.615124) (xy 91.350085 -370.609118)
			(xy 91.550213 -370.61112) (xy 91.750101 -370.621128) (xy 91.949428 -370.639125) (xy 92.147876 -370.665083)
			(xy 92.345126 -370.69896) (xy 92.540863 -370.740702) (xy 92.734773 -370.790241) (xy 92.926546 -370.847499)
			(xy 93.115875 -370.912384) (xy 93.302455 -370.984792) (xy 93.48599 -371.064608) (xy 93.666184 -371.151702)
			(xy 93.842749 -371.245936) (xy 94.015402 -371.347159) (xy 94.183867 -371.455209) (xy 94.347875 -371.569912)
			(xy 94.507162 -371.691086) (xy 94.661473 -371.818535) (xy 94.810561 -371.952056) (xy 94.954188 -372.091436)
			(xy 95.092124 -372.23645) (xy 95.224147 -372.386867) (xy 95.350046 -372.542445) (xy 95.46962 -372.702937)
			(xy 95.582676 -372.868083) (xy 95.689035 -373.037621) (xy 95.788526 -373.211279) (xy 95.880989 -373.388778)
			(xy 95.966276 -373.569834) (xy 96.044251 -373.754158) (xy 96.114788 -373.941454) (xy 96.177776 -374.131422)
			(xy 96.233113 -374.323758) (xy 96.28071 -374.518154) (xy 96.320491 -374.714299) (xy 96.352393 -374.911878)
			(xy 96.376364 -375.110575) (xy 96.392366 -375.310073) (xy 96.400373 -375.510051) (xy 96.400874 -375.61012)
			(xy 96.400373 -375.710189) (xy 96.392366 -375.910167) (xy 96.376364 -376.109665) (xy 96.352393 -376.308362)
			(xy 96.320491 -376.505941) (xy 96.28071 -376.702086) (xy 96.233113 -376.896482) (xy 96.177776 -377.088818)
			(xy 96.114788 -377.278786) (xy 96.044251 -377.466082) (xy 95.966276 -377.650406) (xy 95.880989 -377.831462)
			(xy 95.788526 -378.008961) (xy 95.689035 -378.182619) (xy 95.582676 -378.352157) (xy 95.46962 -378.517303)
			(xy 95.350046 -378.677795) (xy 95.224147 -378.833373) (xy 95.092124 -378.98379) (xy 94.954188 -379.128804)
			(xy 94.810561 -379.268184) (xy 94.661473 -379.401705) (xy 94.507162 -379.529154) (xy 94.347875 -379.650328)
			(xy 94.183867 -379.765031) (xy 94.015402 -379.873081) (xy 93.842749 -379.974304) (xy 93.666184 -380.068538)
			(xy 93.48599 -380.155632) (xy 93.302455 -380.235448) (xy 93.115875 -380.307856) (xy 92.926546 -380.372741)
			(xy 92.734773 -380.429999) (xy 92.540863 -380.479538) (xy 92.345126 -380.52128) (xy 92.147876 -380.555157)
			(xy 91.949428 -380.581115) (xy 91.750101 -380.599112) (xy 91.550213 -380.60912) (xy 91.350085 -380.611122)
			(xy 91.150037 -380.605116) (xy 90.950389 -380.591111) (xy 90.751462 -380.569129) (xy 90.553573 -380.539205)
			(xy 90.35704 -380.501388) (xy 90.162178 -380.455739) (xy 89.969298 -380.402329) (xy 89.778709 -380.341245)
			(xy 89.590717 -380.272585) (xy 89.405622 -380.196458) (xy 89.223722 -380.112987) (xy 89.045306 -380.022304)
			(xy 88.870662 -379.924556) (xy 88.700069 -379.819899) (xy 88.533799 -379.7085) (xy 88.37212 -379.590538)
			(xy 88.215289 -379.466202) (xy 88.063559 -379.33569) (xy 87.917172 -379.199213) (xy 87.776363 -379.056987)
			(xy 87.641356 -378.909242) (xy 87.512369 -378.756214) (xy 87.389608 -378.598147) (xy 87.27327 -378.435296)
			(xy 87.16354 -378.26792) (xy 87.060595 -378.096288) (xy 86.964599 -377.920674) (xy 86.875706 -377.741361)
			(xy 86.794059 -377.558634) (xy 86.719787 -377.372787) (xy 86.653011 -377.184117) (xy 86.593837 -376.992927)
			(xy 86.54236 -376.799522) (xy 86.498662 -376.604213) (xy 86.462814 -376.407311) (xy 86.434872 -376.209133)
			(xy 86.414881 -376.009996) (xy 86.402874 -375.810218) (xy 86.39887 -375.61012) (xy 71.625968 -375.61012)
			(xy 71.625968 -375.77649) (xy 71.625462 -375.80875) (xy 71.617276 -375.872748) (xy 71.60106 -375.935197)
			(xy 71.577074 -375.995093) (xy 71.545703 -376.051473) (xy 71.507453 -376.103432) (xy 71.462936 -376.150134)
			(xy 71.412869 -376.19083) (xy 71.358057 -376.224865) (xy 71.299379 -376.251693) (xy 71.237778 -376.270882)
			(xy 71.174245 -376.282124) (xy 71.109801 -376.285239) (xy 71.04548 -376.280176) (xy 70.982316 -376.267017)
			(xy 70.921324 -376.245974) (xy 70.863485 -376.217383) (xy 70.809727 -376.181706) (xy 70.760914 -376.139514)
			(xy 70.739 -376.115834) (xy 70.722776 -376.098517) (xy 70.685107 -376.069666) (xy 70.642737 -376.048311)
			(xy 70.597138 -376.035193) (xy 70.549897 -376.030769) (xy 70.502656 -376.035193) (xy 70.457057 -376.048311)
			(xy 70.414687 -376.069666) (xy 70.377018 -376.098517) (xy 70.360794 -376.115834) (xy 70.338929 -376.139555)
			(xy 70.290125 -376.181749) (xy 70.236375 -376.217429) (xy 70.178541 -376.246021) (xy 70.117555 -376.267066)
			(xy 70.054396 -376.280224) (xy 69.99008 -376.285286) (xy 69.92564 -376.282168) (xy 69.862113 -376.270922)
			(xy 69.800519 -376.251727) (xy 69.741849 -376.224894) (xy 69.687046 -376.190852) (xy 69.636991 -376.15015)
			(xy 69.592488 -376.103441) (xy 69.554254 -376.051477) (xy 69.522901 -375.995092) (xy 69.498935 -375.935194)
			(xy 69.482741 -375.872744) (xy 69.474579 -375.808748) (xy 69.47408 -375.77649) (xy 69.147944 -375.77649)
			(xy 69.147944 -376.62104) (xy 69.147442 -376.653001) (xy 69.139431 -376.716419) (xy 69.123534 -376.778333)
			(xy 69.100002 -376.837766) (xy 69.069208 -376.893781) (xy 69.031635 -376.945496) (xy 68.987878 -376.992093)
			(xy 68.938625 -377.032838) (xy 68.884654 -377.067089) (xy 68.826815 -377.094306) (xy 68.766022 -377.114059)
			(xy 68.703232 -377.126037) (xy 68.639436 -377.130051) (xy 68.57564 -377.126037) (xy 68.51285 -377.114059)
			(xy 68.452057 -377.094306) (xy 68.394218 -377.067089) (xy 68.340247 -377.032838) (xy 68.290994 -376.992093)
			(xy 68.247237 -376.945496) (xy 68.209664 -376.893781) (xy 68.17887 -376.837766) (xy 68.155338 -376.778333)
			(xy 68.139441 -376.716419) (xy 68.13143 -376.653001) (xy 68.130928 -376.62104) (xy 41.020746 -376.62104)
			(xy 41.020746 -377.077224) (xy 40.785034 -377.312936) (xy 35.293046 -377.312936) (xy 35.230308 -377.375674)
			(xy 35.218848 -377.387807) (xy 35.20214 -377.416687) (xy 35.19349 -377.448911) (xy 35.193488 -377.482275)
			(xy 35.202135 -377.5145) (xy 35.21884 -377.543381) (xy 35.230308 -377.555506) (xy 35.252914 -377.578112)
			(xy 35.314636 -377.5964) (xy 35.346132 -377.589796) (xy 35.388995 -377.581291) (xy 35.475815 -377.571318)
			(xy 35.563186 -377.569443) (xy 35.650354 -377.575683) (xy 35.736567 -377.589984) (xy 35.821082 -377.612222)
			(xy 35.903168 -377.642204) (xy 35.982119 -377.679674) (xy 36.057253 -377.724307) (xy 36.127922 -377.775719)
			(xy 36.193516 -377.833465) (xy 36.253469 -377.897048) (xy 36.307264 -377.96592) (xy 36.354438 -378.039485)
			(xy 36.394582 -378.11711) (xy 36.427352 -378.198125) (xy 36.452463 -378.28183) (xy 36.4697 -378.367504)
			(xy 36.478914 -378.454408) (xy 36.480025 -378.541793) (xy 36.473024 -378.628903) (xy 36.457971 -378.714988)
			(xy 36.434996 -378.799305) (xy 36.404297 -378.881126) (xy 36.366139 -378.959747) (xy 36.320851 -379.034488)
			(xy 36.268824 -379.104705) (xy 36.210507 -379.169791) (xy 36.146402 -379.229187) (xy 36.077064 -379.282379)
			(xy 36.003089 -379.328908) (xy 35.925116 -379.368373) (xy 35.843818 -379.400433) (xy 35.759897 -379.424812)
			(xy 35.674075 -379.4413) (xy 35.587094 -379.449754) (xy 35.499703 -379.450102) (xy 35.412658 -379.44234)
			(xy 35.326707 -379.426535) (xy 35.242594 -379.402824) (xy 35.161044 -379.371412) (xy 35.08276 -379.332568)
			(xy 35.008417 -379.286629) (xy 34.938658 -379.233991) (xy 34.874083 -379.175107) (xy 34.81525 -379.110486)
			(xy 34.762666 -379.040686) (xy 34.716785 -378.966307) (xy 34.678003 -378.887993) (xy 34.646654 -378.806418)
			(xy 34.623009 -378.722286) (xy 34.607271 -378.636324) (xy 34.602928 -378.592842) (xy 34.600496 -378.570806)
			(xy 34.588986 -378.527996) (xy 34.57022 -378.487834) (xy 34.544767 -378.45154) (xy 34.5134 -378.420215)
			(xy 34.477072 -378.39481) (xy 34.436885 -378.376098) (xy 34.39406 -378.364645) (xy 34.349897 -378.360801)
			(xy 34.305738 -378.364681) (xy 34.262922 -378.376168) (xy 34.22275 -378.394913) (xy 34.186442 -378.420346)
			(xy 34.170366 -378.435616) (xy 31.512494 -381.093488) (xy 34.599874 -381.093488) (xy 34.599874 -381.006588)
			(xy 34.607892 -380.920059) (xy 34.62386 -380.834639) (xy 34.647641 -380.751057) (xy 34.679033 -380.670025)
			(xy 34.717767 -380.592236) (xy 34.763514 -380.518352) (xy 34.815883 -380.449005) (xy 34.874427 -380.384785)
			(xy 34.938647 -380.326241) (xy 35.007994 -380.273872) (xy 35.081878 -380.228125) (xy 35.159667 -380.189391)
			(xy 35.240699 -380.157999) (xy 35.324281 -380.134218) (xy 35.409701 -380.11825) (xy 35.49623 -380.110232)
			(xy 35.58313 -380.110232) (xy 35.669659 -380.11825) (xy 35.755079 -380.134218) (xy 35.838661 -380.157999)
			(xy 35.919693 -380.189391) (xy 35.997482 -380.228125) (xy 36.071366 -380.273872) (xy 36.140713 -380.326241)
			(xy 36.204933 -380.384785) (xy 36.263477 -380.449005) (xy 36.315846 -380.518352) (xy 36.361593 -380.592236)
			(xy 36.400327 -380.670025) (xy 36.431719 -380.751057) (xy 36.446236 -380.80208) (xy 38.761819 -380.80208)
			(xy 38.765709 -380.747731) (xy 38.777295 -380.694489) (xy 38.79634 -380.643437) (xy 38.822456 -380.595616)
			(xy 38.855113 -380.551999) (xy 38.893645 -380.513473) (xy 38.937268 -380.480823) (xy 38.985093 -380.454714)
			(xy 39.036147 -380.435678) (xy 39.089391 -380.424101) (xy 39.14374 -380.420219) (xy 39.198089 -380.424112)
			(xy 39.251331 -380.4357) (xy 39.302381 -380.454748) (xy 39.350201 -380.480867) (xy 39.372286 -380.496826)
			(xy 39.391298 -380.510422) (xy 39.433181 -380.531154) (xy 39.478149 -380.54388) (xy 39.524686 -380.54817)
			(xy 39.571223 -380.54388) (xy 39.616191 -380.531154) (xy 39.658074 -380.510422) (xy 39.677086 -380.496826)
			(xy 39.699143 -380.480819) (xy 39.746971 -380.454692) (xy 39.798031 -380.435637) (xy 39.851283 -380.424044)
			(xy 39.905644 -380.420148) (xy 39.960005 -380.424028) (xy 40.01326 -380.435606) (xy 40.064326 -380.454645)
			(xy 40.112162 -380.480758) (xy 40.155795 -380.513414) (xy 40.194336 -380.551947) (xy 40.227 -380.595573)
			(xy 40.253123 -380.643404) (xy 40.272173 -380.694466) (xy 40.283761 -380.747719) (xy 40.287652 -380.80208)
			(xy 40.648512 -380.80208) (xy 40.652402 -380.747729) (xy 40.663988 -380.694485) (xy 40.683034 -380.643433)
			(xy 40.709152 -380.59561) (xy 40.74181 -380.551992) (xy 40.780343 -380.513465) (xy 40.823967 -380.480815)
			(xy 40.871794 -380.454706) (xy 40.92285 -380.435669) (xy 40.976096 -380.424093) (xy 41.030447 -380.420212)
			(xy 41.084798 -380.424106) (xy 41.13804 -380.435696) (xy 41.189092 -380.454745) (xy 41.236912 -380.480866)
			(xy 41.258998 -380.496826) (xy 41.27801 -380.510422) (xy 41.319893 -380.531154) (xy 41.364861 -380.54388)
			(xy 41.411398 -380.54817) (xy 41.457935 -380.54388) (xy 41.502903 -380.531154) (xy 41.544786 -380.510422)
			(xy 41.563798 -380.496826) (xy 41.585854 -380.48082) (xy 41.633682 -380.454695) (xy 41.684741 -380.435642)
			(xy 41.737992 -380.42405) (xy 41.79235 -380.420155) (xy 41.84671 -380.424036) (xy 41.899964 -380.435614)
			(xy 41.951028 -380.454653) (xy 41.998862 -380.480766) (xy 42.042493 -380.513421) (xy 42.081033 -380.551954)
			(xy 42.113696 -380.595579) (xy 42.139818 -380.643409) (xy 42.158866 -380.694469) (xy 42.170454 -380.747721)
			(xy 42.174345 -380.80208) (xy 42.17046 -380.856439) (xy 42.158878 -380.909692) (xy 42.139835 -380.960754)
			(xy 42.113718 -381.008587) (xy 42.081059 -381.052215) (xy 42.042524 -381.090752) (xy 41.998897 -381.123412)
			(xy 41.951065 -381.14953) (xy 41.900003 -381.168574) (xy 41.84675 -381.180158) (xy 41.792391 -381.184045)
			(xy 41.738032 -381.180156) (xy 41.68478 -381.16857) (xy 41.633719 -381.149522) (xy 41.585889 -381.123402)
			(xy 41.563798 -381.107442) (xy 41.544786 -381.093846) (xy 41.502903 -381.073114) (xy 41.457935 -381.060388)
			(xy 41.411398 -381.056098) (xy 41.364861 -381.060388) (xy 41.319893 -381.073114) (xy 41.27801 -381.093846)
			(xy 41.258998 -381.107442) (xy 41.236878 -381.123356) (xy 41.189055 -381.149472) (xy 41.138001 -381.168516)
			(xy 41.084757 -381.1801) (xy 41.030407 -381.183988) (xy 40.976056 -381.180102) (xy 40.922811 -381.168519)
			(xy 40.871757 -381.149477) (xy 40.823933 -381.123363) (xy 40.780312 -381.090708) (xy 40.741783 -381.052177)
			(xy 40.70913 -381.008555) (xy 40.683017 -380.96073) (xy 40.663977 -380.909675) (xy 40.652396 -380.856431)
			(xy 40.648512 -380.80208) (xy 40.287652 -380.80208) (xy 40.283767 -380.85644) (xy 40.272184 -380.909695)
			(xy 40.25314 -380.960759) (xy 40.227023 -381.008593) (xy 40.194363 -381.052222) (xy 40.155826 -381.09076)
			(xy 40.112197 -381.12342) (xy 40.064363 -381.149538) (xy 40.0133 -381.168583) (xy 39.960045 -381.180166)
			(xy 39.905684 -381.184052) (xy 39.851324 -381.180162) (xy 39.79807 -381.168574) (xy 39.747008 -381.149525)
			(xy 39.699177 -381.123403) (xy 39.677086 -381.107442) (xy 39.658074 -381.093846) (xy 39.616191 -381.073114)
			(xy 39.571223 -381.060388) (xy 39.524686 -381.056098) (xy 39.478149 -381.060388) (xy 39.433181 -381.073114)
			(xy 39.391298 -381.093846) (xy 39.372286 -381.107442) (xy 39.350166 -381.123355) (xy 39.302344 -381.149469)
			(xy 39.251291 -381.168511) (xy 39.198049 -381.180094) (xy 39.1437 -381.183981) (xy 39.089351 -381.180094)
			(xy 39.036108 -381.168511) (xy 38.985056 -381.149469) (xy 38.937233 -381.123355) (xy 38.893614 -381.0907)
			(xy 38.855086 -381.05217) (xy 38.822434 -381.008549) (xy 38.796323 -380.960725) (xy 38.777283 -380.909672)
			(xy 38.765703 -380.856429) (xy 38.761819 -380.80208) (xy 36.446236 -380.80208) (xy 36.4555 -380.834639)
			(xy 36.471468 -380.920059) (xy 36.479486 -381.006588) (xy 36.479988 -381.050038) (xy 36.479486 -381.093488)
			(xy 36.471468 -381.180017) (xy 36.4555 -381.265437) (xy 36.431719 -381.349019) (xy 36.400327 -381.430051)
			(xy 36.361593 -381.50784) (xy 36.315846 -381.581724) (xy 36.263477 -381.651071) (xy 36.204933 -381.715291)
			(xy 36.140713 -381.773835) (xy 36.071366 -381.826204) (xy 35.997482 -381.871951) (xy 35.919693 -381.910685)
			(xy 35.838661 -381.942077) (xy 35.755079 -381.965858) (xy 35.669659 -381.981826) (xy 35.58313 -381.989844)
			(xy 35.49623 -381.989844) (xy 35.409701 -381.981826) (xy 35.324281 -381.965858) (xy 35.240699 -381.942077)
			(xy 35.159667 -381.910685) (xy 35.081878 -381.871951) (xy 35.007994 -381.826204) (xy 34.938647 -381.773835)
			(xy 34.874427 -381.715291) (xy 34.815883 -381.651071) (xy 34.763514 -381.581724) (xy 34.717767 -381.50784)
			(xy 34.679033 -381.430051) (xy 34.647641 -381.349019) (xy 34.62386 -381.265437) (xy 34.607892 -381.180017)
			(xy 34.599874 -381.093488) (xy 31.512494 -381.093488) (xy 31.385002 -381.22098) (xy 31.376874 -381.256794)
			(xy 31.366666 -381.299774) (xy 31.339236 -381.383753) (xy 31.304049 -381.464788) (xy 31.261415 -381.542166)
			(xy 31.211711 -381.615202) (xy 31.155375 -381.683254) (xy 31.092903 -381.745721) (xy 31.024847 -381.802053)
			(xy 30.951806 -381.851752) (xy 30.874426 -381.89438) (xy 30.793388 -381.929561) (xy 30.709407 -381.956984)
			(xy 30.666436 -381.967232) (xy 30.630622 -381.97536) (xy 30.385258 -382.220724) (xy 30.369923 -382.236739)
			(xy 30.344487 -382.273053) (xy 30.325742 -382.313232) (xy 30.314257 -382.356055) (xy 30.31038 -382.400221)
			(xy 30.31423 -382.44439) (xy 30.325688 -382.48722) (xy 30.344408 -382.52741) (xy 30.369821 -382.56374)
			(xy 30.401155 -382.595107) (xy 30.437459 -382.620558) (xy 30.470144 -382.635824) (xy 38.76176 -382.635824)
			(xy 38.765644 -382.581466) (xy 38.777225 -382.528215) (xy 38.796267 -382.477153) (xy 38.822382 -382.429322)
			(xy 38.855039 -382.385694) (xy 38.893573 -382.347157) (xy 38.937198 -382.314498) (xy 38.985028 -382.288379)
			(xy 39.036088 -382.269333) (xy 39.089339 -382.257748) (xy 39.143696 -382.25386) (xy 39.198054 -382.257747)
			(xy 39.251305 -382.269331) (xy 39.302365 -382.288376) (xy 39.350195 -382.314493) (xy 39.372286 -382.330452)
			(xy 39.391298 -382.344048) (xy 39.433181 -382.36478) (xy 39.478149 -382.377506) (xy 39.524686 -382.381796)
			(xy 39.571223 -382.377506) (xy 39.616191 -382.36478) (xy 39.658074 -382.344048) (xy 39.677086 -382.330452)
			(xy 39.699212 -382.314545) (xy 39.747036 -382.288427) (xy 39.798091 -382.269382) (xy 39.851336 -382.257796)
			(xy 39.905688 -382.253907) (xy 39.96004 -382.257793) (xy 40.013286 -382.269375) (xy 40.064342 -382.288417)
			(xy 40.112168 -382.314532) (xy 40.15579 -382.347187) (xy 40.19432 -382.385719) (xy 40.226975 -382.429342)
			(xy 40.253088 -382.477169) (xy 40.272128 -382.528225) (xy 40.283709 -382.581471) (xy 40.287593 -382.635824)
			(xy 40.648453 -382.635824) (xy 40.652337 -382.581465) (xy 40.663919 -382.528211) (xy 40.682962 -382.477149)
			(xy 40.709078 -382.429316) (xy 40.741736 -382.385687) (xy 40.780271 -382.34715) (xy 40.823898 -382.314489)
			(xy 40.871729 -382.28837) (xy 40.922791 -382.269325) (xy 40.976044 -382.25774) (xy 41.030403 -382.253853)
			(xy 41.084762 -382.257741) (xy 41.138014 -382.269326) (xy 41.189076 -382.288373) (xy 41.236907 -382.314492)
			(xy 41.258998 -382.330452) (xy 41.27801 -382.344048) (xy 41.319893 -382.36478) (xy 41.364861 -382.377506)
			(xy 41.411398 -382.381796) (xy 41.457935 -382.377506) (xy 41.502903 -382.36478) (xy 41.544786 -382.344048)
			(xy 41.563798 -382.330452) (xy 41.585924 -382.314546) (xy 41.633747 -382.28843) (xy 41.6848 -382.269386)
			(xy 41.738044 -382.257802) (xy 41.792395 -382.253914) (xy 41.846746 -382.257801) (xy 41.89999 -382.269383)
			(xy 41.951044 -382.288426) (xy 41.998868 -382.31454) (xy 42.042488 -382.347195) (xy 42.081017 -382.385726)
			(xy 42.11367 -382.429348) (xy 42.139782 -382.477174) (xy 42.158822 -382.528228) (xy 42.170402 -382.581473)
			(xy 42.174286 -382.635824) (xy 42.889427 -382.635824) (xy 42.893313 -382.581459) (xy 42.904896 -382.5282)
			(xy 42.923941 -382.477132) (xy 42.950061 -382.429295) (xy 42.982724 -382.385662) (xy 43.021264 -382.347122)
			(xy 43.064897 -382.31446) (xy 43.112735 -382.28834) (xy 43.163803 -382.269295) (xy 43.217062 -382.257712)
			(xy 43.271427 -382.253827) (xy 43.325791 -382.25772) (xy 43.379049 -382.26931) (xy 43.430114 -382.288362)
			(xy 43.477948 -382.314489) (xy 43.50004 -382.330452) (xy 43.519052 -382.344048) (xy 43.560935 -382.36478)
			(xy 43.605903 -382.377506) (xy 43.65244 -382.381796) (xy 43.698977 -382.377506) (xy 43.743945 -382.36478)
			(xy 43.785828 -382.344048) (xy 43.80484 -382.330452) (xy 43.826965 -382.314549) (xy 43.874785 -382.28844)
			(xy 43.925834 -382.269403) (xy 43.979074 -382.257824) (xy 44.033419 -382.253939) (xy 44.087763 -382.257829)
			(xy 44.141001 -382.269413) (xy 44.192049 -382.288456) (xy 44.239867 -382.31457) (xy 44.283481 -382.347223)
			(xy 44.322005 -382.385751) (xy 44.354653 -382.429369) (xy 44.380762 -382.47719) (xy 44.399799 -382.52824)
			(xy 44.411377 -382.581479) (xy 44.415261 -382.635824) (xy 44.793437 -382.635824) (xy 44.797322 -382.581461)
			(xy 44.808905 -382.528204) (xy 44.827949 -382.477138) (xy 44.854068 -382.429303) (xy 44.886728 -382.385671)
			(xy 44.925267 -382.347133) (xy 44.968897 -382.314471) (xy 45.016733 -382.288352) (xy 45.067798 -382.269306)
			(xy 45.121055 -382.257723) (xy 45.175418 -382.253837) (xy 45.22978 -382.257728) (xy 45.283036 -382.269316)
			(xy 45.3341 -382.288366) (xy 45.381932 -382.31449) (xy 45.404024 -382.330452) (xy 45.423036 -382.344048)
			(xy 45.464919 -382.36478) (xy 45.509887 -382.377506) (xy 45.556424 -382.381796) (xy 45.602961 -382.377506)
			(xy 45.647929 -382.36478) (xy 45.689812 -382.344048) (xy 45.708824 -382.330452) (xy 45.730949 -382.314548)
			(xy 45.778771 -382.288436) (xy 45.829821 -382.269396) (xy 45.883062 -382.257816) (xy 45.93741 -382.25393)
			(xy 45.991757 -382.257818) (xy 46.044997 -382.269402) (xy 46.096047 -382.288444) (xy 46.143867 -382.314558)
			(xy 46.187484 -382.347212) (xy 46.22601 -382.385741) (xy 46.25866 -382.429361) (xy 46.28477 -382.477184)
			(xy 46.303808 -382.528235) (xy 46.315386 -382.581477) (xy 46.31927 -382.635824) (xy 46.31538 -382.690171)
			(xy 46.303794 -382.743411) (xy 46.28475 -382.79446) (xy 46.258634 -382.842279) (xy 46.225978 -382.885895)
			(xy 46.187448 -382.924419) (xy 46.143827 -382.957068) (xy 46.096003 -382.983176) (xy 46.044951 -383.002212)
			(xy 45.991709 -383.013789) (xy 45.937362 -383.01767) (xy 45.883015 -383.013778) (xy 45.829775 -383.00219)
			(xy 45.778727 -382.983144) (xy 45.730909 -382.957026) (xy 45.708824 -382.941068) (xy 45.689812 -382.927472)
			(xy 45.647929 -382.90674) (xy 45.602961 -382.894014) (xy 45.556424 -382.889724) (xy 45.509887 -382.894014)
			(xy 45.464919 -382.90674) (xy 45.423036 -382.927472) (xy 45.404024 -382.941068) (xy 45.381973 -382.957084)
			(xy 45.334143 -382.983214) (xy 45.283082 -383.00227) (xy 45.229828 -383.013865) (xy 45.175466 -383.017763)
			(xy 45.121102 -383.013884) (xy 45.067844 -383.002307) (xy 45.016776 -382.983268) (xy 44.968938 -382.957155)
			(xy 44.925303 -382.924499) (xy 44.88676 -382.885965) (xy 44.854094 -382.842338) (xy 44.827969 -382.794505)
			(xy 44.808918 -382.743442) (xy 44.797329 -382.690187) (xy 44.793437 -382.635824) (xy 44.415261 -382.635824)
			(xy 44.41137 -382.690169) (xy 44.399785 -382.743406) (xy 44.380742 -382.794454) (xy 44.354628 -382.842271)
			(xy 44.321974 -382.885885) (xy 44.283445 -382.924409) (xy 44.239826 -382.957056) (xy 44.192005 -382.983164)
			(xy 44.140955 -383.0022) (xy 44.087716 -383.013778) (xy 44.033371 -383.017661) (xy 43.979026 -383.01377)
			(xy 43.925788 -383.002184) (xy 43.874741 -382.98314) (xy 43.826924 -382.957025) (xy 43.80484 -382.941068)
			(xy 43.785828 -382.927472) (xy 43.743945 -382.90674) (xy 43.698977 -382.894014) (xy 43.65244 -382.889724)
			(xy 43.605903 -382.894014) (xy 43.560935 -382.90674) (xy 43.519052 -382.927472) (xy 43.50004 -382.941068)
			(xy 43.477988 -382.957085) (xy 43.430158 -382.983218) (xy 43.379095 -383.002276) (xy 43.325839 -383.013873)
			(xy 43.271475 -383.017773) (xy 43.217109 -383.013895) (xy 43.163849 -383.002318) (xy 43.112778 -382.98328)
			(xy 43.064937 -382.957166) (xy 43.0213 -382.924509) (xy 42.982755 -382.885974) (xy 42.950087 -382.842346)
			(xy 42.923961 -382.794512) (xy 42.904909 -382.743446) (xy 42.893319 -382.690189) (xy 42.889427 -382.635824)
			(xy 42.174286 -382.635824) (xy 42.170395 -382.690174) (xy 42.158808 -382.743418) (xy 42.139762 -382.79447)
			(xy 42.113644 -382.842292) (xy 42.080986 -382.88591) (xy 42.042452 -382.924436) (xy 41.998827 -382.957086)
			(xy 41.951 -382.983194) (xy 41.899944 -383.00223) (xy 41.846698 -383.013806) (xy 41.792347 -383.017686)
			(xy 41.737997 -383.013791) (xy 41.684754 -383.0022) (xy 41.633703 -382.98315) (xy 41.585883 -382.957028)
			(xy 41.563798 -382.941068) (xy 41.544786 -382.927472) (xy 41.502903 -382.90674) (xy 41.457935 -382.894014)
			(xy 41.411398 -382.889724) (xy 41.364861 -382.894014) (xy 41.319893 -382.90674) (xy 41.27801 -382.927472)
			(xy 41.258998 -382.941068) (xy 41.236947 -382.957082) (xy 41.18912 -382.983207) (xy 41.138061 -383.00226)
			(xy 41.08481 -383.013852) (xy 41.030451 -383.017747) (xy 40.976091 -383.013867) (xy 40.922837 -383.002289)
			(xy 40.871773 -382.98325) (xy 40.823938 -382.957137) (xy 40.780307 -382.924482) (xy 40.741767 -382.88595)
			(xy 40.709104 -382.842325) (xy 40.682981 -382.794495) (xy 40.663932 -382.743435) (xy 40.652344 -382.690183)
			(xy 40.648453 -382.635824) (xy 40.287593 -382.635824) (xy 40.283702 -382.690176) (xy 40.272115 -382.743421)
			(xy 40.253068 -382.794475) (xy 40.226949 -382.842298) (xy 40.194289 -382.885917) (xy 40.155754 -382.924444)
			(xy 40.112127 -382.957094) (xy 40.064298 -382.983203) (xy 40.01324 -383.002239) (xy 39.959993 -383.013814)
			(xy 39.90564 -383.017693) (xy 39.851288 -383.013797) (xy 39.798044 -383.002205) (xy 39.746992 -382.983153)
			(xy 39.699172 -382.957029) (xy 39.677086 -382.941068) (xy 39.658074 -382.927472) (xy 39.616191 -382.90674)
			(xy 39.571223 -382.894014) (xy 39.524686 -382.889724) (xy 39.478149 -382.894014) (xy 39.433181 -382.90674)
			(xy 39.391298 -382.927472) (xy 39.372286 -382.941068) (xy 39.350236 -382.957081) (xy 39.302409 -382.983204)
			(xy 39.251351 -383.002255) (xy 39.198101 -383.013846) (xy 39.143744 -383.01774) (xy 39.089386 -383.013859)
			(xy 39.036134 -383.00228) (xy 38.985071 -382.983241) (xy 38.937239 -382.957128) (xy 38.893609 -382.924474)
			(xy 38.855071 -382.885943) (xy 38.822408 -382.842319) (xy 38.796287 -382.79449) (xy 38.777239 -382.743432)
			(xy 38.765651 -382.690181) (xy 38.76176 -382.635824) (xy 30.470144 -382.635824) (xy 30.477629 -382.63932)
			(xy 30.520447 -382.650824) (xy 30.542484 -382.653286) (xy 30.586009 -382.65763) (xy 30.672057 -382.673383)
			(xy 30.75627 -382.697061) (xy 30.837919 -382.728458) (xy 30.916299 -382.767304) (xy 30.990731 -382.813261)
			(xy 31.060574 -382.865934) (xy 31.125222 -382.924866) (xy 31.184116 -382.989548) (xy 31.236748 -383.059421)
			(xy 31.282662 -383.133881) (xy 31.321462 -383.212284) (xy 31.352812 -383.293951) (xy 31.37644 -383.378177)
			(xy 31.392143 -383.464234) (xy 31.399785 -383.551377) (xy 31.399988 -383.595118) (xy 31.399336 -383.633488)
			(xy 34.599874 -383.633488) (xy 34.599874 -383.546588) (xy 34.607892 -383.460059) (xy 34.62386 -383.374639)
			(xy 34.647641 -383.291057) (xy 34.679033 -383.210025) (xy 34.717767 -383.132236) (xy 34.763514 -383.058352)
			(xy 34.815883 -382.989005) (xy 34.874427 -382.924785) (xy 34.938647 -382.866241) (xy 35.007994 -382.813872)
			(xy 35.081878 -382.768125) (xy 35.159667 -382.729391) (xy 35.240699 -382.697999) (xy 35.324281 -382.674218)
			(xy 35.409701 -382.65825) (xy 35.49623 -382.650232) (xy 35.58313 -382.650232) (xy 35.669659 -382.65825)
			(xy 35.755079 -382.674218) (xy 35.838661 -382.697999) (xy 35.919693 -382.729391) (xy 35.997482 -382.768125)
			(xy 36.071366 -382.813872) (xy 36.140713 -382.866241) (xy 36.204933 -382.924785) (xy 36.263477 -382.989005)
			(xy 36.315846 -383.058352) (xy 36.361593 -383.132236) (xy 36.400327 -383.210025) (xy 36.431719 -383.291057)
			(xy 36.4555 -383.374639) (xy 36.471468 -383.460059) (xy 36.479486 -383.546588) (xy 36.479988 -383.590038)
			(xy 36.479486 -383.633488) (xy 36.471468 -383.720017) (xy 36.4555 -383.805437) (xy 36.431719 -383.889019)
			(xy 36.400327 -383.970051) (xy 36.361593 -384.04784) (xy 36.315846 -384.121724) (xy 36.263477 -384.191071)
			(xy 36.204933 -384.255291) (xy 36.140713 -384.313835) (xy 36.071366 -384.366204) (xy 35.997482 -384.411951)
			(xy 35.919693 -384.450685) (xy 35.838661 -384.482077) (xy 35.755079 -384.505858) (xy 35.669659 -384.521826)
			(xy 35.58313 -384.529844) (xy 35.49623 -384.529844) (xy 35.409701 -384.521826) (xy 35.324281 -384.505858)
			(xy 35.240699 -384.482077) (xy 35.159667 -384.450685) (xy 35.081878 -384.411951) (xy 35.007994 -384.366204)
			(xy 34.938647 -384.313835) (xy 34.874427 -384.255291) (xy 34.815883 -384.191071) (xy 34.763514 -384.121724)
			(xy 34.717767 -384.04784) (xy 34.679033 -383.970051) (xy 34.647641 -383.889019) (xy 34.62386 -383.805437)
			(xy 34.607892 -383.720017) (xy 34.599874 -383.633488) (xy 31.399336 -383.633488) (xy 31.399242 -383.639021)
			(xy 31.39058 -383.726404) (xy 31.373809 -383.8126) (xy 31.349076 -383.896857) (xy 31.316596 -383.978442)
			(xy 31.276652 -384.056643) (xy 31.229591 -384.13078) (xy 31.175824 -384.200206) (xy 31.115819 -384.264319)
			(xy 31.050099 -384.322557) (xy 30.979235 -384.374416) (xy 30.903846 -384.419443) (xy 30.824587 -384.457245)
			(xy 30.742149 -384.487494) (xy 30.657251 -384.509926) (xy 30.570631 -384.524346) (xy 30.483044 -384.530627)
			(xy 30.395252 -384.528717) (xy 30.308021 -384.51863) (xy 30.222111 -384.500455) (xy 30.138269 -384.47435)
			(xy 30.057225 -384.440543) (xy 30.018228 -384.420364) (xy 29.98425 -384.401842) (xy 29.919144 -384.359998)
			(xy 29.857699 -384.312942) (xy 29.828744 -384.287268) (xy 29.811703 -384.272502) (xy 29.773459 -384.248621)
			(xy 29.731602 -384.231862) (xy 29.687444 -384.222753) (xy 29.642372 -384.221577) (xy 29.5978 -384.228373)
			(xy 29.555126 -384.242928) (xy 29.51569 -384.264783) (xy 29.48073 -384.293254) (xy 29.451341 -384.327447)
			(xy 29.428447 -384.36629) (xy 29.412766 -384.408562) (xy 29.404789 -384.452939) (xy 29.40431 -384.475482)
			(xy 29.40431 -384.536702) (xy 38.761789 -384.536702) (xy 38.765676 -384.482349) (xy 38.777259 -384.429102)
			(xy 38.796303 -384.378046) (xy 38.822418 -384.330219) (xy 38.855075 -384.286596) (xy 38.893608 -384.248065)
			(xy 38.937232 -384.21541) (xy 38.985059 -384.189296) (xy 39.036117 -384.170255) (xy 39.089364 -384.158674)
			(xy 39.143718 -384.154789) (xy 39.198071 -384.158679) (xy 39.251317 -384.170265) (xy 39.302373 -384.189311)
			(xy 39.350198 -384.215429) (xy 39.372286 -384.231388) (xy 39.391298 -384.244984) (xy 39.433181 -384.265716)
			(xy 39.478149 -384.278442) (xy 39.524686 -384.282732) (xy 39.571223 -384.278442) (xy 39.616191 -384.265716)
			(xy 39.658074 -384.244984) (xy 39.677086 -384.231388) (xy 39.699178 -384.215432) (xy 39.747004 -384.18931)
			(xy 39.798062 -384.17026) (xy 39.85131 -384.158671) (xy 39.905666 -384.154778) (xy 39.960023 -384.158661)
			(xy 40.013274 -384.170241) (xy 40.064334 -384.189282) (xy 40.112165 -384.215396) (xy 40.155793 -384.248052)
			(xy 40.194328 -384.286584) (xy 40.226987 -384.330209) (xy 40.253105 -384.378037) (xy 40.27215 -384.429096)
			(xy 40.283734 -384.482346) (xy 40.287622 -384.536702) (xy 40.648481 -384.536702) (xy 40.652369 -384.482347)
			(xy 40.663953 -384.429099) (xy 40.682997 -384.378041) (xy 40.709114 -384.330213) (xy 40.741772 -384.286589)
			(xy 40.780306 -384.248057) (xy 40.823932 -384.215402) (xy 40.871761 -384.189288) (xy 40.92282 -384.170246)
			(xy 40.976069 -384.158666) (xy 41.030425 -384.154781) (xy 41.084779 -384.158673) (xy 41.138027 -384.17026)
			(xy 41.189084 -384.189308) (xy 41.23691 -384.215428) (xy 41.258998 -384.231388) (xy 41.27801 -384.244984)
			(xy 41.319893 -384.265716) (xy 41.364861 -384.278442) (xy 41.411398 -384.282732) (xy 41.457935 -384.278442)
			(xy 41.502903 -384.265716) (xy 41.544786 -384.244984) (xy 41.563798 -384.231388) (xy 41.58589 -384.215433)
			(xy 41.633715 -384.189313) (xy 41.684771 -384.170265) (xy 41.738019 -384.158677) (xy 41.792373 -384.154785)
			(xy 41.846728 -384.158669) (xy 41.899977 -384.17025) (xy 41.951036 -384.189291) (xy 41.998865 -384.215404)
			(xy 42.042491 -384.248059) (xy 42.081025 -384.286591) (xy 42.113682 -384.330215) (xy 42.139799 -384.378042)
			(xy 42.158843 -384.429099) (xy 42.170427 -384.482348) (xy 42.174315 -384.536702) (xy 42.889456 -384.536702)
			(xy 42.893344 -384.482342) (xy 42.90493 -384.429087) (xy 42.923977 -384.378024) (xy 42.950097 -384.330192)
			(xy 42.98276 -384.286564) (xy 43.021299 -384.24803) (xy 43.064931 -384.215372) (xy 43.112766 -384.189257)
			(xy 43.163832 -384.170217) (xy 43.217087 -384.158638) (xy 43.271448 -384.154756) (xy 43.325809 -384.158651)
			(xy 43.379061 -384.170244) (xy 43.430122 -384.189298) (xy 43.477951 -384.215425) (xy 43.50004 -384.231388)
			(xy 43.519052 -384.244984) (xy 43.560935 -384.265716) (xy 43.605903 -384.278442) (xy 43.65244 -384.282732)
			(xy 43.698977 -384.278442) (xy 43.743945 -384.265716) (xy 43.785828 -384.244984) (xy 43.80484 -384.231388)
			(xy 43.826931 -384.215437) (xy 43.874753 -384.189323) (xy 43.925806 -384.170281) (xy 43.979048 -384.158698)
			(xy 44.033397 -384.154811) (xy 44.087746 -384.158697) (xy 44.140989 -384.170279) (xy 44.192041 -384.189321)
			(xy 44.239864 -384.215434) (xy 44.283484 -384.248087) (xy 44.322013 -384.286616) (xy 44.354666 -384.330235)
			(xy 44.380779 -384.378058) (xy 44.399821 -384.429111) (xy 44.411403 -384.482353) (xy 44.415289 -384.536702)
			(xy 44.793466 -384.536702) (xy 44.797354 -384.482344) (xy 44.808938 -384.429092) (xy 44.827984 -384.378031)
			(xy 44.854103 -384.3302) (xy 44.886764 -384.286574) (xy 44.925302 -384.24804) (xy 44.968931 -384.215384)
			(xy 45.016764 -384.189269) (xy 45.067827 -384.170228) (xy 45.12108 -384.158648) (xy 45.175439 -384.154766)
			(xy 45.229798 -384.15866) (xy 45.283048 -384.17025) (xy 45.334107 -384.189302) (xy 45.381935 -384.215426)
			(xy 45.404024 -384.231388) (xy 45.423036 -384.244984) (xy 45.464919 -384.265716) (xy 45.509887 -384.278442)
			(xy 45.556424 -384.282732) (xy 45.602961 -384.278442) (xy 45.647929 -384.265716) (xy 45.689812 -384.244984)
			(xy 45.708824 -384.231388) (xy 45.730915 -384.215435) (xy 45.778739 -384.189319) (xy 45.829793 -384.170275)
			(xy 45.883037 -384.15869) (xy 45.937388 -384.154801) (xy 45.991739 -384.158687) (xy 46.044984 -384.170268)
			(xy 46.096039 -384.189309) (xy 46.143864 -384.215423) (xy 46.187486 -384.248076) (xy 46.226017 -384.286606)
			(xy 46.258672 -384.330227) (xy 46.284787 -384.378052) (xy 46.303829 -384.429106) (xy 46.315412 -384.482351)
			(xy 46.319299 -384.536702) (xy 46.317781 -384.557918) (xy 76.158023 -384.557918) (xy 76.158023 -384.494682)
			(xy 76.166277 -384.431986) (xy 76.182645 -384.370905) (xy 76.206845 -384.312483) (xy 76.238465 -384.257719)
			(xy 76.276962 -384.207552) (xy 76.321679 -384.162838) (xy 76.371849 -384.124345) (xy 76.426615 -384.092729)
			(xy 76.485039 -384.068533) (xy 76.546122 -384.05217) (xy 76.608818 -384.04392) (xy 76.640436 -384.043428)
			(xy 77.593444 -384.043428) (xy 77.621706 -384.043833) (xy 77.677848 -384.050401) (xy 77.732836 -384.063488)
			(xy 77.785917 -384.082916) (xy 77.836362 -384.108417) (xy 77.860144 -384.123692) (xy 77.892148 -384.144774)
			(xy 78.054962 -384.144774) (xy 78.088744 -384.119374) (xy 78.115223 -384.100191) (xy 78.172164 -384.068049)
			(xy 78.232756 -384.043474) (xy 78.296 -384.026872) (xy 78.360851 -384.018518) (xy 78.393544 -384.018028)
			(xy 79.729076 -384.018028) (xy 79.761022 -384.018543) (xy 79.824411 -384.026549) (xy 79.886297 -384.042435)
			(xy 79.945703 -384.065954) (xy 80.001694 -384.096732) (xy 80.053385 -384.134286) (xy 80.099961 -384.178022)
			(xy 80.140689 -384.227251) (xy 80.174925 -384.281197) (xy 80.20213 -384.339008) (xy 80.221874 -384.399773)
			(xy 80.233847 -384.462534) (xy 80.237859 -384.5263) (xy 80.233847 -384.590066) (xy 80.221874 -384.652827)
			(xy 80.20213 -384.713592) (xy 80.174925 -384.771403) (xy 80.140689 -384.825349) (xy 80.099961 -384.874578)
			(xy 80.053385 -384.918314) (xy 80.001694 -384.955868) (xy 79.945703 -384.986646) (xy 79.886297 -385.010165)
			(xy 79.824411 -385.026051) (xy 79.761022 -385.034057) (xy 79.729076 -385.034536) (xy 78.393544 -385.034536)
			(xy 78.39329 -385.034536) (xy 78.360622 -385.034041) (xy 78.295824 -385.025667) (xy 78.232634 -385.009058)
			(xy 78.172093 -384.984488) (xy 78.1152 -384.952362) (xy 78.088744 -384.93319) (xy 78.054962 -384.90779)
			(xy 77.892148 -384.90779) (xy 77.860144 -384.928872) (xy 77.836348 -384.944121) (xy 77.785895 -384.969598)
			(xy 77.732817 -384.98902) (xy 77.677837 -385.002123) (xy 77.621704 -385.008727) (xy 77.593444 -385.009136)
			(xy 76.640436 -385.009136) (xy 76.608818 -385.00868) (xy 76.546122 -385.00043) (xy 76.485039 -384.984067)
			(xy 76.426615 -384.959871) (xy 76.371849 -384.928255) (xy 76.321679 -384.889762) (xy 76.276962 -384.845048)
			(xy 76.238465 -384.794881) (xy 76.206845 -384.740117) (xy 76.182645 -384.681695) (xy 76.166277 -384.620614)
			(xy 76.158023 -384.557918) (xy 46.317781 -384.557918) (xy 46.315411 -384.591054) (xy 46.303828 -384.644298)
			(xy 46.284785 -384.695352) (xy 46.25867 -384.743177) (xy 46.226014 -384.786797) (xy 46.187483 -384.825327)
			(xy 46.14386 -384.85798) (xy 46.096035 -384.884093) (xy 46.04498 -384.903133) (xy 45.991735 -384.914714)
			(xy 45.937383 -384.918599) (xy 45.883032 -384.914709) (xy 45.829788 -384.903124) (xy 45.778735 -384.884079)
			(xy 45.730911 -384.857962) (xy 45.708824 -384.842004) (xy 45.689812 -384.828408) (xy 45.647929 -384.807676)
			(xy 45.602961 -384.79495) (xy 45.556424 -384.79066) (xy 45.509887 -384.79495) (xy 45.464919 -384.807676)
			(xy 45.423036 -384.828408) (xy 45.404024 -384.842004) (xy 45.381939 -384.857971) (xy 45.334112 -384.884096)
			(xy 45.283053 -384.903149) (xy 45.229802 -384.91474) (xy 45.175444 -384.918634) (xy 45.121085 -384.914752)
			(xy 45.067832 -384.903173) (xy 45.016769 -384.884133) (xy 44.968935 -384.858019) (xy 44.925305 -384.825363)
			(xy 44.886767 -384.78683) (xy 44.854106 -384.743204) (xy 44.827986 -384.695374) (xy 44.80894 -384.644313)
			(xy 44.797354 -384.591061) (xy 44.793466 -384.536702) (xy 44.415289 -384.536702) (xy 44.411402 -384.591051)
			(xy 44.399819 -384.644294) (xy 44.380777 -384.695346) (xy 44.354663 -384.743169) (xy 44.32201 -384.786788)
			(xy 44.28348 -384.825316) (xy 44.23986 -384.857969) (xy 44.192037 -384.884081) (xy 44.140984 -384.903122)
			(xy 44.087741 -384.914703) (xy 44.033392 -384.918589) (xy 43.979043 -384.914701) (xy 43.925801 -384.903118)
			(xy 43.874749 -384.884075) (xy 43.826927 -384.857961) (xy 43.80484 -384.842004) (xy 43.785828 -384.828408)
			(xy 43.743945 -384.807676) (xy 43.698977 -384.79495) (xy 43.65244 -384.79066) (xy 43.605903 -384.79495)
			(xy 43.560935 -384.807676) (xy 43.519052 -384.828408) (xy 43.50004 -384.842004) (xy 43.477955 -384.857973)
			(xy 43.430126 -384.8841) (xy 43.379066 -384.903155) (xy 43.325813 -384.914748) (xy 43.271453 -384.918644)
			(xy 43.217092 -384.914763) (xy 43.163836 -384.903185) (xy 43.112771 -384.884145) (xy 43.064935 -384.85803)
			(xy 43.021303 -384.825374) (xy 42.982763 -384.786839) (xy 42.9501 -384.743212) (xy 42.923979 -384.69538)
			(xy 42.904931 -384.644317) (xy 42.893345 -384.591063) (xy 42.889456 -384.536702) (xy 42.174315 -384.536702)
			(xy 42.170426 -384.591057) (xy 42.158842 -384.644305) (xy 42.139797 -384.695362) (xy 42.11368 -384.74319)
			(xy 42.081021 -384.786813) (xy 42.042487 -384.825344) (xy 41.998861 -384.857998) (xy 41.951032 -384.884111)
			(xy 41.899973 -384.903152) (xy 41.846723 -384.914731) (xy 41.792368 -384.918615) (xy 41.738014 -384.914722)
			(xy 41.684767 -384.903134) (xy 41.633711 -384.884085) (xy 41.585886 -384.857964) (xy 41.563798 -384.842004)
			(xy 41.544786 -384.828408) (xy 41.502903 -384.807676) (xy 41.457935 -384.79495) (xy 41.411398 -384.79066)
			(xy 41.364861 -384.79495) (xy 41.319893 -384.807676) (xy 41.27801 -384.828408) (xy 41.258998 -384.842004)
			(xy 41.236914 -384.857969) (xy 41.189088 -384.88409) (xy 41.138032 -384.903139) (xy 41.084784 -384.914727)
			(xy 41.030429 -384.918619) (xy 40.976074 -384.914735) (xy 40.922825 -384.903155) (xy 40.871765 -384.884114)
			(xy 40.823936 -384.858001) (xy 40.780309 -384.825346) (xy 40.741775 -384.786815) (xy 40.709116 -384.743191)
			(xy 40.682999 -384.695364) (xy 40.663954 -384.644306) (xy 40.65237 -384.591057) (xy 40.648481 -384.536702)
			(xy 40.287622 -384.536702) (xy 40.283733 -384.591059) (xy 40.272149 -384.644308) (xy 40.253103 -384.695367)
			(xy 40.226985 -384.743196) (xy 40.194325 -384.78682) (xy 40.155789 -384.825352) (xy 40.112161 -384.858007)
			(xy 40.06433 -384.88412) (xy 40.013269 -384.90316) (xy 39.960018 -384.914739) (xy 39.905662 -384.918622)
			(xy 39.851306 -384.914728) (xy 39.798057 -384.903139) (xy 39.747 -384.884088) (xy 39.699174 -384.857965)
			(xy 39.677086 -384.842004) (xy 39.658074 -384.828408) (xy 39.616191 -384.807676) (xy 39.571223 -384.79495)
			(xy 39.524686 -384.79066) (xy 39.478149 -384.79495) (xy 39.433181 -384.807676) (xy 39.391298 -384.828408)
			(xy 39.372286 -384.842004) (xy 39.350202 -384.857968) (xy 39.302377 -384.884087) (xy 39.251322 -384.903134)
			(xy 39.198076 -384.914721) (xy 39.143722 -384.918611) (xy 39.089369 -384.914727) (xy 39.036121 -384.903147)
			(xy 38.985064 -384.884106) (xy 38.937236 -384.857992) (xy 38.893611 -384.825338) (xy 38.855078 -384.786807)
			(xy 38.822421 -384.743185) (xy 38.796305 -384.695359) (xy 38.77726 -384.644303) (xy 38.765677 -384.591056)
			(xy 38.761789 -384.536702) (xy 29.40431 -384.536702) (xy 29.40431 -385.244594) (xy 29.404797 -385.267138)
			(xy 29.412756 -385.311518) (xy 29.428424 -385.353796) (xy 29.451309 -385.392644) (xy 29.480693 -385.426842)
			(xy 29.515653 -385.455316) (xy 29.55509 -385.477171) (xy 29.597766 -385.491721) (xy 29.64234 -385.498508)
			(xy 29.687412 -385.49732) (xy 29.731567 -385.488194) (xy 29.773417 -385.471417) (xy 29.811648 -385.447515)
			(xy 29.828744 -385.432808) (xy 29.861244 -385.404069) (xy 29.930663 -385.352024) (xy 30.004582 -385.306596)
			(xy 30.082372 -385.268171) (xy 30.16337 -385.237075) (xy 30.246889 -385.213573) (xy 30.332218 -385.197866)
			(xy 30.41863 -385.190085) (xy 30.505393 -385.190299) (xy 30.591766 -385.198504) (xy 30.677016 -385.214631)
			(xy 30.760419 -385.238543) (xy 30.841263 -385.270037) (xy 30.918863 -385.308845) (xy 30.992557 -385.354636)
			(xy 31.06172 -385.407021) (xy 31.125763 -385.465555) (xy 31.184141 -385.52974) (xy 31.236358 -385.59903)
			(xy 31.28197 -385.672836) (xy 31.320588 -385.75053) (xy 31.351885 -385.831451) (xy 31.375595 -385.914911)
			(xy 31.391515 -386.0002) (xy 31.39951 -386.086593) (xy 31.399512 -386.173356) (xy 31.3995 -386.173488)
			(xy 34.599874 -386.173488) (xy 34.599874 -386.086588) (xy 34.607892 -386.000059) (xy 34.62386 -385.914639)
			(xy 34.647641 -385.831057) (xy 34.679033 -385.750025) (xy 34.717767 -385.672236) (xy 34.763514 -385.598352)
			(xy 34.815883 -385.529005) (xy 34.874427 -385.464785) (xy 34.938647 -385.406241) (xy 35.007994 -385.353872)
			(xy 35.081878 -385.308125) (xy 35.159667 -385.269391) (xy 35.240699 -385.237999) (xy 35.324281 -385.214218)
			(xy 35.409701 -385.19825) (xy 35.49623 -385.190232) (xy 35.58313 -385.190232) (xy 35.669659 -385.19825)
			(xy 35.755079 -385.214218) (xy 35.838661 -385.237999) (xy 35.919693 -385.269391) (xy 35.997482 -385.308125)
			(xy 36.071366 -385.353872) (xy 36.140713 -385.406241) (xy 36.204933 -385.464785) (xy 36.263477 -385.529005)
			(xy 36.315846 -385.598352) (xy 36.361593 -385.672236) (xy 36.400327 -385.750025) (xy 36.431719 -385.831057)
			(xy 36.4555 -385.914639) (xy 36.471468 -386.000059) (xy 36.479486 -386.086588) (xy 36.479988 -386.130038)
			(xy 36.479486 -386.173488) (xy 36.475937 -386.211784) (xy 38.761813 -386.211784) (xy 38.765702 -386.157435)
			(xy 38.777287 -386.104191) (xy 38.796332 -386.053139) (xy 38.822448 -386.005317) (xy 38.855105 -385.961698)
			(xy 38.893637 -385.923171) (xy 38.93726 -385.890521) (xy 38.985086 -385.864411) (xy 39.036141 -385.845373)
			(xy 39.089385 -385.833795) (xy 39.143736 -385.829913) (xy 39.198085 -385.833805) (xy 39.251328 -385.845393)
			(xy 39.302379 -385.86444) (xy 39.3502 -385.890559) (xy 39.372286 -385.906518) (xy 39.391298 -385.920114)
			(xy 39.433181 -385.940846) (xy 39.478149 -385.953572) (xy 39.524686 -385.957862) (xy 39.571223 -385.953572)
			(xy 39.616191 -385.940846) (xy 39.658074 -385.920114) (xy 39.677086 -385.906518) (xy 39.69915 -385.890522)
			(xy 39.746978 -385.864395) (xy 39.798038 -385.845342) (xy 39.851289 -385.83375) (xy 39.905648 -385.829854)
			(xy 39.960009 -385.833735) (xy 40.013263 -385.845313) (xy 40.064328 -385.864353) (xy 40.112163 -385.890466)
			(xy 40.155795 -385.923122) (xy 40.194334 -385.961655) (xy 40.226998 -386.00528) (xy 40.253119 -386.053111)
			(xy 40.272168 -386.104172) (xy 40.283755 -386.157425) (xy 40.287646 -386.211784) (xy 40.648505 -386.211784)
			(xy 40.652395 -386.157433) (xy 40.663981 -386.104188) (xy 40.683026 -386.053134) (xy 40.709144 -386.005311)
			(xy 40.741802 -385.961691) (xy 40.780335 -385.923164) (xy 40.82396 -385.890512) (xy 40.871787 -385.864402)
			(xy 40.922844 -385.845364) (xy 40.97609 -385.833787) (xy 41.030443 -385.829905) (xy 41.084794 -385.833799)
			(xy 41.138038 -385.845388) (xy 41.18909 -385.864437) (xy 41.236912 -385.890558) (xy 41.258998 -385.906518)
			(xy 41.27801 -385.920114) (xy 41.319893 -385.940846) (xy 41.364861 -385.953572) (xy 41.411398 -385.957862)
			(xy 41.457935 -385.953572) (xy 41.502903 -385.940846) (xy 41.544786 -385.920114) (xy 41.563798 -385.906518)
			(xy 41.585862 -385.890523) (xy 41.633689 -385.864398) (xy 41.684747 -385.845347) (xy 41.737998 -385.833756)
			(xy 41.792355 -385.829861) (xy 41.846714 -385.833743) (xy 41.899967 -385.845322) (xy 41.951029 -385.864361)
			(xy 41.998863 -385.890474) (xy 42.042493 -385.923129) (xy 42.081031 -385.961662) (xy 42.113693 -386.005286)
			(xy 42.139814 -386.053116) (xy 42.158861 -386.104175) (xy 42.170448 -386.157426) (xy 42.174339 -386.211784)
			(xy 42.88948 -386.211784) (xy 42.893371 -386.157427) (xy 42.904958 -386.104177) (xy 42.924006 -386.053118)
			(xy 42.950127 -386.00529) (xy 42.98279 -385.961667) (xy 43.021329 -385.923136) (xy 43.064959 -385.890483)
			(xy 43.112793 -385.864372) (xy 43.163856 -385.845335) (xy 43.217108 -385.833759) (xy 43.271466 -385.82988)
			(xy 43.325823 -385.833778) (xy 43.379072 -385.845372) (xy 43.430128 -385.864427) (xy 43.477953 -385.890555)
			(xy 43.50004 -385.906518) (xy 43.519052 -385.920114) (xy 43.560935 -385.940846) (xy 43.605903 -385.953572)
			(xy 43.65244 -385.957862) (xy 43.698977 -385.953572) (xy 43.743945 -385.940846) (xy 43.785828 -385.920114)
			(xy 43.80484 -385.906518) (xy 43.826903 -385.890526) (xy 43.874727 -385.864409) (xy 43.925782 -385.845363)
			(xy 43.979027 -385.833777) (xy 44.033379 -385.829887) (xy 44.087732 -385.833771) (xy 44.140978 -385.845351)
			(xy 44.192035 -385.864391) (xy 44.239862 -385.890504) (xy 44.283486 -385.923157) (xy 44.322019 -385.961686)
			(xy 44.354676 -386.005307) (xy 44.380794 -386.053132) (xy 44.399839 -386.104187) (xy 44.411424 -386.157432)
			(xy 44.415313 -386.211784) (xy 44.79349 -386.211784) (xy 44.79738 -386.157429) (xy 44.808966 -386.104181)
			(xy 44.828014 -386.053124) (xy 44.854133 -386.005298) (xy 44.886794 -385.961676) (xy 44.925331 -385.923146)
			(xy 44.968959 -385.890494) (xy 45.016791 -385.864383) (xy 45.067851 -385.845346) (xy 45.121101 -385.83377)
			(xy 45.175457 -385.82989) (xy 45.229812 -385.833786) (xy 45.283059 -385.845378) (xy 45.334114 -385.864431)
			(xy 45.381937 -385.890556) (xy 45.404024 -385.906518) (xy 45.423036 -385.920114) (xy 45.464919 -385.940846)
			(xy 45.509887 -385.953572) (xy 45.556424 -385.957862) (xy 45.602961 -385.953572) (xy 45.647929 -385.940846)
			(xy 45.689812 -385.920114) (xy 45.708824 -385.906518) (xy 45.730887 -385.890525) (xy 45.778713 -385.864405)
			(xy 45.829769 -385.845357) (xy 45.883016 -385.833769) (xy 45.93737 -385.829877) (xy 45.991725 -385.83376)
			(xy 46.044974 -385.84534) (xy 46.096033 -385.86438) (xy 46.143862 -385.890493) (xy 46.187489 -385.923147)
			(xy 46.226024 -385.961677) (xy 46.258683 -386.005299) (xy 46.284801 -386.053126) (xy 46.303847 -386.104182)
			(xy 46.315433 -386.15743) (xy 46.319323 -386.211784) (xy 46.315438 -386.266139) (xy 46.303856 -386.319388)
			(xy 46.284814 -386.370446) (xy 46.2587 -386.418274) (xy 46.226044 -386.461899) (xy 46.187512 -386.500433)
			(xy 46.143889 -386.533091) (xy 46.096061 -386.559207) (xy 46.045004 -386.578251) (xy 45.991756 -386.589835)
			(xy 45.937401 -386.593723) (xy 45.883047 -386.589836) (xy 45.829799 -386.578252) (xy 45.778741 -386.559208)
			(xy 45.730913 -386.533092) (xy 45.708824 -386.517134) (xy 45.689812 -386.503538) (xy 45.647929 -386.482806)
			(xy 45.602961 -386.47008) (xy 45.556424 -386.46579) (xy 45.509887 -386.47008) (xy 45.464919 -386.482806)
			(xy 45.423036 -386.503538) (xy 45.404024 -386.517134) (xy 45.381911 -386.533061) (xy 45.334085 -386.559182)
			(xy 45.283029 -386.578231) (xy 45.229781 -386.589819) (xy 45.175426 -386.59371) (xy 45.121071 -386.589826)
			(xy 45.067821 -386.578245) (xy 45.016762 -386.559204) (xy 44.968933 -386.533089) (xy 44.925307 -386.500433)
			(xy 44.886774 -386.4619) (xy 44.854117 -386.418276) (xy 44.828001 -386.370447) (xy 44.808958 -386.319389)
			(xy 44.797376 -386.26614) (xy 44.79349 -386.211784) (xy 44.415313 -386.211784) (xy 44.411428 -386.266137)
			(xy 44.399847 -386.319383) (xy 44.380806 -386.37044) (xy 44.354693 -386.418266) (xy 44.32204 -386.46189)
			(xy 44.28351 -386.500423) (xy 44.239888 -386.533079) (xy 44.192063 -386.559196) (xy 44.141008 -386.57824)
			(xy 44.087763 -386.589824) (xy 44.03341 -386.593713) (xy 43.979058 -386.589827) (xy 43.925812 -386.578246)
			(xy 43.874756 -386.559204) (xy 43.826929 -386.533091) (xy 43.80484 -386.517134) (xy 43.785828 -386.503538)
			(xy 43.743945 -386.482806) (xy 43.698977 -386.47008) (xy 43.65244 -386.46579) (xy 43.605903 -386.47008)
			(xy 43.560935 -386.482806) (xy 43.519052 -386.503538) (xy 43.50004 -386.517134) (xy 43.477927 -386.533062)
			(xy 43.4301 -386.559186) (xy 43.379042 -386.578237) (xy 43.325792 -386.589827) (xy 43.271435 -386.59372)
			(xy 43.217077 -386.589837) (xy 43.163826 -386.578257) (xy 43.112764 -386.559215) (xy 43.064933 -386.5331)
			(xy 43.021305 -386.500444) (xy 42.982769 -386.46191) (xy 42.95011 -386.418284) (xy 42.923993 -386.370454)
			(xy 42.904949 -386.319393) (xy 42.893366 -386.266142) (xy 42.88948 -386.211784) (xy 42.174339 -386.211784)
			(xy 42.170453 -386.266143) (xy 42.15887 -386.319395) (xy 42.139827 -386.370456) (xy 42.11371 -386.418287)
			(xy 42.081051 -386.461915) (xy 42.042516 -386.50045) (xy 41.998889 -386.533109) (xy 41.951058 -386.559226)
			(xy 41.899997 -386.57827) (xy 41.846745 -386.589853) (xy 41.792386 -386.593739) (xy 41.738028 -386.589849)
			(xy 41.684777 -386.578262) (xy 41.633717 -386.559215) (xy 41.585888 -386.533094) (xy 41.563798 -386.517134)
			(xy 41.544786 -386.503538) (xy 41.502903 -386.482806) (xy 41.457935 -386.47008) (xy 41.411398 -386.46579)
			(xy 41.364861 -386.47008) (xy 41.319893 -386.482806) (xy 41.27801 -386.503538) (xy 41.258998 -386.517134)
			(xy 41.236885 -386.533059) (xy 41.189062 -386.559176) (xy 41.138008 -386.578221) (xy 41.084763 -386.589805)
			(xy 41.030411 -386.593695) (xy 40.97606 -386.589809) (xy 40.922814 -386.578227) (xy 40.871759 -386.559185)
			(xy 40.823934 -386.533071) (xy 40.780312 -386.500416) (xy 40.741781 -386.461885) (xy 40.709127 -386.418263)
			(xy 40.683013 -386.370437) (xy 40.663972 -386.319382) (xy 40.652391 -386.266136) (xy 40.648505 -386.211784)
			(xy 40.287646 -386.211784) (xy 40.28376 -386.266144) (xy 40.272177 -386.319398) (xy 40.253132 -386.370461)
			(xy 40.227015 -386.418293) (xy 40.194355 -386.461922) (xy 40.155818 -386.500458) (xy 40.112189 -386.533117)
			(xy 40.064356 -386.559234) (xy 40.013293 -386.578278) (xy 39.96004 -386.589861) (xy 39.90568 -386.593746)
			(xy 39.85132 -386.589855) (xy 39.798068 -386.578267) (xy 39.747007 -386.559217) (xy 39.699176 -386.533095)
			(xy 39.677086 -386.517134) (xy 39.658074 -386.503538) (xy 39.616191 -386.482806) (xy 39.571223 -386.47008)
			(xy 39.524686 -386.46579) (xy 39.478149 -386.47008) (xy 39.433181 -386.482806) (xy 39.391298 -386.503538)
			(xy 39.372286 -386.517134) (xy 39.350174 -386.533058) (xy 39.302351 -386.559173) (xy 39.251298 -386.578216)
			(xy 39.198054 -386.589799) (xy 39.143704 -386.593687) (xy 39.089354 -386.589801) (xy 39.036111 -386.578218)
			(xy 38.985057 -386.559177) (xy 38.937234 -386.533063) (xy 38.893613 -386.500408) (xy 38.855085 -386.461878)
			(xy 38.822431 -386.418257) (xy 38.796319 -386.370433) (xy 38.777278 -386.319379) (xy 38.765698 -386.266135)
			(xy 38.761813 -386.211784) (xy 36.475937 -386.211784) (xy 36.471468 -386.260017) (xy 36.4555 -386.345437)
			(xy 36.431719 -386.429019) (xy 36.400327 -386.510051) (xy 36.361593 -386.58784) (xy 36.315846 -386.661724)
			(xy 36.263477 -386.731071) (xy 36.204933 -386.795291) (xy 36.140713 -386.853835) (xy 36.071366 -386.906204)
			(xy 35.997482 -386.951951) (xy 35.919693 -386.990685) (xy 35.838661 -387.022077) (xy 35.755079 -387.045858)
			(xy 35.669659 -387.061826) (xy 35.58313 -387.069844) (xy 35.49623 -387.069844) (xy 35.409701 -387.061826)
			(xy 35.324281 -387.045858) (xy 35.240699 -387.022077) (xy 35.159667 -386.990685) (xy 35.081878 -386.951951)
			(xy 35.007994 -386.906204) (xy 34.938647 -386.853835) (xy 34.874427 -386.795291) (xy 34.815883 -386.731071)
			(xy 34.763514 -386.661724) (xy 34.717767 -386.58784) (xy 34.679033 -386.510051) (xy 34.647641 -386.429019)
			(xy 34.62386 -386.345437) (xy 34.607892 -386.260017) (xy 34.599874 -386.173488) (xy 31.3995 -386.173488)
			(xy 31.391522 -386.259749) (xy 31.375606 -386.34504) (xy 31.351902 -386.428501) (xy 31.320609 -386.509424)
			(xy 31.281995 -386.587119) (xy 31.236387 -386.660928) (xy 31.184174 -386.73022) (xy 31.125799 -386.794409)
			(xy 31.061759 -386.852946) (xy 30.992599 -386.905335) (xy 30.918907 -386.95113) (xy 30.84131 -386.989942)
			(xy 30.760467 -387.02144) (xy 30.677066 -387.045357) (xy 30.591817 -387.061489) (xy 30.505444 -387.069699)
			(xy 30.418681 -387.069917) (xy 30.332268 -387.062141) (xy 30.246939 -387.046438) (xy 30.163419 -387.022941)
			(xy 30.082418 -386.99185) (xy 30.004627 -386.953429) (xy 29.930705 -386.908005) (xy 29.861283 -386.855964)
			(xy 29.828744 -386.827268) (xy 29.811703 -386.812502) (xy 29.773459 -386.788621) (xy 29.731602 -386.771862)
			(xy 29.687444 -386.762753) (xy 29.642372 -386.761577) (xy 29.5978 -386.768373) (xy 29.555126 -386.782928)
			(xy 29.51569 -386.804783) (xy 29.48073 -386.833254) (xy 29.451341 -386.867447) (xy 29.428447 -386.90629)
			(xy 29.412766 -386.948562) (xy 29.404789 -386.992939) (xy 29.40431 -387.015482) (xy 29.40431 -387.229519)
			(xy 76.293395 -387.229519) (xy 76.293395 -387.166281) (xy 76.301649 -387.103583) (xy 76.318017 -387.0425)
			(xy 76.342218 -386.984075) (xy 76.373838 -386.929309) (xy 76.412336 -386.879139) (xy 76.457053 -386.834424)
			(xy 76.507224 -386.795928) (xy 76.561991 -386.76431) (xy 76.620417 -386.740111) (xy 76.681501 -386.723746)
			(xy 76.744199 -386.715493) (xy 76.775818 -386.715) (xy 77.662024 -386.715) (xy 77.690312 -386.71538)
			(xy 77.746507 -386.721933) (xy 77.801549 -386.735018) (xy 77.854681 -386.754455) (xy 77.905174 -386.779975)
			(xy 77.928978 -386.795264) (xy 77.960728 -386.8166) (xy 78.018132 -386.8166) (xy 78.018132 -386.871464)
			(xy 78.037942 -386.893829) (xy 78.072573 -386.942514) (xy 78.100934 -386.995098) (xy 78.122594 -387.050778)
			(xy 78.137222 -387.108705) (xy 78.144595 -387.167994) (xy 78.144599 -387.227739) (xy 78.137235 -387.287028)
			(xy 78.122615 -387.344957) (xy 78.100963 -387.400641) (xy 78.072608 -387.453229) (xy 78.037985 -387.501918)
			(xy 78.018132 -387.524244) (xy 78.018132 -387.579108) (xy 77.960728 -387.579108) (xy 77.928978 -387.600444)
			(xy 77.905175 -387.615731) (xy 77.85467 -387.641221) (xy 77.801537 -387.660645) (xy 77.746499 -387.673736)
			(xy 77.690311 -387.680317) (xy 77.662024 -387.680708) (xy 76.775818 -387.680708) (xy 76.744199 -387.680307)
			(xy 76.681501 -387.672054) (xy 76.620417 -387.655689) (xy 76.561991 -387.63149) (xy 76.507224 -387.599872)
			(xy 76.457053 -387.561376) (xy 76.412336 -387.516661) (xy 76.373838 -387.466491) (xy 76.342218 -387.411725)
			(xy 76.318017 -387.3533) (xy 76.301649 -387.292217) (xy 76.293395 -387.229519) (xy 29.40431 -387.229519)
			(xy 29.40431 -387.784594) (xy 29.404797 -387.807138) (xy 29.412756 -387.851518) (xy 29.428424 -387.893796)
			(xy 29.451309 -387.932644) (xy 29.480693 -387.966842) (xy 29.515653 -387.995316) (xy 29.55509 -388.017171)
			(xy 29.597766 -388.031721) (xy 29.64234 -388.038508) (xy 29.687412 -388.03732) (xy 29.731567 -388.028194)
			(xy 29.773417 -388.011417) (xy 29.811648 -387.987515) (xy 29.828744 -387.972808) (xy 29.861244 -387.944069)
			(xy 29.930663 -387.892024) (xy 30.004582 -387.846596) (xy 30.082372 -387.808171) (xy 30.16337 -387.777075)
			(xy 30.246889 -387.753573) (xy 30.332218 -387.737866) (xy 30.41863 -387.730085) (xy 30.505393 -387.730299)
			(xy 30.591766 -387.738504) (xy 30.677016 -387.754631) (xy 30.760419 -387.778543) (xy 30.841263 -387.810037)
			(xy 30.918863 -387.848845) (xy 30.992557 -387.894636) (xy 31.06172 -387.947021) (xy 31.125763 -388.005555)
			(xy 31.184141 -388.06974) (xy 31.236358 -388.13903) (xy 31.28197 -388.212836) (xy 31.320588 -388.29053)
			(xy 31.351885 -388.371451) (xy 31.375595 -388.454911) (xy 31.391515 -388.5402) (xy 31.39951 -388.626593)
			(xy 31.399512 -388.713356) (xy 31.3995 -388.713488) (xy 34.599874 -388.713488) (xy 34.599874 -388.626588)
			(xy 34.607892 -388.540059) (xy 34.62386 -388.454639) (xy 34.647641 -388.371057) (xy 34.679033 -388.290025)
			(xy 34.717767 -388.212236) (xy 34.763514 -388.138352) (xy 34.815883 -388.069005) (xy 34.874427 -388.004785)
			(xy 34.938647 -387.946241) (xy 35.007994 -387.893872) (xy 35.081878 -387.848125) (xy 35.159667 -387.809391)
			(xy 35.240699 -387.777999) (xy 35.324281 -387.754218) (xy 35.409701 -387.73825) (xy 35.49623 -387.730232)
			(xy 35.58313 -387.730232) (xy 35.669659 -387.73825) (xy 35.755079 -387.754218) (xy 35.838661 -387.777999)
			(xy 35.919693 -387.809391) (xy 35.997482 -387.848125) (xy 36.071366 -387.893872) (xy 36.140713 -387.946241)
			(xy 36.204933 -388.004785) (xy 36.263477 -388.069005) (xy 36.315846 -388.138352) (xy 36.361593 -388.212236)
			(xy 36.366953 -388.223001) (xy 38.718411 -388.223001) (xy 38.722298 -388.168653) (xy 38.73388 -388.11541)
			(xy 38.752921 -388.064358) (xy 38.779034 -388.016536) (xy 38.811687 -387.972916) (xy 38.850215 -387.934388)
			(xy 38.893834 -387.901735) (xy 38.941657 -387.875621) (xy 38.992709 -387.85658) (xy 39.045951 -387.844998)
			(xy 39.1003 -387.841111) (xy 39.154648 -387.844998) (xy 39.20789 -387.85658) (xy 39.258942 -387.875621)
			(xy 39.306765 -387.901734) (xy 39.328852 -387.91769) (xy 39.347864 -387.931286) (xy 39.389747 -387.952018)
			(xy 39.434715 -387.964744) (xy 39.481252 -387.969034) (xy 39.527789 -387.964744) (xy 39.572757 -387.952018)
			(xy 39.61464 -387.931286) (xy 39.633652 -387.91769) (xy 39.655743 -387.901729) (xy 39.703572 -387.875601)
			(xy 39.754632 -387.856546) (xy 39.807885 -387.844952) (xy 39.862246 -387.841056) (xy 39.916608 -387.844937)
			(xy 39.969864 -387.856515) (xy 40.02093 -387.875556) (xy 40.068766 -387.90167) (xy 40.112398 -387.934327)
			(xy 40.150938 -387.972862) (xy 40.183601 -388.01649) (xy 40.209722 -388.064322) (xy 40.22877 -388.115386)
			(xy 40.240356 -388.16864) (xy 40.244244 -388.223001) (xy 40.605103 -388.223001) (xy 40.608991 -388.168651)
			(xy 40.620573 -388.115407) (xy 40.639615 -388.064354) (xy 40.665729 -388.01653) (xy 40.698383 -387.972909)
			(xy 40.736913 -387.93438) (xy 40.780534 -387.901726) (xy 40.828358 -387.875613) (xy 40.879412 -387.856572)
			(xy 40.932656 -387.84499) (xy 40.987006 -387.841103) (xy 41.041357 -387.844992) (xy 41.0946 -387.856575)
			(xy 41.145653 -387.875618) (xy 41.193477 -387.901733) (xy 41.215564 -387.91769) (xy 41.234576 -387.931286)
			(xy 41.276459 -387.952018) (xy 41.321427 -387.964744) (xy 41.367964 -387.969034) (xy 41.414501 -387.964744)
			(xy 41.459469 -387.952018) (xy 41.501352 -387.931286) (xy 41.520364 -387.91769) (xy 41.542455 -387.90173)
			(xy 41.590283 -387.875604) (xy 41.641342 -387.85655) (xy 41.694594 -387.844958) (xy 41.748953 -387.841064)
			(xy 41.803313 -387.844945) (xy 41.856567 -387.856524) (xy 41.907631 -387.875564) (xy 41.955465 -387.901679)
			(xy 41.999096 -387.934335) (xy 42.037635 -387.972869) (xy 42.070297 -388.016496) (xy 42.096417 -388.064327)
			(xy 42.115463 -388.115389) (xy 42.127048 -388.168642) (xy 42.130936 -388.223001) (xy 42.846078 -388.223001)
			(xy 42.849966 -388.168645) (xy 42.86155 -388.115396) (xy 42.880595 -388.064337) (xy 42.906713 -388.016509)
			(xy 42.939371 -387.972885) (xy 42.977907 -387.934352) (xy 43.021533 -387.901697) (xy 43.069364 -387.875583)
			(xy 43.120424 -387.856542) (xy 43.173674 -387.844962) (xy 43.22803 -387.841078) (xy 43.282386 -387.84497)
			(xy 43.335634 -387.856559) (xy 43.386691 -387.875608) (xy 43.434518 -387.90173) (xy 43.456606 -387.91769)
			(xy 43.475618 -387.931286) (xy 43.517501 -387.952018) (xy 43.562469 -387.964744) (xy 43.609006 -387.969034)
			(xy 43.655543 -387.964744) (xy 43.700511 -387.952018) (xy 43.742394 -387.931286) (xy 43.761406 -387.91769)
			(xy 43.783496 -387.901733) (xy 43.831321 -387.875614) (xy 43.882376 -387.856567) (xy 43.935623 -387.84498)
			(xy 43.989977 -387.841089) (xy 44.044331 -387.844973) (xy 44.097579 -387.856553) (xy 44.148636 -387.875594)
			(xy 44.196465 -387.901708) (xy 44.240089 -387.934363) (xy 44.278623 -387.972894) (xy 44.31128 -388.016517)
			(xy 44.337396 -388.064343) (xy 44.35644 -388.1154) (xy 44.368024 -388.168647) (xy 44.371911 -388.223001)
			(xy 44.750088 -388.223001) (xy 44.753975 -388.168647) (xy 44.765559 -388.1154) (xy 44.784603 -388.064344)
			(xy 44.810719 -388.016517) (xy 44.843376 -387.972894) (xy 44.881909 -387.934363) (xy 44.925534 -387.901708)
			(xy 44.973362 -387.875594) (xy 45.024419 -387.856553) (xy 45.077667 -387.844972) (xy 45.132021 -387.841088)
			(xy 45.186375 -387.844978) (xy 45.239621 -387.856565) (xy 45.290677 -387.875612) (xy 45.338502 -387.901731)
			(xy 45.36059 -387.91769) (xy 45.379602 -387.931286) (xy 45.421485 -387.952018) (xy 45.466453 -387.964744)
			(xy 45.51299 -387.969034) (xy 45.559527 -387.964744) (xy 45.604495 -387.952018) (xy 45.646378 -387.931286)
			(xy 45.66539 -387.91769) (xy 45.68748 -387.901732) (xy 45.735306 -387.87561) (xy 45.786363 -387.85656)
			(xy 45.839612 -387.844972) (xy 45.893967 -387.841079) (xy 45.948324 -387.844962) (xy 46.001574 -387.856542)
			(xy 46.052634 -387.875583) (xy 46.100465 -387.901697) (xy 46.144092 -387.934352) (xy 46.182627 -387.972884)
			(xy 46.215286 -388.016509) (xy 46.241404 -388.064337) (xy 46.260449 -388.115396) (xy 46.272033 -388.168645)
			(xy 46.275921 -388.223001) (xy 46.272033 -388.277357) (xy 46.260448 -388.330607) (xy 46.241403 -388.381665)
			(xy 46.215285 -388.429493) (xy 46.182626 -388.473118) (xy 46.14409 -388.511649) (xy 46.100463 -388.544305)
			(xy 46.052632 -388.570418) (xy 46.001572 -388.589459) (xy 45.948321 -388.601038) (xy 45.893965 -388.604921)
			(xy 45.839609 -388.601028) (xy 45.786361 -388.589439) (xy 45.735304 -388.570389) (xy 45.687478 -388.544267)
			(xy 45.66539 -388.528306) (xy 45.646378 -388.51471) (xy 45.604495 -388.493978) (xy 45.559527 -388.481252)
			(xy 45.51299 -388.476962) (xy 45.466453 -388.481252) (xy 45.421485 -388.493978) (xy 45.379602 -388.51471)
			(xy 45.36059 -388.528306) (xy 45.338504 -388.544268) (xy 45.290679 -388.570387) (xy 45.239624 -388.589434)
			(xy 45.186377 -388.601021) (xy 45.132024 -388.604912) (xy 45.07767 -388.601028) (xy 45.024422 -388.589447)
			(xy 44.973364 -388.570407) (xy 44.925536 -388.544293) (xy 44.881911 -388.511639) (xy 44.843378 -388.473108)
			(xy 44.81072 -388.429485) (xy 44.784604 -388.381659) (xy 44.765559 -388.330602) (xy 44.753976 -388.277355)
			(xy 44.750088 -388.223001) (xy 44.371911 -388.223001) (xy 44.368024 -388.277355) (xy 44.35644 -388.330602)
			(xy 44.337395 -388.381659) (xy 44.311279 -388.429485) (xy 44.278621 -388.473108) (xy 44.240088 -388.511639)
			(xy 44.196463 -388.544293) (xy 44.148634 -388.570407) (xy 44.097576 -388.589447) (xy 44.044328 -388.601027)
			(xy 43.989974 -388.604911) (xy 43.935621 -388.60102) (xy 43.882374 -388.589433) (xy 43.831319 -388.570385)
			(xy 43.783494 -388.544265) (xy 43.761406 -388.528306) (xy 43.742394 -388.51471) (xy 43.700511 -388.493978)
			(xy 43.655543 -388.481252) (xy 43.609006 -388.476962) (xy 43.562469 -388.481252) (xy 43.517501 -388.493978)
			(xy 43.475618 -388.51471) (xy 43.456606 -388.528306) (xy 43.43452 -388.544269) (xy 43.386694 -388.570391)
			(xy 43.335637 -388.58944) (xy 43.282388 -388.601029) (xy 43.228033 -388.604922) (xy 43.173676 -388.601039)
			(xy 43.120426 -388.589459) (xy 43.069366 -388.570418) (xy 43.021535 -388.544304) (xy 42.977908 -388.511649)
			(xy 42.939373 -388.473117) (xy 42.906714 -388.429493) (xy 42.880596 -388.381665) (xy 42.861551 -388.330606)
			(xy 42.849966 -388.277357) (xy 42.846078 -388.223001) (xy 42.130936 -388.223001) (xy 42.127048 -388.277361)
			(xy 42.115463 -388.330614) (xy 42.096416 -388.381675) (xy 42.070295 -388.429506) (xy 42.037633 -388.473133)
			(xy 41.999094 -388.511666) (xy 41.955463 -388.544323) (xy 41.907629 -388.570437) (xy 41.856565 -388.589477)
			(xy 41.80331 -388.601055) (xy 41.74895 -388.604936) (xy 41.694591 -388.601041) (xy 41.64134 -388.589449)
			(xy 41.590281 -388.570396) (xy 41.542453 -388.544269) (xy 41.520364 -388.528306) (xy 41.501352 -388.51471)
			(xy 41.459469 -388.493978) (xy 41.414501 -388.481252) (xy 41.367964 -388.476962) (xy 41.321427 -388.481252)
			(xy 41.276459 -388.493978) (xy 41.234576 -388.51471) (xy 41.215564 -388.528306) (xy 41.193479 -388.544266)
			(xy 41.145655 -388.570381) (xy 41.094602 -388.589424) (xy 41.041359 -388.601008) (xy 40.987009 -388.604897)
			(xy 40.932658 -388.601011) (xy 40.879414 -388.589429) (xy 40.828361 -388.570388) (xy 40.780536 -388.544275)
			(xy 40.736915 -388.511622) (xy 40.698385 -388.473093) (xy 40.66573 -388.429472) (xy 40.639616 -388.381649)
			(xy 40.620574 -388.330595) (xy 40.608991 -388.277351) (xy 40.605103 -388.223001) (xy 40.244244 -388.223001)
			(xy 40.240355 -388.277362) (xy 40.228769 -388.330617) (xy 40.209721 -388.38168) (xy 40.1836 -388.429512)
			(xy 40.150937 -388.47314) (xy 40.112396 -388.511674) (xy 40.068764 -388.544331) (xy 40.020927 -388.570445)
			(xy 39.969861 -388.589485) (xy 39.916605 -388.601063) (xy 39.862243 -388.604944) (xy 39.807883 -388.601047)
			(xy 39.75463 -388.589454) (xy 39.70357 -388.570398) (xy 39.655741 -388.54427) (xy 39.633652 -388.528306)
			(xy 39.61464 -388.51471) (xy 39.572757 -388.493978) (xy 39.527789 -388.481252) (xy 39.481252 -388.476962)
			(xy 39.434715 -388.481252) (xy 39.389747 -388.493978) (xy 39.347864 -388.51471) (xy 39.328852 -388.528306)
			(xy 39.306767 -388.544265) (xy 39.258945 -388.570378) (xy 39.207893 -388.58942) (xy 39.154651 -388.601002)
			(xy 39.100302 -388.604889) (xy 39.045953 -388.601003) (xy 38.992711 -388.589421) (xy 38.941659 -388.570379)
			(xy 38.893836 -388.544267) (xy 38.850217 -388.511614) (xy 38.811688 -388.473086) (xy 38.779035 -388.429466)
			(xy 38.752922 -388.381644) (xy 38.73388 -388.330592) (xy 38.722298 -388.27735) (xy 38.718411 -388.223001)
			(xy 36.366953 -388.223001) (xy 36.400327 -388.290025) (xy 36.431719 -388.371057) (xy 36.4555 -388.454639)
			(xy 36.471468 -388.540059) (xy 36.479486 -388.626588) (xy 36.479988 -388.670038) (xy 36.479486 -388.713488)
			(xy 36.471468 -388.800017) (xy 36.4555 -388.885437) (xy 36.431719 -388.969019) (xy 36.400327 -389.050051)
			(xy 36.361593 -389.12784) (xy 36.315846 -389.201724) (xy 36.263477 -389.271071) (xy 36.204933 -389.335291)
			(xy 36.140713 -389.393835) (xy 36.071366 -389.446204) (xy 35.997482 -389.491951) (xy 35.919693 -389.530685)
			(xy 35.838661 -389.562077) (xy 35.755079 -389.585858) (xy 35.669659 -389.601826) (xy 35.58313 -389.609844)
			(xy 35.49623 -389.609844) (xy 35.409701 -389.601826) (xy 35.324281 -389.585858) (xy 35.240699 -389.562077)
			(xy 35.159667 -389.530685) (xy 35.081878 -389.491951) (xy 35.007994 -389.446204) (xy 34.938647 -389.393835)
			(xy 34.874427 -389.335291) (xy 34.815883 -389.271071) (xy 34.763514 -389.201724) (xy 34.717767 -389.12784)
			(xy 34.679033 -389.050051) (xy 34.647641 -388.969019) (xy 34.62386 -388.885437) (xy 34.607892 -388.800017)
			(xy 34.599874 -388.713488) (xy 31.3995 -388.713488) (xy 31.391522 -388.799749) (xy 31.375606 -388.88504)
			(xy 31.351902 -388.968501) (xy 31.320609 -389.049424) (xy 31.281995 -389.127119) (xy 31.236387 -389.200928)
			(xy 31.184174 -389.27022) (xy 31.125799 -389.334409) (xy 31.061759 -389.392946) (xy 30.992599 -389.445335)
			(xy 30.918907 -389.49113) (xy 30.84131 -389.529942) (xy 30.760467 -389.56144) (xy 30.677066 -389.585357)
			(xy 30.591817 -389.601489) (xy 30.505444 -389.609699) (xy 30.418681 -389.609917) (xy 30.332268 -389.602141)
			(xy 30.246939 -389.586438) (xy 30.163419 -389.562941) (xy 30.082418 -389.53185) (xy 30.004627 -389.493429)
			(xy 29.930705 -389.448005) (xy 29.861283 -389.395964) (xy 29.828744 -389.367268) (xy 29.811703 -389.352502)
			(xy 29.773459 -389.328621) (xy 29.731602 -389.311862) (xy 29.687444 -389.302753) (xy 29.642372 -389.301577)
			(xy 29.5978 -389.308373) (xy 29.555126 -389.322928) (xy 29.51569 -389.344783) (xy 29.48073 -389.373254)
			(xy 29.451341 -389.407447) (xy 29.428447 -389.44629) (xy 29.412766 -389.488562) (xy 29.404789 -389.532939)
			(xy 29.40431 -389.555482) (xy 29.40431 -390.113488) (xy 38.718428 -390.113488) (xy 38.722317 -390.059142)
			(xy 38.7339 -390.005903) (xy 38.752942 -389.954854) (xy 38.779056 -389.907034) (xy 38.811709 -389.863418)
			(xy 38.850237 -389.824892) (xy 38.893855 -389.792242) (xy 38.941676 -389.766132) (xy 38.992726 -389.747093)
			(xy 39.045967 -389.735513) (xy 39.100313 -389.731628) (xy 39.154659 -389.735517) (xy 39.207898 -389.7471)
			(xy 39.258947 -389.766143) (xy 39.306766 -389.792256) (xy 39.328852 -389.808212) (xy 39.347864 -389.821808)
			(xy 39.389747 -389.84254) (xy 39.434715 -389.855266) (xy 39.481252 -389.859556) (xy 39.527789 -389.855266)
			(xy 39.572757 -389.84254) (xy 39.61464 -389.821808) (xy 39.633652 -389.808212) (xy 39.655723 -389.792221)
			(xy 39.703553 -389.76609) (xy 39.754615 -389.747033) (xy 39.80787 -389.735437) (xy 39.862233 -389.731539)
			(xy 39.916597 -389.735418) (xy 39.969856 -389.746995) (xy 40.020925 -389.766034) (xy 40.068764 -389.792148)
			(xy 40.1124 -389.824805) (xy 40.150943 -389.86334) (xy 40.183609 -389.906969) (xy 40.209733 -389.954803)
			(xy 40.228783 -390.005868) (xy 40.240371 -390.059124) (xy 40.244261 -390.113488) (xy 40.605121 -390.113488)
			(xy 40.60901 -390.05914) (xy 40.620594 -390.005899) (xy 40.639637 -389.954849) (xy 40.665751 -389.907028)
			(xy 40.698405 -389.863411) (xy 40.736935 -389.824885) (xy 40.780555 -389.792234) (xy 40.828378 -389.766123)
			(xy 40.87943 -389.747085) (xy 40.932672 -389.735505) (xy 40.98702 -389.731621) (xy 41.041367 -389.735511)
			(xy 41.094608 -389.747096) (xy 41.145658 -389.76614) (xy 41.193478 -389.792255) (xy 41.215564 -389.808212)
			(xy 41.234576 -389.821808) (xy 41.276459 -389.84254) (xy 41.321427 -389.855266) (xy 41.367964 -389.859556)
			(xy 41.414501 -389.855266) (xy 41.459469 -389.84254) (xy 41.501352 -389.821808) (xy 41.520364 -389.808212)
			(xy 41.542434 -389.792222) (xy 41.590263 -389.766093) (xy 41.641325 -389.747037) (xy 41.694578 -389.735443)
			(xy 41.748939 -389.731546) (xy 41.803302 -389.735426) (xy 41.856559 -389.747003) (xy 41.907626 -389.766043)
			(xy 41.955464 -389.792157) (xy 41.999098 -389.824813) (xy 42.037639 -389.863348) (xy 42.070304 -389.906975)
			(xy 42.096427 -389.954808) (xy 42.115476 -390.005871) (xy 42.127064 -390.059126) (xy 42.130954 -390.113488)
			(xy 42.846096 -390.113488) (xy 42.849985 -390.059135) (xy 42.861571 -390.005888) (xy 42.880616 -389.954833)
			(xy 42.906734 -389.907007) (xy 42.939393 -389.863386) (xy 42.977928 -389.824857) (xy 43.021554 -389.792205)
			(xy 43.069383 -389.766093) (xy 43.120441 -389.747055) (xy 43.17369 -389.735477) (xy 43.228043 -389.731596)
			(xy 43.282396 -389.73549) (xy 43.335642 -389.74708) (xy 43.386696 -389.766129) (xy 43.434519 -389.792252)
			(xy 43.456606 -389.808212) (xy 43.475618 -389.821808) (xy 43.517501 -389.84254) (xy 43.562469 -389.855266)
			(xy 43.609006 -389.859556) (xy 43.655543 -389.855266) (xy 43.700511 -389.84254) (xy 43.742394 -389.821808)
			(xy 43.761406 -389.808212) (xy 43.783475 -389.792226) (xy 43.831302 -389.766103) (xy 43.882359 -389.747053)
			(xy 43.935607 -389.735464) (xy 43.989963 -389.731571) (xy 44.04432 -389.735454) (xy 44.097571 -389.747033)
			(xy 44.148632 -389.766073) (xy 44.196463 -389.792186) (xy 44.240091 -389.824841) (xy 44.278627 -389.863372)
			(xy 44.311288 -389.906996) (xy 44.337407 -389.954824) (xy 44.356453 -390.005882) (xy 44.368039 -390.059132)
			(xy 44.371929 -390.113488) (xy 44.750105 -390.113488) (xy 44.753995 -390.059137) (xy 44.765579 -390.005892)
			(xy 44.784624 -389.954839) (xy 44.810741 -389.907015) (xy 44.843398 -389.863396) (xy 44.881931 -389.824868)
			(xy 44.925554 -389.792216) (xy 44.973381 -389.766105) (xy 45.024437 -389.747066) (xy 45.077683 -389.735488)
			(xy 45.132034 -389.731605) (xy 45.186385 -389.735498) (xy 45.239629 -389.747086) (xy 45.290682 -389.766133)
			(xy 45.338504 -389.792253) (xy 45.36059 -389.808212) (xy 45.379602 -389.821808) (xy 45.421485 -389.84254)
			(xy 45.466453 -389.855266) (xy 45.51299 -389.859556) (xy 45.559527 -389.855266) (xy 45.604495 -389.84254)
			(xy 45.646378 -389.821808) (xy 45.66539 -389.808212) (xy 45.68746 -389.792224) (xy 45.735287 -389.766099)
			(xy 45.786346 -389.747047) (xy 45.839596 -389.735456) (xy 45.893954 -389.731561) (xy 45.948313 -389.735443)
			(xy 46.001567 -389.747022) (xy 46.05263 -389.766061) (xy 46.100463 -389.792175) (xy 46.144094 -389.82483)
			(xy 46.182632 -389.863363) (xy 46.215294 -389.906988) (xy 46.241415 -389.954818) (xy 46.260462 -390.005878)
			(xy 46.272049 -390.05913) (xy 46.275939 -390.113488) (xy 46.272052 -390.167847) (xy 46.260469 -390.221099)
			(xy 46.241425 -390.27216) (xy 46.215307 -390.319992) (xy 46.182648 -390.363619) (xy 46.144112 -390.402154)
			(xy 46.100484 -390.434812) (xy 46.052652 -390.460929) (xy 46.00159 -390.479972) (xy 45.948337 -390.491554)
			(xy 45.893978 -390.495439) (xy 45.83962 -390.491547) (xy 45.786369 -390.479959) (xy 45.735309 -390.460911)
			(xy 45.68748 -390.434789) (xy 45.66539 -390.418828) (xy 45.646378 -390.405232) (xy 45.604495 -390.3845)
			(xy 45.559527 -390.371774) (xy 45.51299 -390.367484) (xy 45.466453 -390.371774) (xy 45.421485 -390.3845)
			(xy 45.379602 -390.405232) (xy 45.36059 -390.418828) (xy 45.338483 -390.43476) (xy 45.29066 -390.460877)
			(xy 45.239606 -390.479921) (xy 45.186362 -390.491506) (xy 45.13201 -390.495395) (xy 45.077659 -390.491509)
			(xy 45.024414 -390.479927) (xy 44.973359 -390.460885) (xy 44.925534 -390.434771) (xy 44.881912 -390.402117)
			(xy 44.843382 -390.363586) (xy 44.810728 -390.319965) (xy 44.784614 -390.272139) (xy 44.765573 -390.221085)
			(xy 44.753991 -390.167839) (xy 44.750105 -390.113488) (xy 44.371929 -390.113488) (xy 44.368043 -390.167844)
			(xy 44.35646 -390.221095) (xy 44.337417 -390.272154) (xy 44.311301 -390.319984) (xy 44.278643 -390.36361)
			(xy 44.240109 -390.402144) (xy 44.196483 -390.434801) (xy 44.148654 -390.460917) (xy 44.097594 -390.47996)
			(xy 44.044344 -390.491543) (xy 43.989987 -390.495429) (xy 43.935631 -390.491539) (xy 43.882382 -390.479953)
			(xy 43.831323 -390.460907) (xy 43.783495 -390.434787) (xy 43.761406 -390.418828) (xy 43.742394 -390.405232)
			(xy 43.700511 -390.3845) (xy 43.655543 -390.371774) (xy 43.609006 -390.367484) (xy 43.562469 -390.371774)
			(xy 43.517501 -390.3845) (xy 43.475618 -390.405232) (xy 43.456606 -390.418828) (xy 43.434499 -390.434761)
			(xy 43.386674 -390.460881) (xy 43.335619 -390.479927) (xy 43.282373 -390.491514) (xy 43.228019 -390.495404)
			(xy 43.173666 -390.491519) (xy 43.120418 -390.479938) (xy 43.069361 -390.460897) (xy 43.021534 -390.434783)
			(xy 42.97791 -390.402127) (xy 42.939378 -390.363596) (xy 42.906722 -390.319972) (xy 42.880606 -390.272146)
			(xy 42.861564 -390.221089) (xy 42.849982 -390.167842) (xy 42.846096 -390.113488) (xy 42.130954 -390.113488)
			(xy 42.127067 -390.16785) (xy 42.115483 -390.221106) (xy 42.096437 -390.272171) (xy 42.070317 -390.320005)
			(xy 42.037655 -390.363634) (xy 41.999116 -390.402171) (xy 41.955484 -390.43483) (xy 41.907648 -390.460947)
			(xy 41.856582 -390.47999) (xy 41.803326 -390.491571) (xy 41.748963 -390.495454) (xy 41.694602 -390.491561)
			(xy 41.641348 -390.47997) (xy 41.590285 -390.460917) (xy 41.542454 -390.434791) (xy 41.520364 -390.418828)
			(xy 41.501352 -390.405232) (xy 41.459469 -390.3845) (xy 41.414501 -390.371774) (xy 41.367964 -390.367484)
			(xy 41.321427 -390.371774) (xy 41.276459 -390.3845) (xy 41.234576 -390.405232) (xy 41.215564 -390.418828)
			(xy 41.193458 -390.434758) (xy 41.145636 -390.46087) (xy 41.094585 -390.479911) (xy 41.041343 -390.491492)
			(xy 40.986996 -390.495379) (xy 40.932648 -390.491491) (xy 40.879407 -390.479909) (xy 40.828356 -390.460867)
			(xy 40.780535 -390.434753) (xy 40.736917 -390.4021) (xy 40.69839 -390.363571) (xy 40.665738 -390.319952)
			(xy 40.639627 -390.272129) (xy 40.620587 -390.221078) (xy 40.609006 -390.167836) (xy 40.605121 -390.113488)
			(xy 40.244261 -390.113488) (xy 40.240374 -390.167852) (xy 40.22879 -390.221109) (xy 40.209743 -390.272175)
			(xy 40.183622 -390.320011) (xy 40.150958 -390.363641) (xy 40.112418 -390.402179) (xy 40.068784 -390.434839)
			(xy 40.020947 -390.460956) (xy 39.969879 -390.479999) (xy 39.916621 -390.491579) (xy 39.862257 -390.495461)
			(xy 39.807893 -390.491567) (xy 39.754638 -390.479974) (xy 39.703574 -390.46092) (xy 39.655743 -390.434792)
			(xy 39.633652 -390.418828) (xy 39.61464 -390.405232) (xy 39.572757 -390.3845) (xy 39.527789 -390.371774)
			(xy 39.481252 -390.367484) (xy 39.434715 -390.371774) (xy 39.389747 -390.3845) (xy 39.347864 -390.405232)
			(xy 39.328852 -390.418828) (xy 39.306746 -390.434757) (xy 39.258925 -390.460867) (xy 39.207875 -390.479906)
			(xy 39.154635 -390.491486) (xy 39.100289 -390.495372) (xy 39.045943 -390.491483) (xy 38.992703 -390.4799)
			(xy 38.941654 -390.460858) (xy 38.893835 -390.434745) (xy 38.850218 -390.402092) (xy 38.811693 -390.363564)
			(xy 38.779043 -390.319946) (xy 38.752932 -390.272125) (xy 38.733893 -390.221074) (xy 38.722313 -390.167834)
			(xy 38.718428 -390.113488) (xy 29.40431 -390.113488) (xy 29.40431 -390.324594) (xy 29.404797 -390.347138)
			(xy 29.412756 -390.391518) (xy 29.428424 -390.433796) (xy 29.451309 -390.472644) (xy 29.480693 -390.506842)
			(xy 29.515653 -390.535316) (xy 29.55509 -390.557171) (xy 29.597766 -390.571721) (xy 29.64234 -390.578508)
			(xy 29.687412 -390.57732) (xy 29.731567 -390.568194) (xy 29.773417 -390.551417) (xy 29.811648 -390.527515)
			(xy 29.828744 -390.512808) (xy 29.861244 -390.484069) (xy 29.930663 -390.432024) (xy 30.004582 -390.386596)
			(xy 30.082372 -390.348171) (xy 30.16337 -390.317075) (xy 30.246889 -390.293573) (xy 30.332218 -390.277866)
			(xy 30.41863 -390.270085) (xy 30.505393 -390.270299) (xy 30.591766 -390.278504) (xy 30.677016 -390.294631)
			(xy 30.760419 -390.318543) (xy 30.841263 -390.350037) (xy 30.918863 -390.388845) (xy 30.992557 -390.434636)
			(xy 31.06172 -390.487021) (xy 31.125763 -390.545555) (xy 31.184141 -390.60974) (xy 31.236358 -390.67903)
			(xy 31.28197 -390.752836) (xy 31.320588 -390.83053) (xy 31.351885 -390.911451) (xy 31.375595 -390.994911)
			(xy 31.391515 -391.0802) (xy 31.39951 -391.166593) (xy 31.399512 -391.253356) (xy 31.3995 -391.253488)
			(xy 34.599874 -391.253488) (xy 34.599874 -391.166588) (xy 34.607892 -391.080059) (xy 34.62386 -390.994639)
			(xy 34.647641 -390.911057) (xy 34.679033 -390.830025) (xy 34.717767 -390.752236) (xy 34.763514 -390.678352)
			(xy 34.815883 -390.609005) (xy 34.874427 -390.544785) (xy 34.938647 -390.486241) (xy 35.007994 -390.433872)
			(xy 35.081878 -390.388125) (xy 35.159667 -390.349391) (xy 35.240699 -390.317999) (xy 35.324281 -390.294218)
			(xy 35.409701 -390.27825) (xy 35.49623 -390.270232) (xy 35.58313 -390.270232) (xy 35.669659 -390.27825)
			(xy 35.755079 -390.294218) (xy 35.838661 -390.317999) (xy 35.919693 -390.349391) (xy 35.997482 -390.388125)
			(xy 36.071366 -390.433872) (xy 36.140713 -390.486241) (xy 36.204933 -390.544785) (xy 36.263477 -390.609005)
			(xy 36.315846 -390.678352) (xy 36.361593 -390.752236) (xy 36.400327 -390.830025) (xy 36.431719 -390.911057)
			(xy 36.4555 -390.994639) (xy 36.471468 -391.080059) (xy 36.479486 -391.166588) (xy 36.479988 -391.210038)
			(xy 36.479486 -391.253488) (xy 36.471468 -391.340017) (xy 36.4555 -391.425437) (xy 36.431719 -391.509019)
			(xy 36.400327 -391.590051) (xy 36.361593 -391.66784) (xy 36.315846 -391.741724) (xy 36.263477 -391.811071)
			(xy 36.204933 -391.875291) (xy 36.140713 -391.933835) (xy 36.071366 -391.986204) (xy 35.997482 -392.031951)
			(xy 35.919693 -392.070685) (xy 35.838661 -392.102077) (xy 35.755079 -392.125858) (xy 35.669659 -392.141826)
			(xy 35.58313 -392.149844) (xy 35.49623 -392.149844) (xy 35.409701 -392.141826) (xy 35.324281 -392.125858)
			(xy 35.240699 -392.102077) (xy 35.159667 -392.070685) (xy 35.081878 -392.031951) (xy 35.007994 -391.986204)
			(xy 34.938647 -391.933835) (xy 34.874427 -391.875291) (xy 34.815883 -391.811071) (xy 34.763514 -391.741724)
			(xy 34.717767 -391.66784) (xy 34.679033 -391.590051) (xy 34.647641 -391.509019) (xy 34.62386 -391.425437)
			(xy 34.607892 -391.340017) (xy 34.599874 -391.253488) (xy 31.3995 -391.253488) (xy 31.391522 -391.339749)
			(xy 31.375606 -391.42504) (xy 31.351902 -391.508501) (xy 31.320609 -391.589424) (xy 31.281995 -391.667119)
			(xy 31.236387 -391.740928) (xy 31.184174 -391.81022) (xy 31.125799 -391.874409) (xy 31.061759 -391.932946)
			(xy 30.992599 -391.985335) (xy 30.918907 -392.03113) (xy 30.84131 -392.069942) (xy 30.760467 -392.10144)
			(xy 30.677066 -392.125357) (xy 30.591817 -392.141489) (xy 30.505444 -392.149699) (xy 30.418681 -392.149917)
			(xy 30.332268 -392.142141) (xy 30.246939 -392.126438) (xy 30.163419 -392.102941) (xy 30.082418 -392.07185)
			(xy 30.004627 -392.033429) (xy 29.930705 -391.988005) (xy 29.861283 -391.935964) (xy 29.828744 -391.907268)
			(xy 29.811703 -391.892502) (xy 29.773459 -391.868621) (xy 29.731602 -391.851862) (xy 29.687444 -391.842753)
			(xy 29.642372 -391.841577) (xy 29.5978 -391.848373) (xy 29.555126 -391.862928) (xy 29.51569 -391.884783)
			(xy 29.48073 -391.913254) (xy 29.451341 -391.947447) (xy 29.428447 -391.98629) (xy 29.412766 -392.028562)
			(xy 29.404789 -392.072939) (xy 29.40431 -392.095482) (xy 29.40431 -392.154722) (xy 38.718383 -392.154722)
			(xy 38.722268 -392.100369) (xy 38.733848 -392.047122) (xy 38.752888 -391.996066) (xy 38.779 -391.948238)
			(xy 38.811653 -391.904614) (xy 38.850182 -391.866081) (xy 38.893803 -391.833423) (xy 38.941627 -391.807305)
			(xy 38.992682 -391.78826) (xy 39.045927 -391.776674) (xy 39.100279 -391.772783) (xy 39.154632 -391.776668)
			(xy 39.207878 -391.788248) (xy 39.258935 -391.807288) (xy 39.306762 -391.8334) (xy 39.328852 -391.849356)
			(xy 39.347864 -391.862952) (xy 39.389747 -391.883684) (xy 39.434715 -391.89641) (xy 39.481252 -391.9007)
			(xy 39.527789 -391.89641) (xy 39.572757 -391.883684) (xy 39.61464 -391.862952) (xy 39.633652 -391.849356)
			(xy 39.655775 -391.833441) (xy 39.703602 -391.807317) (xy 39.75466 -391.788266) (xy 39.807909 -391.776676)
			(xy 39.862266 -391.772784) (xy 39.916624 -391.776667) (xy 39.969876 -391.788247) (xy 40.020937 -391.807289)
			(xy 40.068768 -391.833404) (xy 40.112396 -391.866061) (xy 40.150931 -391.904595) (xy 40.183589 -391.948222)
			(xy 40.209706 -391.996052) (xy 40.228749 -392.047113) (xy 40.240331 -392.100364) (xy 40.244216 -392.154722)
			(xy 40.605076 -392.154722) (xy 40.608961 -392.100367) (xy 40.620541 -392.047119) (xy 40.639582 -391.996061)
			(xy 40.665695 -391.948232) (xy 40.698349 -391.904607) (xy 40.73688 -391.866073) (xy 40.780502 -391.833414)
			(xy 40.828328 -391.807297) (xy 40.879385 -391.788251) (xy 40.932632 -391.776666) (xy 40.986986 -391.772776)
			(xy 41.04134 -391.776662) (xy 41.094588 -391.788243) (xy 41.145646 -391.807285) (xy 41.193474 -391.833399)
			(xy 41.215564 -391.849356) (xy 41.234576 -391.862952) (xy 41.276459 -391.883684) (xy 41.321427 -391.89641)
			(xy 41.367964 -391.9007) (xy 41.414501 -391.89641) (xy 41.459469 -391.883684) (xy 41.501352 -391.862952)
			(xy 41.520364 -391.849356) (xy 41.542487 -391.833442) (xy 41.590313 -391.80732) (xy 41.641369 -391.788271)
			(xy 41.694618 -391.776682) (xy 41.748973 -391.772791) (xy 41.803329 -391.776675) (xy 41.856579 -391.788256)
			(xy 41.907638 -391.807297) (xy 41.955468 -391.833412) (xy 41.999094 -391.866069) (xy 42.037627 -391.904602)
			(xy 42.070285 -391.948228) (xy 42.0964 -391.996057) (xy 42.115443 -392.047116) (xy 42.127024 -392.100366)
			(xy 42.130909 -392.154722) (xy 42.846051 -392.154722) (xy 42.849936 -392.100362) (xy 42.861518 -392.047108)
			(xy 42.880562 -391.996045) (xy 42.906679 -391.948211) (xy 42.939337 -391.904582) (xy 42.977873 -391.866045)
			(xy 43.021501 -391.833385) (xy 43.069334 -391.807266) (xy 43.120397 -391.788222) (xy 43.17365 -391.776638)
			(xy 43.22801 -391.772751) (xy 43.28237 -391.776641) (xy 43.335622 -391.788227) (xy 43.386684 -391.807275)
			(xy 43.434515 -391.833396) (xy 43.456606 -391.849356) (xy 43.475618 -391.862952) (xy 43.517501 -391.883684)
			(xy 43.562469 -391.89641) (xy 43.609006 -391.9007) (xy 43.655543 -391.89641) (xy 43.700511 -391.883684)
			(xy 43.742394 -391.862952) (xy 43.761406 -391.849356) (xy 43.783528 -391.833445) (xy 43.831351 -391.80733)
			(xy 43.882404 -391.788287) (xy 43.935647 -391.776704) (xy 43.989997 -391.772816) (xy 44.044347 -391.776703)
			(xy 44.097591 -391.788285) (xy 44.148644 -391.807328) (xy 44.196467 -391.833442) (xy 44.240087 -391.866097)
			(xy 44.278616 -391.904627) (xy 44.311268 -391.948249) (xy 44.33738 -391.996073) (xy 44.35642 -392.047127)
			(xy 44.368 -392.100371) (xy 44.371884 -392.154722) (xy 44.750061 -392.154722) (xy 44.753945 -392.100364)
			(xy 44.765527 -392.047112) (xy 44.784569 -391.996051) (xy 44.810685 -391.948219) (xy 44.843342 -391.904592)
			(xy 44.881876 -391.866056) (xy 44.925502 -391.833396) (xy 44.973332 -391.807278) (xy 45.024392 -391.788233)
			(xy 45.077643 -391.776648) (xy 45.132001 -391.772761) (xy 45.186358 -391.776649) (xy 45.239609 -391.788233)
			(xy 45.29067 -391.807279) (xy 45.338499 -391.833397) (xy 45.36059 -391.849356) (xy 45.379602 -391.862952)
			(xy 45.421485 -391.883684) (xy 45.466453 -391.89641) (xy 45.51299 -391.9007) (xy 45.559527 -391.89641)
			(xy 45.604495 -391.883684) (xy 45.646378 -391.862952) (xy 45.66539 -391.849356) (xy 45.687512 -391.833444)
			(xy 45.735336 -391.807326) (xy 45.786391 -391.788281) (xy 45.839636 -391.776696) (xy 45.893988 -391.772806)
			(xy 45.94834 -391.776692) (xy 46.001586 -391.788274) (xy 46.052642 -391.807316) (xy 46.100467 -391.833431)
			(xy 46.14409 -391.866086) (xy 46.18262 -391.904618) (xy 46.215274 -391.948241) (xy 46.241388 -391.996067)
			(xy 46.260429 -392.047123) (xy 46.272009 -392.100369) (xy 46.275894 -392.154722) (xy 46.272003 -392.209074)
			(xy 46.260417 -392.262319) (xy 46.24137 -392.313372) (xy 46.215251 -392.361196) (xy 46.182592 -392.404815)
			(xy 46.144057 -392.443342) (xy 46.100431 -392.475993) (xy 46.052602 -392.502102) (xy 46.001545 -392.521138)
			(xy 45.948297 -392.532714) (xy 45.893945 -392.536594) (xy 45.839593 -392.532698) (xy 45.786349 -392.521107)
			(xy 45.735297 -392.502056) (xy 45.687476 -392.475933) (xy 45.66539 -392.459972) (xy 45.646378 -392.446376)
			(xy 45.604495 -392.425644) (xy 45.559527 -392.412918) (xy 45.51299 -392.408628) (xy 45.466453 -392.412918)
			(xy 45.421485 -392.425644) (xy 45.379602 -392.446376) (xy 45.36059 -392.459972) (xy 45.338536 -392.47598)
			(xy 45.290709 -392.502103) (xy 45.239651 -392.521155) (xy 45.186401 -392.532745) (xy 45.132044 -392.536639)
			(xy 45.077686 -392.532758) (xy 45.024434 -392.521179) (xy 44.973371 -392.50214) (xy 44.925538 -392.476027)
			(xy 44.881908 -392.443373) (xy 44.84337 -392.404841) (xy 44.810708 -392.361217) (xy 44.784587 -392.313389)
			(xy 44.765539 -392.262329) (xy 44.753952 -392.209079) (xy 44.750061 -392.154722) (xy 44.371884 -392.154722)
			(xy 44.367994 -392.209071) (xy 44.356408 -392.262314) (xy 44.337362 -392.313366) (xy 44.311245 -392.361188)
			(xy 44.278587 -392.404806) (xy 44.240054 -392.443332) (xy 44.196431 -392.475982) (xy 44.148604 -392.50209)
			(xy 44.097549 -392.521127) (xy 44.044304 -392.532703) (xy 43.989954 -392.536584) (xy 43.935604 -392.53269)
			(xy 43.882362 -392.521101) (xy 43.831311 -392.502052) (xy 43.783491 -392.475932) (xy 43.761406 -392.459972)
			(xy 43.742394 -392.446376) (xy 43.700511 -392.425644) (xy 43.655543 -392.412918) (xy 43.609006 -392.408628)
			(xy 43.562469 -392.412918) (xy 43.517501 -392.425644) (xy 43.475618 -392.446376) (xy 43.456606 -392.459972)
			(xy 43.434551 -392.475981) (xy 43.386723 -392.502107) (xy 43.335664 -392.521161) (xy 43.282412 -392.532753)
			(xy 43.228053 -392.536649) (xy 43.173693 -392.532768) (xy 43.120438 -392.521191) (xy 43.069373 -392.502151)
			(xy 43.021538 -392.476038) (xy 42.977906 -392.443383) (xy 42.939366 -392.40485) (xy 42.906702 -392.361225)
			(xy 42.88058 -392.313395) (xy 42.86153 -392.262334) (xy 42.849942 -392.209081) (xy 42.846051 -392.154722)
			(xy 42.130909 -392.154722) (xy 42.127018 -392.209077) (xy 42.115431 -392.262325) (xy 42.096382 -392.313383)
			(xy 42.070261 -392.361209) (xy 42.037599 -392.40483) (xy 41.999061 -392.443359) (xy 41.955432 -392.476011)
			(xy 41.907599 -392.502121) (xy 41.856537 -392.521157) (xy 41.803286 -392.532731) (xy 41.74893 -392.536609)
			(xy 41.694575 -392.532711) (xy 41.641328 -392.521117) (xy 41.590273 -392.502062) (xy 41.54245 -392.475935)
			(xy 41.520364 -392.459972) (xy 41.501352 -392.446376) (xy 41.459469 -392.425644) (xy 41.414501 -392.412918)
			(xy 41.367964 -392.408628) (xy 41.321427 -392.412918) (xy 41.276459 -392.425644) (xy 41.234576 -392.446376)
			(xy 41.215564 -392.459972) (xy 41.19351 -392.475977) (xy 41.145685 -392.502097) (xy 41.09463 -392.521145)
			(xy 41.041383 -392.532732) (xy 40.987029 -392.536624) (xy 40.932675 -392.53274) (xy 40.879426 -392.521161)
			(xy 40.828368 -392.502121) (xy 40.780539 -392.476009) (xy 40.736913 -392.443356) (xy 40.698378 -392.404826)
			(xy 40.665718 -392.361204) (xy 40.6396 -392.313378) (xy 40.620553 -392.262322) (xy 40.608967 -392.209075)
			(xy 40.605076 -392.154722) (xy 40.244216 -392.154722) (xy 40.240325 -392.209079) (xy 40.228737 -392.262329)
			(xy 40.209688 -392.313387) (xy 40.183566 -392.361215) (xy 40.150903 -392.404837) (xy 40.112363 -392.443367)
			(xy 40.068732 -392.476019) (xy 40.020898 -392.502129) (xy 39.969834 -392.521165) (xy 39.916581 -392.532739)
			(xy 39.862223 -392.536616) (xy 39.807866 -392.532717) (xy 39.754618 -392.521122) (xy 39.703562 -392.502065)
			(xy 39.655739 -392.475936) (xy 39.633652 -392.459972) (xy 39.61464 -392.446376) (xy 39.572757 -392.425644)
			(xy 39.527789 -392.412918) (xy 39.481252 -392.408628) (xy 39.434715 -392.412918) (xy 39.389747 -392.425644)
			(xy 39.347864 -392.446376) (xy 39.328852 -392.459972) (xy 39.306799 -392.475976) (xy 39.258974 -392.502094)
			(xy 39.20792 -392.52114) (xy 39.154675 -392.532726) (xy 39.100322 -392.536617) (xy 39.04597 -392.532732)
			(xy 38.992723 -392.521153) (xy 38.941666 -392.502113) (xy 38.893839 -392.476001) (xy 38.850214 -392.443348)
			(xy 38.811681 -392.404819) (xy 38.779023 -392.361198) (xy 38.752906 -392.313374) (xy 38.73386 -392.262319)
			(xy 38.722274 -392.209074) (xy 38.718383 -392.154722) (xy 29.40431 -392.154722) (xy 29.40431 -392.864594)
			(xy 29.404797 -392.887138) (xy 29.412756 -392.931518) (xy 29.428424 -392.973796) (xy 29.451309 -393.012644)
			(xy 29.480693 -393.046842) (xy 29.515653 -393.075316) (xy 29.55509 -393.097171) (xy 29.597766 -393.111721)
			(xy 29.64234 -393.118508) (xy 29.687412 -393.11732) (xy 29.731567 -393.108194) (xy 29.773417 -393.091417)
			(xy 29.811648 -393.067515) (xy 29.828744 -393.052808) (xy 29.861244 -393.024069) (xy 29.930663 -392.972024)
			(xy 30.004582 -392.926596) (xy 30.082372 -392.888171) (xy 30.16337 -392.857075) (xy 30.246889 -392.833573)
			(xy 30.332218 -392.817866) (xy 30.41863 -392.810085) (xy 30.505393 -392.810299) (xy 30.591766 -392.818504)
			(xy 30.677016 -392.834631) (xy 30.760419 -392.858543) (xy 30.841263 -392.890037) (xy 30.918863 -392.928845)
			(xy 30.992557 -392.974636) (xy 31.06172 -393.027021) (xy 31.125763 -393.085555) (xy 31.184141 -393.14974)
			(xy 31.236358 -393.21903) (xy 31.28197 -393.292836) (xy 31.320588 -393.37053) (xy 31.351885 -393.451451)
			(xy 31.375595 -393.534911) (xy 31.391515 -393.6202) (xy 31.39951 -393.706593) (xy 31.399512 -393.793356)
			(xy 31.3995 -393.793488) (xy 34.599874 -393.793488) (xy 34.599874 -393.706588) (xy 34.607892 -393.620059)
			(xy 34.62386 -393.534639) (xy 34.647641 -393.451057) (xy 34.679033 -393.370025) (xy 34.717767 -393.292236)
			(xy 34.763514 -393.218352) (xy 34.815883 -393.149005) (xy 34.874427 -393.084785) (xy 34.938647 -393.026241)
			(xy 35.007994 -392.973872) (xy 35.081878 -392.928125) (xy 35.159667 -392.889391) (xy 35.240699 -392.857999)
			(xy 35.324281 -392.834218) (xy 35.409701 -392.81825) (xy 35.49623 -392.810232) (xy 35.58313 -392.810232)
			(xy 35.669659 -392.81825) (xy 35.755079 -392.834218) (xy 35.838661 -392.857999) (xy 35.919693 -392.889391)
			(xy 35.997482 -392.928125) (xy 36.071366 -392.973872) (xy 36.140713 -393.026241) (xy 36.169577 -393.052554)
			(xy 73.419208 -393.052554) (xy 73.419208 -391.975594) (xy 73.41965 -391.944447) (xy 73.42726 -391.882619)
			(xy 73.442366 -391.822184) (xy 73.464741 -391.764047) (xy 73.49405 -391.709079) (xy 73.529855 -391.658102)
			(xy 73.571618 -391.611881) (xy 73.618715 -391.571108) (xy 73.67044 -391.536393) (xy 73.726018 -391.508256)
			(xy 73.784617 -391.48712) (xy 73.845359 -391.4733) (xy 73.907334 -391.467003) (xy 73.969614 -391.468324)
			(xy 74.031267 -391.477243) (xy 74.091368 -391.493626) (xy 74.149018 -391.517229) (xy 74.203353 -391.547697)
			(xy 74.253559 -391.584574) (xy 74.298885 -391.627307) (xy 74.31913 -391.650982) (xy 74.333747 -391.667852)
			(xy 74.367822 -391.696681) (xy 74.406408 -391.719115) (xy 74.448318 -391.734465) (xy 74.492266 -391.742261)
			(xy 74.5369 -391.742261) (xy 74.580848 -391.734465) (xy 74.622758 -391.719115) (xy 74.661344 -391.696681)
			(xy 74.695419 -391.667852) (xy 74.710036 -391.650982) (xy 74.731092 -391.626379) (xy 74.778434 -391.582195)
			(xy 74.831003 -391.544378) (xy 74.887947 -391.513541) (xy 74.948345 -391.490182) (xy 75.01122 -391.47468)
			(xy 75.075554 -391.467286) (xy 75.140307 -391.468118) (xy 75.20443 -391.477164) (xy 75.266885 -391.494277)
			(xy 75.326663 -391.519181) (xy 75.382796 -391.551472) (xy 75.434375 -391.590627) (xy 75.480566 -391.636014)
			(xy 75.500992 -391.661142) (xy 75.515595 -391.678874) (xy 75.550045 -391.709254) (xy 75.589393 -391.732949)
			(xy 75.632359 -391.749187) (xy 75.677543 -391.757441) (xy 75.723475 -391.757441) (xy 75.768659 -391.749187)
			(xy 75.811625 -391.732949) (xy 75.850973 -391.709254) (xy 75.885423 -391.678874) (xy 75.900026 -391.661142)
			(xy 75.919993 -391.6365) (xy 75.965125 -391.591936) (xy 76.015448 -391.55333) (xy 76.070183 -391.521282)
			(xy 76.128477 -391.496291) (xy 76.189428 -391.478743) (xy 76.252087 -391.468912) (xy 76.315483 -391.46695)
			(xy 76.37863 -391.472888) (xy 76.440549 -391.486633) (xy 76.500278 -391.507971) (xy 76.556889 -391.536573)
			(xy 76.609504 -391.571993) (xy 76.657305 -391.613681) (xy 76.67879 -391.637012) (xy 76.695029 -391.654397)
			(xy 76.732754 -391.683368) (xy 76.775211 -391.704815) (xy 76.820916 -391.717991) (xy 76.868274 -391.722435)
			(xy 76.915632 -391.717991) (xy 76.961337 -391.704815) (xy 77.003794 -391.683368) (xy 77.041519 -391.654397)
			(xy 77.057758 -391.637012) (xy 77.079648 -391.613259) (xy 77.128413 -391.570898) (xy 77.18215 -391.535055)
			(xy 77.239996 -391.506308) (xy 77.301016 -391.48512) (xy 77.364229 -391.471833) (xy 77.428616 -391.466659)
			(xy 77.49314 -391.469683) (xy 77.556761 -391.480857) (xy 77.618454 -391.499999) (xy 77.677225 -391.526801)
			(xy 77.732128 -391.560832) (xy 77.782278 -391.601544) (xy 77.826867 -391.64828) (xy 77.865176 -391.700288)
			(xy 77.89659 -391.75673) (xy 77.9206 -391.816696) (xy 77.936821 -391.879221) (xy 77.944992 -391.943297)
			(xy 77.945488 -391.975594) (xy 77.945488 -393.052554) (xy 77.944967 -393.085289) (xy 77.936532 -393.150214)
			(xy 77.919833 -393.213519) (xy 77.895147 -393.274157) (xy 77.862882 -393.331125) (xy 77.843634 -393.357608)
			(xy 77.818488 -393.39139) (xy 77.818488 -393.408408) (xy 77.802994 -393.408408) (xy 77.76718 -393.438888)
			(xy 77.742003 -393.459741) (xy 77.687271 -393.495492) (xy 77.628406 -393.523931) (xy 77.566381 -393.544586)
			(xy 77.502219 -393.557117) (xy 77.43698 -393.561317) (xy 77.371741 -393.557117) (xy 77.307579 -393.544586)
			(xy 77.245554 -393.523931) (xy 77.186689 -393.495492) (xy 77.131957 -393.459741) (xy 77.10678 -393.438888)
			(xy 77.070966 -393.408408) (xy 77.055472 -393.408408) (xy 77.055472 -393.39139) (xy 77.030326 -393.357608)
			(xy 77.016729 -393.339036) (xy 76.992559 -393.299862) (xy 76.982066 -393.279376) (xy 76.974663 -393.265541)
			(xy 76.954256 -393.241717) (xy 76.928655 -393.223591) (xy 76.899405 -393.212258) (xy 76.868274 -393.208403)
			(xy 76.837143 -393.212258) (xy 76.807893 -393.223591) (xy 76.782292 -393.241717) (xy 76.761885 -393.265541)
			(xy 76.754482 -393.279376) (xy 76.743991 -393.299863) (xy 76.719821 -393.339038) (xy 76.706222 -393.357608)
			(xy 76.681076 -393.39139) (xy 76.681076 -393.408408) (xy 76.665582 -393.408408) (xy 76.629768 -393.438888)
			(xy 76.604591 -393.459741) (xy 76.549859 -393.495492) (xy 76.490994 -393.523931) (xy 76.428969 -393.544586)
			(xy 76.364807 -393.557117) (xy 76.299568 -393.561317) (xy 76.234329 -393.557117) (xy 76.170167 -393.544586)
			(xy 76.108142 -393.523931) (xy 76.049277 -393.495492) (xy 75.994545 -393.459741) (xy 75.969368 -393.438888)
			(xy 75.933554 -393.408408) (xy 75.91806 -393.408408) (xy 75.91806 -393.39139) (xy 75.892914 -393.357608)
			(xy 75.87031 -393.326269) (xy 75.833826 -393.258157) (xy 75.82027 -393.221972) (xy 75.814625 -393.207353)
			(xy 75.797314 -393.181241) (xy 75.774159 -393.160139) (xy 75.746556 -393.14532) (xy 75.716173 -393.13768)
			(xy 75.684845 -393.13768) (xy 75.654462 -393.14532) (xy 75.626859 -393.160139) (xy 75.603704 -393.181241)
			(xy 75.586393 -393.207353) (xy 75.580748 -393.221972) (xy 75.567195 -393.258158) (xy 75.530713 -393.326272)
			(xy 75.508104 -393.357608) (xy 75.482704 -393.39139) (xy 75.482704 -393.408408) (xy 75.467464 -393.408408)
			(xy 75.43165 -393.438888) (xy 75.406473 -393.459741) (xy 75.351741 -393.495492) (xy 75.292876 -393.523931)
			(xy 75.230851 -393.544586) (xy 75.166689 -393.557117) (xy 75.10145 -393.561317) (xy 75.036211 -393.557117)
			(xy 74.972049 -393.544586) (xy 74.910024 -393.523931) (xy 74.851159 -393.495492) (xy 74.796427 -393.459741)
			(xy 74.77125 -393.438888) (xy 74.735436 -393.408408) (xy 74.720196 -393.408408) (xy 74.720196 -393.39139)
			(xy 74.694796 -393.357608) (xy 74.676059 -393.331866) (xy 74.644474 -393.276582) (xy 74.631804 -393.247372)
			(xy 74.624936 -393.232215) (xy 74.604683 -393.205829) (xy 74.578292 -393.185583) (xy 74.547561 -393.172855)
			(xy 74.514583 -393.168514) (xy 74.481605 -393.172855) (xy 74.450874 -393.185583) (xy 74.424483 -393.205829)
			(xy 74.40423 -393.232215) (xy 74.397362 -393.247372) (xy 74.384692 -393.276581) (xy 74.353098 -393.33186)
			(xy 74.33437 -393.357608) (xy 74.309224 -393.39139) (xy 74.309224 -393.408408) (xy 74.29373 -393.408408)
			(xy 74.257916 -393.438888) (xy 74.232739 -393.459741) (xy 74.178007 -393.495492) (xy 74.119142 -393.523931)
			(xy 74.057117 -393.544586) (xy 73.992955 -393.557117) (xy 73.927716 -393.561317) (xy 73.862477 -393.557117)
			(xy 73.798315 -393.544586) (xy 73.73629 -393.523931) (xy 73.677425 -393.495492) (xy 73.622693 -393.459741)
			(xy 73.597516 -393.438888) (xy 73.561702 -393.408408) (xy 73.546208 -393.408408) (xy 73.546208 -393.39139)
			(xy 73.521062 -393.357608) (xy 73.501816 -393.331123) (xy 73.469552 -393.274155) (xy 73.444867 -393.213518)
			(xy 73.428168 -393.150213) (xy 73.419732 -393.085289) (xy 73.419208 -393.052554) (xy 36.169577 -393.052554)
			(xy 36.204933 -393.084785) (xy 36.263477 -393.149005) (xy 36.315846 -393.218352) (xy 36.361593 -393.292236)
			(xy 36.400327 -393.370025) (xy 36.431719 -393.451057) (xy 36.4555 -393.534639) (xy 36.471468 -393.620059)
			(xy 36.479486 -393.706588) (xy 36.479988 -393.750038) (xy 36.479486 -393.793488) (xy 36.471468 -393.880017)
			(xy 36.4555 -393.965437) (xy 36.431719 -394.049019) (xy 36.425719 -394.064506) (xy 38.718404 -394.064506)
			(xy 38.722291 -394.010156) (xy 38.733872 -393.956913) (xy 38.752913 -393.90586) (xy 38.779026 -393.858036)
			(xy 38.811679 -393.814416) (xy 38.850207 -393.775886) (xy 38.893827 -393.743232) (xy 38.94165 -393.717118)
			(xy 38.992702 -393.698075) (xy 39.045945 -393.686492) (xy 39.100295 -393.682604) (xy 39.154644 -393.686491)
			(xy 39.207888 -393.698072) (xy 39.258941 -393.717113) (xy 39.306764 -393.743226) (xy 39.328852 -393.759182)
			(xy 39.347864 -393.772778) (xy 39.389747 -393.79351) (xy 39.434715 -393.806236) (xy 39.481252 -393.810526)
			(xy 39.527789 -393.806236) (xy 39.572757 -393.79351) (xy 39.61464 -393.772778) (xy 39.633652 -393.759182)
			(xy 39.655751 -393.743231) (xy 39.703579 -393.717104) (xy 39.754639 -393.698051) (xy 39.807891 -393.686458)
			(xy 39.862251 -393.682563) (xy 39.916611 -393.686444) (xy 39.969866 -393.698023) (xy 40.020931 -393.717063)
			(xy 40.068766 -393.743178) (xy 40.112397 -393.775835) (xy 40.150936 -393.81437) (xy 40.183598 -393.857997)
			(xy 40.209719 -393.905829) (xy 40.228765 -393.956892) (xy 40.24035 -394.010146) (xy 40.244237 -394.064506)
			(xy 40.605097 -394.064506) (xy 40.608984 -394.010155) (xy 40.620565 -393.95691) (xy 40.639607 -393.905855)
			(xy 40.665721 -393.85803) (xy 40.698375 -393.814409) (xy 40.736905 -393.775878) (xy 40.780527 -393.743223)
			(xy 40.828351 -393.717109) (xy 40.879406 -393.698067) (xy 40.93265 -393.686484) (xy 40.987002 -393.682597)
			(xy 41.041353 -393.686485) (xy 41.094597 -393.698068) (xy 41.145652 -393.71711) (xy 41.193476 -393.743225)
			(xy 41.215564 -393.759182) (xy 41.234576 -393.772778) (xy 41.276459 -393.79351) (xy 41.321427 -393.806236)
			(xy 41.367964 -393.810526) (xy 41.414501 -393.806236) (xy 41.459469 -393.79351) (xy 41.501352 -393.772778)
			(xy 41.520364 -393.759182) (xy 41.542462 -393.743232) (xy 41.59029 -393.717107) (xy 41.641349 -393.698055)
			(xy 41.694599 -393.686464) (xy 41.748957 -393.68257) (xy 41.803317 -393.686452) (xy 41.85657 -393.698031)
			(xy 41.907633 -393.717072) (xy 41.955466 -393.743187) (xy 41.999096 -393.775843) (xy 42.037633 -393.814377)
			(xy 42.070294 -393.858003) (xy 42.096413 -393.905834) (xy 42.115458 -393.956895) (xy 42.127043 -394.010147)
			(xy 42.13093 -394.064506) (xy 42.846072 -394.064506) (xy 42.849959 -394.010149) (xy 42.861543 -393.956899)
			(xy 42.880587 -393.905839) (xy 42.906705 -393.858009) (xy 42.939363 -393.814384) (xy 42.977899 -393.775851)
			(xy 43.021526 -393.743194) (xy 43.069357 -393.717079) (xy 43.120417 -393.698037) (xy 43.173668 -393.686456)
			(xy 43.228025 -393.682572) (xy 43.282382 -393.686463) (xy 43.335631 -393.698051) (xy 43.38669 -393.7171)
			(xy 43.434517 -393.743222) (xy 43.456606 -393.759182) (xy 43.475618 -393.772778) (xy 43.517501 -393.79351)
			(xy 43.562469 -393.806236) (xy 43.609006 -393.810526) (xy 43.655543 -393.806236) (xy 43.700511 -393.79351)
			(xy 43.742394 -393.772778) (xy 43.761406 -393.759182) (xy 43.783503 -393.743236) (xy 43.831328 -393.717118)
			(xy 43.882383 -393.698071) (xy 43.935629 -393.686485) (xy 43.989981 -393.682595) (xy 44.044335 -393.68648)
			(xy 44.097581 -393.698061) (xy 44.148638 -393.717102) (xy 44.196465 -393.743216) (xy 44.240089 -393.775871)
			(xy 44.278621 -393.814402) (xy 44.311277 -393.858024) (xy 44.337393 -393.90585) (xy 44.356436 -393.956906)
			(xy 44.368018 -394.010153) (xy 44.371905 -394.064506) (xy 44.750081 -394.064506) (xy 44.753968 -394.010151)
			(xy 44.765551 -393.956903) (xy 44.784595 -393.905845) (xy 44.810711 -393.858017) (xy 44.843368 -393.814393)
			(xy 44.881901 -393.775861) (xy 44.925526 -393.743205) (xy 44.973355 -393.71709) (xy 45.024413 -393.698048)
			(xy 45.077662 -393.686467) (xy 45.132016 -393.682581) (xy 45.186371 -393.686471) (xy 45.239618 -393.698058)
			(xy 45.290675 -393.717104) (xy 45.338501 -393.743223) (xy 45.36059 -393.759182) (xy 45.379602 -393.772778)
			(xy 45.421485 -393.79351) (xy 45.466453 -393.806236) (xy 45.51299 -393.810526) (xy 45.559527 -393.806236)
			(xy 45.604495 -393.79351) (xy 45.646378 -393.772778) (xy 45.66539 -393.759182) (xy 45.687488 -393.743235)
			(xy 45.735313 -393.717114) (xy 45.78637 -393.698065) (xy 45.839617 -393.686477) (xy 45.893972 -393.682585)
			(xy 45.948328 -393.686469) (xy 46.001577 -393.69805) (xy 46.052636 -393.717091) (xy 46.100466 -393.743205)
			(xy 46.144091 -393.77586) (xy 46.182626 -393.814392) (xy 46.215284 -393.858016) (xy 46.2414 -393.905844)
			(xy 46.260444 -393.956902) (xy 46.272028 -394.010151) (xy 46.275915 -394.064506) (xy 46.272026 -394.118861)
			(xy 46.260441 -394.172109) (xy 46.241395 -394.223167) (xy 46.215277 -394.270994) (xy 46.182618 -394.314617)
			(xy 46.144082 -394.353148) (xy 46.100455 -394.385802) (xy 46.052625 -394.411914) (xy 46.001566 -394.430954)
			(xy 45.948316 -394.442532) (xy 45.89396 -394.446415) (xy 45.839606 -394.442521) (xy 45.786358 -394.430931)
			(xy 45.735302 -394.411881) (xy 45.687478 -394.385759) (xy 45.66539 -394.369798) (xy 45.646378 -394.356202)
			(xy 45.604495 -394.33547) (xy 45.559527 -394.322744) (xy 45.51299 -394.318454) (xy 45.466453 -394.322744)
			(xy 45.421485 -394.33547) (xy 45.379602 -394.356202) (xy 45.36059 -394.369798) (xy 45.338511 -394.385771)
			(xy 45.290686 -394.411891) (xy 45.23963 -394.430939) (xy 45.186383 -394.442527) (xy 45.132028 -394.446419)
			(xy 45.077673 -394.442535) (xy 45.024424 -394.430955) (xy 44.973366 -394.411915) (xy 44.925536 -394.385801)
			(xy 44.88191 -394.353147) (xy 44.843376 -394.314616) (xy 44.810717 -394.270993) (xy 44.7846 -394.223166)
			(xy 44.765555 -394.172109) (xy 44.75397 -394.118861) (xy 44.750081 -394.064506) (xy 44.371905 -394.064506)
			(xy 44.368017 -394.118859) (xy 44.356432 -394.172105) (xy 44.337388 -394.223161) (xy 44.311271 -394.270986)
			(xy 44.278613 -394.314608) (xy 44.24008 -394.353137) (xy 44.196455 -394.385791) (xy 44.148627 -394.411903)
			(xy 44.09757 -394.430942) (xy 44.044323 -394.442522) (xy 43.989969 -394.446405) (xy 43.935617 -394.442513)
			(xy 43.882371 -394.430925) (xy 43.831317 -394.411877) (xy 43.783493 -394.385757) (xy 43.761406 -394.369798)
			(xy 43.742394 -394.356202) (xy 43.700511 -394.33547) (xy 43.655543 -394.322744) (xy 43.609006 -394.318454)
			(xy 43.562469 -394.322744) (xy 43.517501 -394.33547) (xy 43.475618 -394.356202) (xy 43.456606 -394.369798)
			(xy 43.434527 -394.385772) (xy 43.386701 -394.411895) (xy 43.335643 -394.430945) (xy 43.282394 -394.442535)
			(xy 43.228037 -394.446428) (xy 43.17368 -394.442546) (xy 43.120429 -394.430966) (xy 43.069368 -394.411926)
			(xy 43.021536 -394.385812) (xy 42.977908 -394.353157) (xy 42.939371 -394.314625) (xy 42.906711 -394.271001)
			(xy 42.880592 -394.223172) (xy 42.861546 -394.172113) (xy 42.849961 -394.118863) (xy 42.846072 -394.064506)
			(xy 42.13093 -394.064506) (xy 42.127041 -394.118865) (xy 42.115455 -394.172116) (xy 42.096408 -394.223177)
			(xy 42.070287 -394.271007) (xy 42.037625 -394.314632) (xy 41.999086 -394.353165) (xy 41.955456 -394.38582)
			(xy 41.907622 -394.411933) (xy 41.856558 -394.430972) (xy 41.803305 -394.44255) (xy 41.748945 -394.44643)
			(xy 41.694587 -394.442534) (xy 41.641337 -394.430941) (xy 41.590279 -394.411888) (xy 41.542452 -394.385761)
			(xy 41.520364 -394.369798) (xy 41.501352 -394.356202) (xy 41.459469 -394.33547) (xy 41.414501 -394.322744)
			(xy 41.367964 -394.318454) (xy 41.321427 -394.322744) (xy 41.276459 -394.33547) (xy 41.234576 -394.356202)
			(xy 41.215564 -394.369798) (xy 41.193486 -394.385768) (xy 41.145662 -394.411885) (xy 41.094609 -394.430929)
			(xy 41.041365 -394.442514) (xy 40.987014 -394.446403) (xy 40.932662 -394.442518) (xy 40.879417 -394.430937)
			(xy 40.828362 -394.411896) (xy 40.780537 -394.385783) (xy 40.736914 -394.35313) (xy 40.698383 -394.3146)
			(xy 40.665728 -394.27098) (xy 40.639612 -394.223156) (xy 40.620569 -394.172102) (xy 40.608985 -394.118857)
			(xy 40.605097 -394.064506) (xy 40.244237 -394.064506) (xy 40.240348 -394.118866) (xy 40.228762 -394.17212)
			(xy 40.209714 -394.223182) (xy 40.183592 -394.271013) (xy 40.150929 -394.314639) (xy 40.112388 -394.353173)
			(xy 40.068756 -394.385828) (xy 40.02092 -394.411942) (xy 39.969855 -394.430981) (xy 39.9166 -394.442558)
			(xy 39.862239 -394.446437) (xy 39.807879 -394.44254) (xy 39.754627 -394.430946) (xy 39.703568 -394.411891)
			(xy 39.655741 -394.385762) (xy 39.633652 -394.369798) (xy 39.61464 -394.356202) (xy 39.572757 -394.33547)
			(xy 39.527789 -394.322744) (xy 39.481252 -394.318454) (xy 39.434715 -394.322744) (xy 39.389747 -394.33547)
			(xy 39.347864 -394.356202) (xy 39.328852 -394.369798) (xy 39.306774 -394.385767) (xy 39.258952 -394.411882)
			(xy 39.207899 -394.430924) (xy 39.154656 -394.442508) (xy 39.100307 -394.446396) (xy 39.045957 -394.44251)
			(xy 38.992714 -394.430928) (xy 38.941661 -394.411887) (xy 38.893837 -394.385775) (xy 38.850216 -394.353122)
			(xy 38.811687 -394.314593) (xy 38.779032 -394.270974) (xy 38.752918 -394.223151) (xy 38.733875 -394.172098)
			(xy 38.722292 -394.118855) (xy 38.718404 -394.064506) (xy 36.425719 -394.064506) (xy 36.400327 -394.130051)
			(xy 36.361593 -394.20784) (xy 36.315846 -394.281724) (xy 36.263477 -394.351071) (xy 36.204933 -394.415291)
			(xy 36.140713 -394.473835) (xy 36.071366 -394.526204) (xy 35.997482 -394.571951) (xy 35.919693 -394.610685)
			(xy 35.838661 -394.642077) (xy 35.755079 -394.665858) (xy 35.669659 -394.681826) (xy 35.58313 -394.689844)
			(xy 35.49623 -394.689844) (xy 35.409701 -394.681826) (xy 35.324281 -394.665858) (xy 35.240699 -394.642077)
			(xy 35.159667 -394.610685) (xy 35.081878 -394.571951) (xy 35.007994 -394.526204) (xy 34.938647 -394.473835)
			(xy 34.874427 -394.415291) (xy 34.815883 -394.351071) (xy 34.763514 -394.281724) (xy 34.717767 -394.20784)
			(xy 34.679033 -394.130051) (xy 34.647641 -394.049019) (xy 34.62386 -393.965437) (xy 34.607892 -393.880017)
			(xy 34.599874 -393.793488) (xy 31.3995 -393.793488) (xy 31.391522 -393.879749) (xy 31.375606 -393.96504)
			(xy 31.351902 -394.048501) (xy 31.320609 -394.129424) (xy 31.281995 -394.207119) (xy 31.236387 -394.280928)
			(xy 31.184174 -394.35022) (xy 31.125799 -394.414409) (xy 31.061759 -394.472946) (xy 30.992599 -394.525335)
			(xy 30.918907 -394.57113) (xy 30.84131 -394.609942) (xy 30.760467 -394.64144) (xy 30.677066 -394.665357)
			(xy 30.591817 -394.681489) (xy 30.505444 -394.689699) (xy 30.418681 -394.689917) (xy 30.332268 -394.682141)
			(xy 30.246939 -394.666438) (xy 30.163419 -394.642941) (xy 30.082418 -394.61185) (xy 30.004627 -394.573429)
			(xy 29.930705 -394.528005) (xy 29.861283 -394.475964) (xy 29.828744 -394.447268) (xy 29.811703 -394.432502)
			(xy 29.773459 -394.408621) (xy 29.731602 -394.391862) (xy 29.687444 -394.382753) (xy 29.642372 -394.381577)
			(xy 29.5978 -394.388373) (xy 29.555126 -394.402928) (xy 29.51569 -394.424783) (xy 29.48073 -394.453254)
			(xy 29.451341 -394.487447) (xy 29.428447 -394.52629) (xy 29.412766 -394.568562) (xy 29.404789 -394.612939)
			(xy 29.40431 -394.635482) (xy 29.40431 -394.722604) (xy 51.208432 -394.722604) (xy 52.85994 -394.722604)
			(xy 52.85994 -396.374112) (xy 51.208432 -396.374112) (xy 51.208432 -394.722604) (xy 29.40431 -394.722604)
			(xy 29.40431 -395.404594) (xy 29.404797 -395.427138) (xy 29.412756 -395.471518) (xy 29.428424 -395.513796)
			(xy 29.451309 -395.552644) (xy 29.480693 -395.586842) (xy 29.515653 -395.615316) (xy 29.55509 -395.637171)
			(xy 29.597766 -395.651721) (xy 29.64234 -395.658508) (xy 29.687412 -395.65732) (xy 29.731567 -395.648194)
			(xy 29.773417 -395.631417) (xy 29.811648 -395.607515) (xy 29.828744 -395.592808) (xy 29.861244 -395.564069)
			(xy 29.930663 -395.512024) (xy 30.004582 -395.466596) (xy 30.082372 -395.428171) (xy 30.16337 -395.397075)
			(xy 30.246889 -395.373573) (xy 30.332218 -395.357866) (xy 30.41863 -395.350085) (xy 30.505393 -395.350299)
			(xy 30.591766 -395.358504) (xy 30.677016 -395.374631) (xy 30.760419 -395.398543) (xy 30.841263 -395.430037)
			(xy 30.918863 -395.468845) (xy 30.992557 -395.514636) (xy 31.06172 -395.567021) (xy 31.125763 -395.625555)
			(xy 31.184141 -395.68974) (xy 31.236358 -395.75903) (xy 31.28197 -395.832836) (xy 31.320588 -395.91053)
			(xy 31.351885 -395.991451) (xy 31.375595 -396.074911) (xy 31.391515 -396.1602) (xy 31.39951 -396.246593)
			(xy 31.399512 -396.333356) (xy 31.3995 -396.333488) (xy 34.599874 -396.333488) (xy 34.599874 -396.246588)
			(xy 34.607892 -396.160059) (xy 34.62386 -396.074639) (xy 34.647641 -395.991057) (xy 34.679033 -395.910025)
			(xy 34.717767 -395.832236) (xy 34.763514 -395.758352) (xy 34.815883 -395.689005) (xy 34.874427 -395.624785)
			(xy 34.938647 -395.566241) (xy 35.007994 -395.513872) (xy 35.081878 -395.468125) (xy 35.159667 -395.429391)
			(xy 35.240699 -395.397999) (xy 35.324281 -395.374218) (xy 35.409701 -395.35825) (xy 35.49623 -395.350232)
			(xy 35.58313 -395.350232) (xy 35.669659 -395.35825) (xy 35.755079 -395.374218) (xy 35.838661 -395.397999)
			(xy 35.919693 -395.429391) (xy 35.997482 -395.468125) (xy 36.071366 -395.513872) (xy 36.140713 -395.566241)
			(xy 36.165583 -395.588913) (xy 47.708556 -395.588913) (xy 47.708556 -395.507803) (xy 47.716506 -395.427084)
			(xy 47.732329 -395.347533) (xy 47.755874 -395.269917) (xy 47.786913 -395.194981) (xy 47.825148 -395.123449)
			(xy 47.87021 -395.056009) (xy 47.921665 -394.99331) (xy 47.979018 -394.935957) (xy 48.041717 -394.884502)
			(xy 48.109157 -394.83944) (xy 48.180689 -394.801205) (xy 48.255625 -394.770166) (xy 48.333241 -394.746621)
			(xy 48.412792 -394.730798) (xy 48.493511 -394.722848) (xy 48.574621 -394.722848) (xy 48.65534 -394.730798)
			(xy 48.734891 -394.746621) (xy 48.812507 -394.770166) (xy 48.887443 -394.801205) (xy 48.958975 -394.83944)
			(xy 49.026415 -394.884502) (xy 49.089114 -394.935957) (xy 49.146467 -394.99331) (xy 49.197922 -395.056009)
			(xy 49.242984 -395.123449) (xy 49.281219 -395.194981) (xy 49.312258 -395.269917) (xy 49.335803 -395.347533)
			(xy 49.351626 -395.427084) (xy 49.359576 -395.507803) (xy 49.360074 -395.548358) (xy 49.359576 -395.588913)
			(xy 49.351626 -395.669632) (xy 49.335803 -395.749183) (xy 49.312258 -395.826799) (xy 49.281219 -395.901735)
			(xy 49.242984 -395.973267) (xy 49.197922 -396.040707) (xy 49.146467 -396.103406) (xy 49.089114 -396.160759)
			(xy 49.026415 -396.212214) (xy 48.958975 -396.257276) (xy 48.887443 -396.295511) (xy 48.812507 -396.32655)
			(xy 48.734891 -396.350095) (xy 48.65534 -396.365918) (xy 48.574621 -396.373868) (xy 48.493511 -396.373868)
			(xy 48.412792 -396.365918) (xy 48.333241 -396.350095) (xy 48.255625 -396.32655) (xy 48.180689 -396.295511)
			(xy 48.109157 -396.257276) (xy 48.041717 -396.212214) (xy 47.979018 -396.160759) (xy 47.921665 -396.103406)
			(xy 47.87021 -396.040707) (xy 47.825148 -395.973267) (xy 47.786913 -395.901735) (xy 47.755874 -395.826799)
			(xy 47.732329 -395.749183) (xy 47.716506 -395.669632) (xy 47.708556 -395.588913) (xy 36.165583 -395.588913)
			(xy 36.204933 -395.624785) (xy 36.263477 -395.689005) (xy 36.315846 -395.758352) (xy 36.361593 -395.832236)
			(xy 36.400327 -395.910025) (xy 36.431719 -395.991057) (xy 36.4555 -396.074639) (xy 36.471468 -396.160059)
			(xy 36.479486 -396.246588) (xy 36.479988 -396.290038) (xy 36.479486 -396.333488) (xy 36.471468 -396.420017)
			(xy 36.4555 -396.505437) (xy 36.431719 -396.589019) (xy 36.400327 -396.670051) (xy 36.361593 -396.74784)
			(xy 36.315846 -396.821724) (xy 36.263477 -396.891071) (xy 36.204933 -396.955291) (xy 36.140713 -397.013835)
			(xy 36.071366 -397.066204) (xy 35.997482 -397.111951) (xy 35.919693 -397.150685) (xy 35.838661 -397.182077)
			(xy 35.755079 -397.205858) (xy 35.669659 -397.221826) (xy 35.58313 -397.229844) (xy 35.49623 -397.229844)
			(xy 35.409701 -397.221826) (xy 35.324281 -397.205858) (xy 35.240699 -397.182077) (xy 35.159667 -397.150685)
			(xy 35.081878 -397.111951) (xy 35.007994 -397.066204) (xy 34.938647 -397.013835) (xy 34.874427 -396.955291)
			(xy 34.815883 -396.891071) (xy 34.763514 -396.821724) (xy 34.717767 -396.74784) (xy 34.679033 -396.670051)
			(xy 34.647641 -396.589019) (xy 34.62386 -396.505437) (xy 34.607892 -396.420017) (xy 34.599874 -396.333488)
			(xy 31.3995 -396.333488) (xy 31.391522 -396.419749) (xy 31.375606 -396.50504) (xy 31.351902 -396.588501)
			(xy 31.320609 -396.669424) (xy 31.281995 -396.747119) (xy 31.236387 -396.820928) (xy 31.184174 -396.89022)
			(xy 31.125799 -396.954409) (xy 31.061759 -397.012946) (xy 30.992599 -397.065335) (xy 30.918907 -397.11113)
			(xy 30.84131 -397.149942) (xy 30.760467 -397.18144) (xy 30.677066 -397.205357) (xy 30.591817 -397.221489)
			(xy 30.505444 -397.229699) (xy 30.418681 -397.229917) (xy 30.332268 -397.222141) (xy 30.246939 -397.206438)
			(xy 30.163419 -397.182941) (xy 30.082418 -397.15185) (xy 30.004627 -397.113429) (xy 29.930705 -397.068005)
			(xy 29.861283 -397.015964) (xy 29.828744 -396.987268) (xy 29.811703 -396.972502) (xy 29.773459 -396.948621)
			(xy 29.731602 -396.931862) (xy 29.687444 -396.922753) (xy 29.642372 -396.921577) (xy 29.5978 -396.928373)
			(xy 29.555126 -396.942928) (xy 29.51569 -396.964783) (xy 29.48073 -396.993254) (xy 29.451341 -397.027447)
			(xy 29.428447 -397.06629) (xy 29.412766 -397.108562) (xy 29.404789 -397.152939) (xy 29.40431 -397.175482)
			(xy 29.40431 -397.944594) (xy 29.404797 -397.967138) (xy 29.412756 -398.011518) (xy 29.428424 -398.053796)
			(xy 29.451309 -398.092644) (xy 29.480693 -398.126842) (xy 29.515653 -398.155316) (xy 29.55509 -398.177171)
			(xy 29.597766 -398.191721) (xy 29.64234 -398.198508) (xy 29.687412 -398.19732) (xy 29.731567 -398.188194)
			(xy 29.773417 -398.171417) (xy 29.811648 -398.147515) (xy 29.828744 -398.132808) (xy 29.861244 -398.104069)
			(xy 29.930663 -398.052024) (xy 30.004582 -398.006596) (xy 30.082372 -397.968171) (xy 30.16337 -397.937075)
			(xy 30.246889 -397.913573) (xy 30.332218 -397.897866) (xy 30.41863 -397.890085) (xy 30.505393 -397.890299)
			(xy 30.591766 -397.898504) (xy 30.677016 -397.914631) (xy 30.760419 -397.938543) (xy 30.841263 -397.970037)
			(xy 30.918863 -398.008845) (xy 30.992557 -398.054636) (xy 31.06172 -398.107021) (xy 31.125763 -398.165555)
			(xy 31.184141 -398.22974) (xy 31.236358 -398.29903) (xy 31.28197 -398.372836) (xy 31.320588 -398.45053)
			(xy 31.351885 -398.531451) (xy 31.375595 -398.614911) (xy 31.391515 -398.7002) (xy 31.39951 -398.786593)
			(xy 31.399512 -398.873356) (xy 31.3995 -398.873488) (xy 34.599874 -398.873488) (xy 34.599874 -398.786588)
			(xy 34.607892 -398.700059) (xy 34.62386 -398.614639) (xy 34.647641 -398.531057) (xy 34.679033 -398.450025)
			(xy 34.717767 -398.372236) (xy 34.763514 -398.298352) (xy 34.815883 -398.229005) (xy 34.874427 -398.164785)
			(xy 34.938647 -398.106241) (xy 35.007994 -398.053872) (xy 35.081878 -398.008125) (xy 35.159667 -397.969391)
			(xy 35.240699 -397.937999) (xy 35.324281 -397.914218) (xy 35.409701 -397.89825) (xy 35.49623 -397.890232)
			(xy 35.58313 -397.890232) (xy 35.669659 -397.89825) (xy 35.755079 -397.914218) (xy 35.838661 -397.937999)
			(xy 35.839293 -397.938244) (xy 84.320378 -397.938244) (xy 84.324449 -397.882622) (xy 84.336575 -397.828185)
			(xy 84.356498 -397.776094) (xy 84.383794 -397.727459) (xy 84.41788 -397.683316) (xy 84.458029 -397.644607)
			(xy 84.503387 -397.612156) (xy 84.552987 -397.586655) (xy 84.605771 -397.568648) (xy 84.660614 -397.558518)
			(xy 84.716348 -397.556481) (xy 84.771785 -397.562581) (xy 84.825742 -397.576687) (xy 84.877071 -397.598499)
			(xy 84.924677 -397.627553) (xy 84.967545 -397.663228) (xy 85.004762 -397.704765) (xy 85.035535 -397.751278)
			(xy 85.054358 -397.791432) (xy 93.046548 -397.791432) (xy 93.050619 -397.73581) (xy 93.062745 -397.681373)
			(xy 93.082668 -397.629282) (xy 93.109964 -397.580647) (xy 93.14405 -397.536504) (xy 93.184199 -397.497795)
			(xy 93.229557 -397.465344) (xy 93.279157 -397.439843) (xy 93.331941 -397.421836) (xy 93.386784 -397.411706)
			(xy 93.442518 -397.409669) (xy 93.497955 -397.415769) (xy 93.551912 -397.429875) (xy 93.603241 -397.451687)
			(xy 93.650847 -397.480741) (xy 93.693715 -397.516416) (xy 93.730932 -397.557953) (xy 93.761705 -397.604466)
			(xy 93.785377 -397.654963) (xy 93.801445 -397.70837) (xy 93.809565 -397.763546) (xy 93.810074 -397.791432)
			(xy 93.809565 -397.819318) (xy 93.801445 -397.874494) (xy 93.785377 -397.927901) (xy 93.761705 -397.978398)
			(xy 93.730932 -398.024911) (xy 93.693715 -398.066448) (xy 93.650847 -398.102123) (xy 93.603241 -398.131177)
			(xy 93.551912 -398.152989) (xy 93.497955 -398.167095) (xy 93.442518 -398.173195) (xy 93.386784 -398.171158)
			(xy 93.331941 -398.161028) (xy 93.279157 -398.143021) (xy 93.229557 -398.11752) (xy 93.184199 -398.085069)
			(xy 93.14405 -398.04636) (xy 93.109964 -398.002217) (xy 93.082668 -397.953582) (xy 93.062745 -397.901491)
			(xy 93.050619 -397.847054) (xy 93.046548 -397.791432) (xy 85.054358 -397.791432) (xy 85.059207 -397.801775)
			(xy 85.075275 -397.855182) (xy 85.083395 -397.910358) (xy 85.083904 -397.938244) (xy 85.083395 -397.96613)
			(xy 85.075275 -398.021306) (xy 85.059207 -398.074713) (xy 85.035535 -398.12521) (xy 85.004762 -398.171723)
			(xy 84.967545 -398.21326) (xy 84.924677 -398.248935) (xy 84.877071 -398.277989) (xy 84.825742 -398.299801)
			(xy 84.771785 -398.313907) (xy 84.716348 -398.320007) (xy 84.660614 -398.31797) (xy 84.605771 -398.30784)
			(xy 84.552987 -398.289833) (xy 84.503387 -398.264332) (xy 84.458029 -398.231881) (xy 84.41788 -398.193172)
			(xy 84.383794 -398.149029) (xy 84.356498 -398.100394) (xy 84.336575 -398.048303) (xy 84.324449 -397.993866)
			(xy 84.320378 -397.938244) (xy 35.839293 -397.938244) (xy 35.919693 -397.969391) (xy 35.997482 -398.008125)
			(xy 36.071366 -398.053872) (xy 36.140713 -398.106241) (xy 36.204933 -398.164785) (xy 36.263477 -398.229005)
			(xy 36.315846 -398.298352) (xy 36.361593 -398.372236) (xy 36.400327 -398.450025) (xy 36.431719 -398.531057)
			(xy 36.4555 -398.614639) (xy 36.471468 -398.700059) (xy 36.479486 -398.786588) (xy 36.479988 -398.830038)
			(xy 36.479486 -398.873488) (xy 36.471468 -398.960017) (xy 36.461247 -399.014696) (xy 81.842862 -399.014696)
			(xy 81.846933 -398.959074) (xy 81.859059 -398.904637) (xy 81.878982 -398.852546) (xy 81.906278 -398.803911)
			(xy 81.940364 -398.759768) (xy 81.980513 -398.721059) (xy 82.025871 -398.688608) (xy 82.075471 -398.663107)
			(xy 82.128255 -398.6451) (xy 82.183098 -398.63497) (xy 82.238832 -398.632933) (xy 82.294269 -398.639033)
			(xy 82.348226 -398.653139) (xy 82.399555 -398.674951) (xy 82.447161 -398.704005) (xy 82.490029 -398.73968)
			(xy 82.527246 -398.781217) (xy 82.557866 -398.827498) (xy 88.190322 -398.827498) (xy 88.194393 -398.771876)
			(xy 88.206519 -398.717439) (xy 88.226442 -398.665348) (xy 88.253738 -398.616713) (xy 88.287824 -398.57257)
			(xy 88.327973 -398.533861) (xy 88.373331 -398.50141) (xy 88.422931 -398.475909) (xy 88.475715 -398.457902)
			(xy 88.530558 -398.447772) (xy 88.586292 -398.445735) (xy 88.641729 -398.451835) (xy 88.695686 -398.465941)
			(xy 88.747015 -398.487753) (xy 88.763903 -398.49806) (xy 91.314776 -398.49806) (xy 91.318847 -398.442438)
			(xy 91.330973 -398.388001) (xy 91.350896 -398.33591) (xy 91.378192 -398.287275) (xy 91.412278 -398.243132)
			(xy 91.452427 -398.204423) (xy 91.497785 -398.171972) (xy 91.547385 -398.146471) (xy 91.600169 -398.128464)
			(xy 91.655012 -398.118334) (xy 91.710746 -398.116297) (xy 91.766183 -398.122397) (xy 91.82014 -398.136503)
			(xy 91.871469 -398.158315) (xy 91.919075 -398.187369) (xy 91.961943 -398.223044) (xy 91.99916 -398.264581)
			(xy 92.029933 -398.311094) (xy 92.053605 -398.361591) (xy 92.069673 -398.414998) (xy 92.077793 -398.470174)
			(xy 92.078302 -398.49806) (xy 92.077793 -398.525946) (xy 92.069673 -398.581122) (xy 92.053605 -398.634529)
			(xy 92.029933 -398.685026) (xy 91.99916 -398.731539) (xy 91.961943 -398.773076) (xy 91.919075 -398.808751)
			(xy 91.871469 -398.837805) (xy 91.82014 -398.859617) (xy 91.766183 -398.873723) (xy 91.710746 -398.879823)
			(xy 91.655012 -398.877786) (xy 91.600169 -398.867656) (xy 91.547385 -398.849649) (xy 91.497785 -398.824148)
			(xy 91.452427 -398.791697) (xy 91.412278 -398.752988) (xy 91.378192 -398.708845) (xy 91.350896 -398.66021)
			(xy 91.330973 -398.608119) (xy 91.318847 -398.553682) (xy 91.314776 -398.49806) (xy 88.763903 -398.49806)
			(xy 88.794621 -398.516807) (xy 88.837489 -398.552482) (xy 88.874706 -398.594019) (xy 88.905479 -398.640532)
			(xy 88.929151 -398.691029) (xy 88.945219 -398.744436) (xy 88.953339 -398.799612) (xy 88.953848 -398.827498)
			(xy 88.953339 -398.855384) (xy 88.945219 -398.91056) (xy 88.929151 -398.963967) (xy 88.905479 -399.014464)
			(xy 88.894234 -399.03146) (xy 89.880438 -399.03146) (xy 89.884509 -398.975838) (xy 89.896635 -398.921401)
			(xy 89.916558 -398.86931) (xy 89.943854 -398.820675) (xy 89.97794 -398.776532) (xy 90.018089 -398.737823)
			(xy 90.063447 -398.705372) (xy 90.113047 -398.679871) (xy 90.165831 -398.661864) (xy 90.220674 -398.651734)
			(xy 90.276408 -398.649697) (xy 90.331845 -398.655797) (xy 90.385802 -398.669903) (xy 90.437131 -398.691715)
			(xy 90.484737 -398.720769) (xy 90.527605 -398.756444) (xy 90.564822 -398.797981) (xy 90.595595 -398.844494)
			(xy 90.619267 -398.894991) (xy 90.635335 -398.948398) (xy 90.643455 -399.003574) (xy 90.643964 -399.03146)
			(xy 90.643455 -399.059346) (xy 90.635335 -399.114522) (xy 90.619267 -399.167929) (xy 90.595595 -399.218426)
			(xy 90.564822 -399.264939) (xy 90.527605 -399.306476) (xy 90.484737 -399.342151) (xy 90.437131 -399.371205)
			(xy 90.385802 -399.393017) (xy 90.331845 -399.407123) (xy 90.276408 -399.413223) (xy 90.220674 -399.411186)
			(xy 90.165831 -399.401056) (xy 90.113047 -399.383049) (xy 90.063447 -399.357548) (xy 90.018089 -399.325097)
			(xy 89.97794 -399.286388) (xy 89.943854 -399.242245) (xy 89.916558 -399.19361) (xy 89.896635 -399.141519)
			(xy 89.884509 -399.087082) (xy 89.880438 -399.03146) (xy 88.894234 -399.03146) (xy 88.874706 -399.060977)
			(xy 88.837489 -399.102514) (xy 88.794621 -399.138189) (xy 88.747015 -399.167243) (xy 88.695686 -399.189055)
			(xy 88.641729 -399.203161) (xy 88.586292 -399.209261) (xy 88.530558 -399.207224) (xy 88.475715 -399.197094)
			(xy 88.422931 -399.179087) (xy 88.373331 -399.153586) (xy 88.327973 -399.121135) (xy 88.287824 -399.082426)
			(xy 88.253738 -399.038283) (xy 88.226442 -398.989648) (xy 88.206519 -398.937557) (xy 88.194393 -398.88312)
			(xy 88.190322 -398.827498) (xy 82.557866 -398.827498) (xy 82.558019 -398.82773) (xy 82.581691 -398.878227)
			(xy 82.597759 -398.931634) (xy 82.605879 -398.98681) (xy 82.606388 -399.014696) (xy 82.605879 -399.042582)
			(xy 82.597759 -399.097758) (xy 82.581691 -399.151165) (xy 82.558019 -399.201662) (xy 82.527246 -399.248175)
			(xy 82.490029 -399.289712) (xy 82.467669 -399.30832) (xy 86.84209 -399.30832) (xy 86.846161 -399.252698)
			(xy 86.858287 -399.198261) (xy 86.87821 -399.14617) (xy 86.905506 -399.097535) (xy 86.939592 -399.053392)
			(xy 86.979741 -399.014683) (xy 87.025099 -398.982232) (xy 87.074699 -398.956731) (xy 87.127483 -398.938724)
			(xy 87.182326 -398.928594) (xy 87.23806 -398.926557) (xy 87.293497 -398.932657) (xy 87.347454 -398.946763)
			(xy 87.398783 -398.968575) (xy 87.446389 -398.997629) (xy 87.489257 -399.033304) (xy 87.526474 -399.074841)
			(xy 87.557247 -399.121354) (xy 87.580919 -399.171851) (xy 87.596987 -399.225258) (xy 87.605107 -399.280434)
			(xy 87.605616 -399.30832) (xy 87.605107 -399.336206) (xy 87.596987 -399.391382) (xy 87.580919 -399.444789)
			(xy 87.557247 -399.495286) (xy 87.526474 -399.541799) (xy 87.489257 -399.583336) (xy 87.446389 -399.619011)
			(xy 87.398783 -399.648065) (xy 87.347454 -399.669877) (xy 87.293497 -399.683983) (xy 87.23806 -399.690083)
			(xy 87.182326 -399.688046) (xy 87.127483 -399.677916) (xy 87.074699 -399.659909) (xy 87.025099 -399.634408)
			(xy 86.979741 -399.601957) (xy 86.939592 -399.563248) (xy 86.905506 -399.519105) (xy 86.87821 -399.47047)
			(xy 86.858287 -399.418379) (xy 86.846161 -399.363942) (xy 86.84209 -399.30832) (xy 82.467669 -399.30832)
			(xy 82.447161 -399.325387) (xy 82.399555 -399.354441) (xy 82.348226 -399.376253) (xy 82.294269 -399.390359)
			(xy 82.238832 -399.396459) (xy 82.183098 -399.394422) (xy 82.128255 -399.384292) (xy 82.075471 -399.366285)
			(xy 82.025871 -399.340784) (xy 81.980513 -399.308333) (xy 81.940364 -399.269624) (xy 81.906278 -399.225481)
			(xy 81.878982 -399.176846) (xy 81.859059 -399.124755) (xy 81.846933 -399.070318) (xy 81.842862 -399.014696)
			(xy 36.461247 -399.014696) (xy 36.4555 -399.045437) (xy 36.431719 -399.129019) (xy 36.400327 -399.210051)
			(xy 36.361593 -399.28784) (xy 36.315846 -399.361724) (xy 36.263477 -399.431071) (xy 36.204933 -399.495291)
			(xy 36.140713 -399.553835) (xy 36.071366 -399.606204) (xy 35.997482 -399.651951) (xy 35.919693 -399.690685)
			(xy 35.838661 -399.722077) (xy 35.76007 -399.744438) (xy 84.952584 -399.744438) (xy 84.956655 -399.688816)
			(xy 84.968781 -399.634379) (xy 84.988704 -399.582288) (xy 85.016 -399.533653) (xy 85.050086 -399.48951)
			(xy 85.090235 -399.450801) (xy 85.135593 -399.41835) (xy 85.185193 -399.392849) (xy 85.237977 -399.374842)
			(xy 85.29282 -399.364712) (xy 85.348554 -399.362675) (xy 85.403991 -399.368775) (xy 85.457948 -399.382881)
			(xy 85.509277 -399.404693) (xy 85.556883 -399.433747) (xy 85.599751 -399.469422) (xy 85.636968 -399.510959)
			(xy 85.667741 -399.557472) (xy 85.691413 -399.607969) (xy 85.707481 -399.661376) (xy 85.715601 -399.716552)
			(xy 85.71611 -399.744438) (xy 85.715601 -399.772324) (xy 85.707481 -399.8275) (xy 85.691413 -399.880907)
			(xy 85.667741 -399.931404) (xy 85.636968 -399.977917) (xy 85.599751 -400.019454) (xy 85.556883 -400.055129)
			(xy 85.509277 -400.084183) (xy 85.457948 -400.105995) (xy 85.437985 -400.111214) (xy 88.072212 -400.111214)
			(xy 88.076283 -400.055592) (xy 88.088409 -400.001155) (xy 88.108332 -399.949064) (xy 88.135628 -399.900429)
			(xy 88.169714 -399.856286) (xy 88.209863 -399.817577) (xy 88.255221 -399.785126) (xy 88.304821 -399.759625)
			(xy 88.357605 -399.741618) (xy 88.412448 -399.731488) (xy 88.468182 -399.729451) (xy 88.523619 -399.735551)
			(xy 88.577576 -399.749657) (xy 88.628905 -399.771469) (xy 88.676511 -399.800523) (xy 88.719379 -399.836198)
			(xy 88.756596 -399.877735) (xy 88.787369 -399.924248) (xy 88.811041 -399.974745) (xy 88.827109 -400.028152)
			(xy 88.835229 -400.083328) (xy 88.835738 -400.111214) (xy 88.835229 -400.1391) (xy 88.827109 -400.194276)
			(xy 88.811041 -400.247683) (xy 88.787369 -400.29818) (xy 88.756596 -400.344693) (xy 88.719379 -400.38623)
			(xy 88.676511 -400.421905) (xy 88.628905 -400.450959) (xy 88.577576 -400.472771) (xy 88.523619 -400.486877)
			(xy 88.468182 -400.492977) (xy 88.412448 -400.49094) (xy 88.357605 -400.48081) (xy 88.304821 -400.462803)
			(xy 88.255221 -400.437302) (xy 88.209863 -400.404851) (xy 88.169714 -400.366142) (xy 88.135628 -400.321999)
			(xy 88.108332 -400.273364) (xy 88.088409 -400.221273) (xy 88.076283 -400.166836) (xy 88.072212 -400.111214)
			(xy 85.437985 -400.111214) (xy 85.403991 -400.120101) (xy 85.348554 -400.126201) (xy 85.29282 -400.124164)
			(xy 85.237977 -400.114034) (xy 85.185193 -400.096027) (xy 85.135593 -400.070526) (xy 85.090235 -400.038075)
			(xy 85.050086 -399.999366) (xy 85.016 -399.955223) (xy 84.988704 -399.906588) (xy 84.968781 -399.854497)
			(xy 84.956655 -399.80006) (xy 84.952584 -399.744438) (xy 35.76007 -399.744438) (xy 35.755079 -399.745858)
			(xy 35.669659 -399.761826) (xy 35.58313 -399.769844) (xy 35.49623 -399.769844) (xy 35.409701 -399.761826)
			(xy 35.324281 -399.745858) (xy 35.240699 -399.722077) (xy 35.159667 -399.690685) (xy 35.081878 -399.651951)
			(xy 35.007994 -399.606204) (xy 34.938647 -399.553835) (xy 34.874427 -399.495291) (xy 34.815883 -399.431071)
			(xy 34.763514 -399.361724) (xy 34.717767 -399.28784) (xy 34.679033 -399.210051) (xy 34.647641 -399.129019)
			(xy 34.62386 -399.045437) (xy 34.607892 -398.960017) (xy 34.599874 -398.873488) (xy 31.3995 -398.873488)
			(xy 31.391522 -398.959749) (xy 31.375606 -399.04504) (xy 31.351902 -399.128501) (xy 31.320609 -399.209424)
			(xy 31.281995 -399.287119) (xy 31.236387 -399.360928) (xy 31.184174 -399.43022) (xy 31.125799 -399.494409)
			(xy 31.061759 -399.552946) (xy 30.992599 -399.605335) (xy 30.918907 -399.65113) (xy 30.84131 -399.689942)
			(xy 30.760467 -399.72144) (xy 30.677066 -399.745357) (xy 30.591817 -399.761489) (xy 30.505444 -399.769699)
			(xy 30.418681 -399.769917) (xy 30.332268 -399.762141) (xy 30.246939 -399.746438) (xy 30.163419 -399.722941)
			(xy 30.082418 -399.69185) (xy 30.004627 -399.653429) (xy 29.930705 -399.608005) (xy 29.861283 -399.555964)
			(xy 29.828744 -399.527268) (xy 29.811703 -399.512502) (xy 29.773459 -399.488621) (xy 29.731602 -399.471862)
			(xy 29.687444 -399.462753) (xy 29.642372 -399.461577) (xy 29.5978 -399.468373) (xy 29.555126 -399.482928)
			(xy 29.51569 -399.504783) (xy 29.48073 -399.533254) (xy 29.451341 -399.567447) (xy 29.428447 -399.60629)
			(xy 29.412766 -399.648562) (xy 29.404789 -399.692939) (xy 29.40431 -399.715482) (xy 29.40431 -400.271234)
			(xy 78.88554 -400.271234) (xy 78.889611 -400.215612) (xy 78.901737 -400.161175) (xy 78.92166 -400.109084)
			(xy 78.948956 -400.060449) (xy 78.983042 -400.016306) (xy 79.023191 -399.977597) (xy 79.068549 -399.945146)
			(xy 79.118149 -399.919645) (xy 79.170933 -399.901638) (xy 79.225776 -399.891508) (xy 79.28151 -399.889471)
			(xy 79.336947 -399.895571) (xy 79.390904 -399.909677) (xy 79.442233 -399.931489) (xy 79.489839 -399.960543)
			(xy 79.532707 -399.996218) (xy 79.569924 -400.037755) (xy 79.600697 -400.084268) (xy 79.624369 -400.134765)
			(xy 79.640437 -400.188172) (xy 79.648557 -400.243348) (xy 79.649066 -400.271234) (xy 79.648557 -400.29912)
			(xy 79.640437 -400.354296) (xy 79.624369 -400.407703) (xy 79.600697 -400.4582) (xy 79.569924 -400.504713)
			(xy 79.532707 -400.54625) (xy 79.489839 -400.581925) (xy 79.442233 -400.610979) (xy 79.390904 -400.632791)
			(xy 79.336947 -400.646897) (xy 79.28151 -400.652997) (xy 79.225776 -400.65096) (xy 79.170933 -400.64083)
			(xy 79.118149 -400.622823) (xy 79.068549 -400.597322) (xy 79.023191 -400.564871) (xy 78.983042 -400.526162)
			(xy 78.948956 -400.482019) (xy 78.92166 -400.433384) (xy 78.901737 -400.381293) (xy 78.889611 -400.326856)
			(xy 78.88554 -400.271234) (xy 29.40431 -400.271234) (xy 29.40431 -400.484594) (xy 29.404797 -400.507138)
			(xy 29.412756 -400.551518) (xy 29.428424 -400.593796) (xy 29.451309 -400.632644) (xy 29.480693 -400.666842)
			(xy 29.515653 -400.695316) (xy 29.55509 -400.717171) (xy 29.597766 -400.731721) (xy 29.64234 -400.738508)
			(xy 29.687412 -400.73732) (xy 29.731567 -400.728194) (xy 29.773417 -400.711417) (xy 29.811648 -400.687515)
			(xy 29.828744 -400.672808) (xy 29.861244 -400.644069) (xy 29.930663 -400.592024) (xy 30.004582 -400.546596)
			(xy 30.082372 -400.508171) (xy 30.16337 -400.477075) (xy 30.246889 -400.453573) (xy 30.332218 -400.437866)
			(xy 30.41863 -400.430085) (xy 30.505393 -400.430299) (xy 30.591766 -400.438504) (xy 30.677016 -400.454631)
			(xy 30.760419 -400.478543) (xy 30.841263 -400.510037) (xy 30.918863 -400.548845) (xy 30.992557 -400.594636)
			(xy 31.06172 -400.647021) (xy 31.125763 -400.705555) (xy 31.184141 -400.76974) (xy 31.236358 -400.83903)
			(xy 31.28197 -400.912836) (xy 31.320588 -400.99053) (xy 31.351885 -401.071451) (xy 31.375595 -401.154911)
			(xy 31.391515 -401.2402) (xy 31.39951 -401.326593) (xy 31.399512 -401.413356) (xy 31.3995 -401.413488)
			(xy 34.599874 -401.413488) (xy 34.599874 -401.326588) (xy 34.607892 -401.240059) (xy 34.62386 -401.154639)
			(xy 34.647641 -401.071057) (xy 34.679033 -400.990025) (xy 34.717767 -400.912236) (xy 34.763514 -400.838352)
			(xy 34.815883 -400.769005) (xy 34.874427 -400.704785) (xy 34.938647 -400.646241) (xy 35.007994 -400.593872)
			(xy 35.081878 -400.548125) (xy 35.159667 -400.509391) (xy 35.240699 -400.477999) (xy 35.324281 -400.454218)
			(xy 35.409701 -400.43825) (xy 35.49623 -400.430232) (xy 35.58313 -400.430232) (xy 35.669659 -400.43825)
			(xy 35.755079 -400.454218) (xy 35.838661 -400.477999) (xy 35.919693 -400.509391) (xy 35.997482 -400.548125)
			(xy 36.071366 -400.593872) (xy 36.140713 -400.646241) (xy 36.204933 -400.704785) (xy 36.263477 -400.769005)
			(xy 36.315846 -400.838352) (xy 36.361593 -400.912236) (xy 36.400327 -400.990025) (xy 36.431719 -401.071057)
			(xy 36.4555 -401.154639) (xy 36.471468 -401.240059) (xy 36.479486 -401.326588) (xy 36.479988 -401.370038)
			(xy 36.479486 -401.413488) (xy 36.471468 -401.500017) (xy 36.4555 -401.585437) (xy 36.431719 -401.669019)
			(xy 36.400327 -401.750051) (xy 36.361593 -401.82784) (xy 36.315846 -401.901724) (xy 36.263477 -401.971071)
			(xy 36.204933 -402.035291) (xy 36.140713 -402.093835) (xy 36.071366 -402.146204) (xy 35.997482 -402.191951)
			(xy 35.919693 -402.230685) (xy 35.838661 -402.262077) (xy 35.755079 -402.285858) (xy 35.669659 -402.301826)
			(xy 35.58313 -402.309844) (xy 35.49623 -402.309844) (xy 35.409701 -402.301826) (xy 35.324281 -402.285858)
			(xy 35.240699 -402.262077) (xy 35.159667 -402.230685) (xy 35.081878 -402.191951) (xy 35.007994 -402.146204)
			(xy 34.938647 -402.093835) (xy 34.874427 -402.035291) (xy 34.815883 -401.971071) (xy 34.763514 -401.901724)
			(xy 34.717767 -401.82784) (xy 34.679033 -401.750051) (xy 34.647641 -401.669019) (xy 34.62386 -401.585437)
			(xy 34.607892 -401.500017) (xy 34.599874 -401.413488) (xy 31.3995 -401.413488) (xy 31.391522 -401.499749)
			(xy 31.375606 -401.58504) (xy 31.351902 -401.668501) (xy 31.320609 -401.749424) (xy 31.281995 -401.827119)
			(xy 31.236387 -401.900928) (xy 31.184174 -401.97022) (xy 31.125799 -402.034409) (xy 31.061759 -402.092946)
			(xy 30.992599 -402.145335) (xy 30.918907 -402.19113) (xy 30.84131 -402.229942) (xy 30.760467 -402.26144)
			(xy 30.677066 -402.285357) (xy 30.591817 -402.301489) (xy 30.505444 -402.309699) (xy 30.418681 -402.309917)
			(xy 30.332268 -402.302141) (xy 30.246939 -402.286438) (xy 30.163419 -402.262941) (xy 30.082418 -402.23185)
			(xy 30.004627 -402.193429) (xy 29.930705 -402.148005) (xy 29.861283 -402.095964) (xy 29.828744 -402.067268)
			(xy 29.811703 -402.052502) (xy 29.773459 -402.028621) (xy 29.731602 -402.011862) (xy 29.687444 -402.002753)
			(xy 29.642372 -402.001577) (xy 29.5978 -402.008373) (xy 29.555126 -402.022928) (xy 29.51569 -402.044783)
			(xy 29.48073 -402.073254) (xy 29.451341 -402.107447) (xy 29.428447 -402.14629) (xy 29.412766 -402.188562)
			(xy 29.404789 -402.232939) (xy 29.40431 -402.255482) (xy 29.40431 -403.024594) (xy 29.404797 -403.047138)
			(xy 29.412756 -403.091518) (xy 29.428424 -403.133796) (xy 29.451309 -403.172644) (xy 29.480693 -403.206842)
			(xy 29.515653 -403.235316) (xy 29.55509 -403.257171) (xy 29.597766 -403.271721) (xy 29.64234 -403.278508)
			(xy 29.687412 -403.27732) (xy 29.731567 -403.268194) (xy 29.773417 -403.251417) (xy 29.811648 -403.227515)
			(xy 29.828744 -403.212808) (xy 29.861244 -403.184069) (xy 29.930663 -403.132024) (xy 30.004582 -403.086596)
			(xy 30.082372 -403.048171) (xy 30.16337 -403.017075) (xy 30.246889 -402.993573) (xy 30.332218 -402.977866)
			(xy 30.41863 -402.970085) (xy 30.505393 -402.970299) (xy 30.591766 -402.978504) (xy 30.677016 -402.994631)
			(xy 30.760419 -403.018543) (xy 30.841263 -403.050037) (xy 30.918863 -403.088845) (xy 30.992557 -403.134636)
			(xy 31.06172 -403.187021) (xy 31.125763 -403.245555) (xy 31.184141 -403.30974) (xy 31.236358 -403.37903)
			(xy 31.28197 -403.452836) (xy 31.320588 -403.53053) (xy 31.351885 -403.611451) (xy 31.375595 -403.694911)
			(xy 31.391515 -403.7802) (xy 31.39951 -403.866593) (xy 31.399512 -403.953356) (xy 31.3995 -403.953488)
			(xy 34.599874 -403.953488) (xy 34.599874 -403.866588) (xy 34.607892 -403.780059) (xy 34.62386 -403.694639)
			(xy 34.647641 -403.611057) (xy 34.679033 -403.530025) (xy 34.717767 -403.452236) (xy 34.763514 -403.378352)
			(xy 34.815883 -403.309005) (xy 34.874427 -403.244785) (xy 34.938647 -403.186241) (xy 35.007994 -403.133872)
			(xy 35.081878 -403.088125) (xy 35.159667 -403.049391) (xy 35.240699 -403.017999) (xy 35.324281 -402.994218)
			(xy 35.409701 -402.97825) (xy 35.49623 -402.970232) (xy 35.58313 -402.970232) (xy 35.669659 -402.97825)
			(xy 35.755079 -402.994218) (xy 35.838661 -403.017999) (xy 35.919693 -403.049391) (xy 35.997482 -403.088125)
			(xy 36.071366 -403.133872) (xy 36.140713 -403.186241) (xy 36.204933 -403.244785) (xy 36.263477 -403.309005)
			(xy 36.315846 -403.378352) (xy 36.361593 -403.452236) (xy 36.400327 -403.530025) (xy 36.431719 -403.611057)
			(xy 36.4555 -403.694639) (xy 36.471468 -403.780059) (xy 36.479486 -403.866588) (xy 36.479988 -403.910038)
			(xy 36.479486 -403.953488) (xy 36.471468 -404.040017) (xy 36.4555 -404.125437) (xy 36.431719 -404.209019)
			(xy 36.400327 -404.290051) (xy 36.361593 -404.36784) (xy 36.315846 -404.441724) (xy 36.263477 -404.511071)
			(xy 36.204933 -404.575291) (xy 36.140713 -404.633835) (xy 36.071366 -404.686204) (xy 35.997482 -404.731951)
			(xy 35.919693 -404.770685) (xy 35.838661 -404.802077) (xy 35.755079 -404.825858) (xy 35.669659 -404.841826)
			(xy 35.58313 -404.849844) (xy 35.49623 -404.849844) (xy 35.409701 -404.841826) (xy 35.324281 -404.825858)
			(xy 35.240699 -404.802077) (xy 35.159667 -404.770685) (xy 35.081878 -404.731951) (xy 35.007994 -404.686204)
			(xy 34.938647 -404.633835) (xy 34.874427 -404.575291) (xy 34.815883 -404.511071) (xy 34.763514 -404.441724)
			(xy 34.717767 -404.36784) (xy 34.679033 -404.290051) (xy 34.647641 -404.209019) (xy 34.62386 -404.125437)
			(xy 34.607892 -404.040017) (xy 34.599874 -403.953488) (xy 31.3995 -403.953488) (xy 31.391522 -404.039749)
			(xy 31.375606 -404.12504) (xy 31.351902 -404.208501) (xy 31.320609 -404.289424) (xy 31.281995 -404.367119)
			(xy 31.236387 -404.440928) (xy 31.184174 -404.51022) (xy 31.125799 -404.574409) (xy 31.061759 -404.632946)
			(xy 30.992599 -404.685335) (xy 30.918907 -404.73113) (xy 30.84131 -404.769942) (xy 30.760467 -404.80144)
			(xy 30.677066 -404.825357) (xy 30.591817 -404.841489) (xy 30.505444 -404.849699) (xy 30.418681 -404.849917)
			(xy 30.332268 -404.842141) (xy 30.246939 -404.826438) (xy 30.163419 -404.802941) (xy 30.082418 -404.77185)
			(xy 30.004627 -404.733429) (xy 29.930705 -404.688005) (xy 29.861283 -404.635964) (xy 29.828744 -404.607268)
			(xy 29.811703 -404.592502) (xy 29.773459 -404.568621) (xy 29.731602 -404.551862) (xy 29.687444 -404.542753)
			(xy 29.642372 -404.541577) (xy 29.5978 -404.548373) (xy 29.555126 -404.562928) (xy 29.51569 -404.584783)
			(xy 29.48073 -404.613254) (xy 29.451341 -404.647447) (xy 29.428447 -404.68629) (xy 29.412766 -404.728562)
			(xy 29.404789 -404.772939) (xy 29.40431 -404.795482) (xy 29.40431 -405.564594) (xy 29.404797 -405.587138)
			(xy 29.412756 -405.631518) (xy 29.428424 -405.673796) (xy 29.451309 -405.712644) (xy 29.480693 -405.746842)
			(xy 29.515653 -405.775316) (xy 29.55509 -405.797171) (xy 29.597766 -405.811721) (xy 29.64234 -405.818508)
			(xy 29.687412 -405.81732) (xy 29.731567 -405.808194) (xy 29.773417 -405.791417) (xy 29.811648 -405.767515)
			(xy 29.828744 -405.752808) (xy 29.861244 -405.724069) (xy 29.930663 -405.672024) (xy 30.004582 -405.626596)
			(xy 30.082372 -405.588171) (xy 30.16337 -405.557075) (xy 30.246889 -405.533573) (xy 30.332218 -405.517866)
			(xy 30.41863 -405.510085) (xy 30.505393 -405.510299) (xy 30.591766 -405.518504) (xy 30.677016 -405.534631)
			(xy 30.760419 -405.558543) (xy 30.841263 -405.590037) (xy 30.918863 -405.628845) (xy 30.992557 -405.674636)
			(xy 31.06172 -405.727021) (xy 31.125763 -405.785555) (xy 31.184141 -405.84974) (xy 31.236358 -405.91903)
			(xy 31.28197 -405.992836) (xy 31.320588 -406.07053) (xy 31.351885 -406.151451) (xy 31.375595 -406.234911)
			(xy 31.391515 -406.3202) (xy 31.39951 -406.406593) (xy 31.399512 -406.493356) (xy 31.3995 -406.493488)
			(xy 34.599874 -406.493488) (xy 34.599874 -406.406588) (xy 34.607892 -406.320059) (xy 34.62386 -406.234639)
			(xy 34.647641 -406.151057) (xy 34.679033 -406.070025) (xy 34.717767 -405.992236) (xy 34.763514 -405.918352)
			(xy 34.815883 -405.849005) (xy 34.874427 -405.784785) (xy 34.938647 -405.726241) (xy 35.007994 -405.673872)
			(xy 35.081878 -405.628125) (xy 35.159667 -405.589391) (xy 35.240699 -405.557999) (xy 35.324281 -405.534218)
			(xy 35.409701 -405.51825) (xy 35.49623 -405.510232) (xy 35.58313 -405.510232) (xy 35.669659 -405.51825)
			(xy 35.755079 -405.534218) (xy 35.838661 -405.557999) (xy 35.919693 -405.589391) (xy 35.997482 -405.628125)
			(xy 36.071366 -405.673872) (xy 36.140713 -405.726241) (xy 36.204933 -405.784785) (xy 36.263477 -405.849005)
			(xy 36.315846 -405.918352) (xy 36.361593 -405.992236) (xy 36.400327 -406.070025) (xy 36.431719 -406.151057)
			(xy 36.4555 -406.234639) (xy 36.471468 -406.320059) (xy 36.479486 -406.406588) (xy 36.479988 -406.450038)
			(xy 36.479486 -406.493488) (xy 36.471468 -406.580017) (xy 36.4555 -406.665437) (xy 36.431719 -406.749019)
			(xy 36.400327 -406.830051) (xy 36.361593 -406.90784) (xy 36.329254 -406.96007) (xy 39.818564 -406.96007)
			(xy 39.819058 -406.902661) (xy 39.826902 -406.788113) (xy 39.842544 -406.674366) (xy 39.865911 -406.561952)
			(xy 39.896896 -406.451394) (xy 39.935352 -406.343209) (xy 39.981101 -406.2379) (xy 40.03393 -406.135958)
			(xy 40.093592 -406.037859) (xy 40.159809 -405.94406) (xy 40.232272 -405.854998) (xy 40.310645 -405.771089)
			(xy 40.39456 -405.692723) (xy 40.483627 -405.620266) (xy 40.577431 -405.554056) (xy 40.675535 -405.494402)
			(xy 40.777481 -405.441581) (xy 40.882793 -405.395839) (xy 40.990981 -405.357391) (xy 41.101541 -405.326415)
			(xy 41.213957 -405.303056) (xy 41.327705 -405.287423) (xy 41.442254 -405.279588) (xy 41.557072 -405.279588)
			(xy 41.671621 -405.287423) (xy 41.785369 -405.303056) (xy 41.897785 -405.326415) (xy 42.008345 -405.357391)
			(xy 42.116533 -405.395839) (xy 42.221845 -405.441581) (xy 42.323791 -405.494402) (xy 42.421895 -405.554056)
			(xy 42.501239 -405.61006) (xy 43.327577 -405.61006) (xy 43.331612 -405.534356) (xy 43.343671 -405.459511)
			(xy 43.363617 -405.38637) (xy 43.391224 -405.315765) (xy 43.42618 -405.248494) (xy 43.468088 -405.185319)
			(xy 43.516474 -405.126957) (xy 43.57079 -405.074069) (xy 43.630419 -405.027254) (xy 43.694687 -404.987042)
			(xy 43.762864 -404.95389) (xy 43.83418 -404.928172) (xy 43.907825 -404.91018) (xy 43.982965 -404.900118)
			(xy 44.058749 -404.898099) (xy 44.134319 -404.904148) (xy 44.208817 -404.918195) (xy 44.2814 -404.940081)
			(xy 44.351246 -404.969558) (xy 44.417563 -405.006293) (xy 44.479599 -405.049868) (xy 44.536652 -405.09979)
			(xy 44.588076 -405.155494) (xy 44.633287 -405.216349) (xy 44.671774 -405.281664) (xy 44.7031 -405.3507)
			(xy 44.72691 -405.422675) (xy 44.742935 -405.496773) (xy 44.750994 -405.572154) (xy 44.751498 -405.61006)
			(xy 45.867577 -405.61006) (xy 45.871612 -405.534356) (xy 45.883671 -405.459511) (xy 45.903617 -405.38637)
			(xy 45.931224 -405.315765) (xy 45.96618 -405.248494) (xy 46.008088 -405.185319) (xy 46.056474 -405.126957)
			(xy 46.11079 -405.074069) (xy 46.170419 -405.027254) (xy 46.234687 -404.987042) (xy 46.302864 -404.95389)
			(xy 46.37418 -404.928172) (xy 46.447825 -404.91018) (xy 46.522965 -404.900118) (xy 46.598749 -404.898099)
			(xy 46.674319 -404.904148) (xy 46.748817 -404.918195) (xy 46.8214 -404.940081) (xy 46.891246 -404.969558)
			(xy 46.957563 -405.006293) (xy 47.019599 -405.049868) (xy 47.076652 -405.09979) (xy 47.128076 -405.155494)
			(xy 47.173287 -405.216349) (xy 47.211774 -405.281664) (xy 47.2431 -405.3507) (xy 47.26691 -405.422675)
			(xy 47.282935 -405.496773) (xy 47.290994 -405.572154) (xy 47.291498 -405.61006) (xy 48.407577 -405.61006)
			(xy 48.411612 -405.534356) (xy 48.423671 -405.459511) (xy 48.443617 -405.38637) (xy 48.471224 -405.315765)
			(xy 48.50618 -405.248494) (xy 48.548088 -405.185319) (xy 48.596474 -405.126957) (xy 48.65079 -405.074069)
			(xy 48.710419 -405.027254) (xy 48.774687 -404.987042) (xy 48.842864 -404.95389) (xy 48.91418 -404.928172)
			(xy 48.987825 -404.91018) (xy 49.062965 -404.900118) (xy 49.138749 -404.898099) (xy 49.214319 -404.904148)
			(xy 49.288817 -404.918195) (xy 49.3614 -404.940081) (xy 49.431246 -404.969558) (xy 49.497563 -405.006293)
			(xy 49.559599 -405.049868) (xy 49.616652 -405.09979) (xy 49.668076 -405.155494) (xy 49.713287 -405.216349)
			(xy 49.751774 -405.281664) (xy 49.7831 -405.3507) (xy 49.80691 -405.422675) (xy 49.822935 -405.496773)
			(xy 49.830994 -405.572154) (xy 49.831498 -405.61006) (xy 50.947577 -405.61006) (xy 50.951612 -405.534356)
			(xy 50.963671 -405.459511) (xy 50.983617 -405.38637) (xy 51.011224 -405.315765) (xy 51.04618 -405.248494)
			(xy 51.088088 -405.185319) (xy 51.136474 -405.126957) (xy 51.19079 -405.074069) (xy 51.250419 -405.027254)
			(xy 51.314687 -404.987042) (xy 51.382864 -404.95389) (xy 51.45418 -404.928172) (xy 51.527825 -404.91018)
			(xy 51.602965 -404.900118) (xy 51.678749 -404.898099) (xy 51.754319 -404.904148) (xy 51.828817 -404.918195)
			(xy 51.9014 -404.940081) (xy 51.971246 -404.969558) (xy 52.037563 -405.006293) (xy 52.099599 -405.049868)
			(xy 52.156652 -405.09979) (xy 52.208076 -405.155494) (xy 52.253287 -405.216349) (xy 52.291774 -405.281664)
			(xy 52.3231 -405.3507) (xy 52.34691 -405.422675) (xy 52.362935 -405.496773) (xy 52.370994 -405.572154)
			(xy 52.371498 -405.61006) (xy 53.487577 -405.61006) (xy 53.491612 -405.534356) (xy 53.503671 -405.459511)
			(xy 53.523617 -405.38637) (xy 53.551224 -405.315765) (xy 53.58618 -405.248494) (xy 53.628088 -405.185319)
			(xy 53.676474 -405.126957) (xy 53.73079 -405.074069) (xy 53.790419 -405.027254) (xy 53.854687 -404.987042)
			(xy 53.922864 -404.95389) (xy 53.99418 -404.928172) (xy 54.067825 -404.91018) (xy 54.142965 -404.900118)
			(xy 54.218749 -404.898099) (xy 54.294319 -404.904148) (xy 54.368817 -404.918195) (xy 54.4414 -404.940081)
			(xy 54.511246 -404.969558) (xy 54.577563 -405.006293) (xy 54.639599 -405.049868) (xy 54.696652 -405.09979)
			(xy 54.748076 -405.155494) (xy 54.793287 -405.216349) (xy 54.831774 -405.281664) (xy 54.8631 -405.3507)
			(xy 54.88691 -405.422675) (xy 54.902935 -405.496773) (xy 54.910994 -405.572154) (xy 54.911498 -405.61006)
			(xy 56.027577 -405.61006) (xy 56.031612 -405.534356) (xy 56.043671 -405.459511) (xy 56.063617 -405.38637)
			(xy 56.091224 -405.315765) (xy 56.12618 -405.248494) (xy 56.168088 -405.185319) (xy 56.216474 -405.126957)
			(xy 56.27079 -405.074069) (xy 56.330419 -405.027254) (xy 56.394687 -404.987042) (xy 56.462864 -404.95389)
			(xy 56.53418 -404.928172) (xy 56.607825 -404.91018) (xy 56.682965 -404.900118) (xy 56.758749 -404.898099)
			(xy 56.834319 -404.904148) (xy 56.908817 -404.918195) (xy 56.9814 -404.940081) (xy 57.051246 -404.969558)
			(xy 57.117563 -405.006293) (xy 57.179599 -405.049868) (xy 57.236652 -405.09979) (xy 57.288076 -405.155494)
			(xy 57.333287 -405.216349) (xy 57.371774 -405.281664) (xy 57.4031 -405.3507) (xy 57.42691 -405.422675)
			(xy 57.442935 -405.496773) (xy 57.450994 -405.572154) (xy 57.451498 -405.61006) (xy 58.567577 -405.61006)
			(xy 58.571612 -405.534356) (xy 58.583671 -405.459511) (xy 58.603617 -405.38637) (xy 58.631224 -405.315765)
			(xy 58.66618 -405.248494) (xy 58.708088 -405.185319) (xy 58.756474 -405.126957) (xy 58.81079 -405.074069)
			(xy 58.870419 -405.027254) (xy 58.934687 -404.987042) (xy 59.002864 -404.95389) (xy 59.07418 -404.928172)
			(xy 59.147825 -404.91018) (xy 59.222965 -404.900118) (xy 59.298749 -404.898099) (xy 59.374319 -404.904148)
			(xy 59.448817 -404.918195) (xy 59.5214 -404.940081) (xy 59.591246 -404.969558) (xy 59.657563 -405.006293)
			(xy 59.719599 -405.049868) (xy 59.776652 -405.09979) (xy 59.828076 -405.155494) (xy 59.873287 -405.216349)
			(xy 59.911774 -405.281664) (xy 59.9431 -405.3507) (xy 59.96691 -405.422675) (xy 59.982935 -405.496773)
			(xy 59.990994 -405.572154) (xy 59.991498 -405.61006) (xy 61.107577 -405.61006) (xy 61.111612 -405.534356)
			(xy 61.123671 -405.459511) (xy 61.143617 -405.38637) (xy 61.171224 -405.315765) (xy 61.20618 -405.248494)
			(xy 61.248088 -405.185319) (xy 61.296474 -405.126957) (xy 61.35079 -405.074069) (xy 61.410419 -405.027254)
			(xy 61.474687 -404.987042) (xy 61.542864 -404.95389) (xy 61.61418 -404.928172) (xy 61.687825 -404.91018)
			(xy 61.762965 -404.900118) (xy 61.838749 -404.898099) (xy 61.914319 -404.904148) (xy 61.988817 -404.918195)
			(xy 62.0614 -404.940081) (xy 62.131246 -404.969558) (xy 62.197563 -405.006293) (xy 62.259599 -405.049868)
			(xy 62.265544 -405.05507) (xy 86.197697 -405.05507) (xy 86.201732 -404.979366) (xy 86.213791 -404.904521)
			(xy 86.233737 -404.83138) (xy 86.261344 -404.760775) (xy 86.2963 -404.693504) (xy 86.338208 -404.630329)
			(xy 86.386594 -404.571967) (xy 86.44091 -404.519079) (xy 86.500539 -404.472264) (xy 86.564807 -404.432052)
			(xy 86.632984 -404.3989) (xy 86.7043 -404.373182) (xy 86.777945 -404.35519) (xy 86.853085 -404.345128)
			(xy 86.928869 -404.343109) (xy 87.004439 -404.349158) (xy 87.078937 -404.363205) (xy 87.15152 -404.385091)
			(xy 87.221366 -404.414568) (xy 87.287683 -404.451303) (xy 87.349719 -404.494878) (xy 87.406772 -404.5448)
			(xy 87.458196 -404.600504) (xy 87.503407 -404.661359) (xy 87.541894 -404.726674) (xy 87.57322 -404.79571)
			(xy 87.59703 -404.867685) (xy 87.613055 -404.941783) (xy 87.621114 -405.017164) (xy 87.621618 -405.05507)
			(xy 88.737697 -405.05507) (xy 88.741732 -404.979366) (xy 88.753791 -404.904521) (xy 88.773737 -404.83138)
			(xy 88.801344 -404.760775) (xy 88.8363 -404.693504) (xy 88.878208 -404.630329) (xy 88.926594 -404.571967)
			(xy 88.98091 -404.519079) (xy 89.040539 -404.472264) (xy 89.104807 -404.432052) (xy 89.172984 -404.3989)
			(xy 89.2443 -404.373182) (xy 89.317945 -404.35519) (xy 89.393085 -404.345128) (xy 89.468869 -404.343109)
			(xy 89.544439 -404.349158) (xy 89.618937 -404.363205) (xy 89.69152 -404.385091) (xy 89.761366 -404.414568)
			(xy 89.827683 -404.451303) (xy 89.889719 -404.494878) (xy 89.946772 -404.5448) (xy 89.998196 -404.600504)
			(xy 90.043407 -404.661359) (xy 90.081894 -404.726674) (xy 90.11322 -404.79571) (xy 90.13703 -404.867685)
			(xy 90.153055 -404.941783) (xy 90.161114 -405.017164) (xy 90.161618 -405.05507) (xy 91.277697 -405.05507)
			(xy 91.281732 -404.979366) (xy 91.293791 -404.904521) (xy 91.313737 -404.83138) (xy 91.341344 -404.760775)
			(xy 91.3763 -404.693504) (xy 91.418208 -404.630329) (xy 91.466594 -404.571967) (xy 91.52091 -404.519079)
			(xy 91.580539 -404.472264) (xy 91.644807 -404.432052) (xy 91.712984 -404.3989) (xy 91.7843 -404.373182)
			(xy 91.857945 -404.35519) (xy 91.933085 -404.345128) (xy 92.008869 -404.343109) (xy 92.084439 -404.349158)
			(xy 92.158937 -404.363205) (xy 92.23152 -404.385091) (xy 92.301366 -404.414568) (xy 92.367683 -404.451303)
			(xy 92.429719 -404.494878) (xy 92.486772 -404.5448) (xy 92.538196 -404.600504) (xy 92.583407 -404.661359)
			(xy 92.621894 -404.726674) (xy 92.65322 -404.79571) (xy 92.67703 -404.867685) (xy 92.693055 -404.941783)
			(xy 92.701114 -405.017164) (xy 92.701618 -405.05507) (xy 92.701114 -405.092976) (xy 92.693055 -405.168357)
			(xy 92.67703 -405.242455) (xy 92.65322 -405.31443) (xy 92.621894 -405.383466) (xy 92.583407 -405.448781)
			(xy 92.538196 -405.509636) (xy 92.486772 -405.56534) (xy 92.429719 -405.615262) (xy 92.367683 -405.658837)
			(xy 92.301366 -405.695572) (xy 92.23152 -405.725049) (xy 92.158937 -405.746935) (xy 92.084439 -405.760982)
			(xy 92.008869 -405.767031) (xy 91.933085 -405.765012) (xy 91.857945 -405.75495) (xy 91.7843 -405.736958)
			(xy 91.712984 -405.71124) (xy 91.644807 -405.678088) (xy 91.580539 -405.637876) (xy 91.52091 -405.591061)
			(xy 91.466594 -405.538173) (xy 91.418208 -405.479811) (xy 91.3763 -405.416636) (xy 91.341344 -405.349365)
			(xy 91.313737 -405.27876) (xy 91.293791 -405.205619) (xy 91.281732 -405.130774) (xy 91.277697 -405.05507)
			(xy 90.161618 -405.05507) (xy 90.161114 -405.092976) (xy 90.153055 -405.168357) (xy 90.13703 -405.242455)
			(xy 90.11322 -405.31443) (xy 90.081894 -405.383466) (xy 90.043407 -405.448781) (xy 89.998196 -405.509636)
			(xy 89.946772 -405.56534) (xy 89.889719 -405.615262) (xy 89.827683 -405.658837) (xy 89.761366 -405.695572)
			(xy 89.69152 -405.725049) (xy 89.618937 -405.746935) (xy 89.544439 -405.760982) (xy 89.468869 -405.767031)
			(xy 89.393085 -405.765012) (xy 89.317945 -405.75495) (xy 89.2443 -405.736958) (xy 89.172984 -405.71124)
			(xy 89.104807 -405.678088) (xy 89.040539 -405.637876) (xy 88.98091 -405.591061) (xy 88.926594 -405.538173)
			(xy 88.878208 -405.479811) (xy 88.8363 -405.416636) (xy 88.801344 -405.349365) (xy 88.773737 -405.27876)
			(xy 88.753791 -405.205619) (xy 88.741732 -405.130774) (xy 88.737697 -405.05507) (xy 87.621618 -405.05507)
			(xy 87.621114 -405.092976) (xy 87.613055 -405.168357) (xy 87.59703 -405.242455) (xy 87.57322 -405.31443)
			(xy 87.541894 -405.383466) (xy 87.503407 -405.448781) (xy 87.458196 -405.509636) (xy 87.406772 -405.56534)
			(xy 87.349719 -405.615262) (xy 87.287683 -405.658837) (xy 87.221366 -405.695572) (xy 87.15152 -405.725049)
			(xy 87.078937 -405.746935) (xy 87.004439 -405.760982) (xy 86.928869 -405.767031) (xy 86.853085 -405.765012)
			(xy 86.777945 -405.75495) (xy 86.7043 -405.736958) (xy 86.632984 -405.71124) (xy 86.564807 -405.678088)
			(xy 86.500539 -405.637876) (xy 86.44091 -405.591061) (xy 86.386594 -405.538173) (xy 86.338208 -405.479811)
			(xy 86.2963 -405.416636) (xy 86.261344 -405.349365) (xy 86.233737 -405.27876) (xy 86.213791 -405.205619)
			(xy 86.201732 -405.130774) (xy 86.197697 -405.05507) (xy 62.265544 -405.05507) (xy 62.316652 -405.09979)
			(xy 62.368076 -405.155494) (xy 62.413287 -405.216349) (xy 62.451774 -405.281664) (xy 62.4831 -405.3507)
			(xy 62.50691 -405.422675) (xy 62.522935 -405.496773) (xy 62.530994 -405.572154) (xy 62.531498 -405.61006)
			(xy 62.530994 -405.647966) (xy 62.522935 -405.723347) (xy 62.50691 -405.797445) (xy 62.4831 -405.86942)
			(xy 62.451774 -405.938456) (xy 62.413287 -406.003771) (xy 62.368076 -406.064626) (xy 62.316652 -406.12033)
			(xy 62.259599 -406.170252) (xy 62.197563 -406.213827) (xy 62.131246 -406.250562) (xy 62.0614 -406.280039)
			(xy 61.988817 -406.301925) (xy 61.914319 -406.315972) (xy 61.838749 -406.322021) (xy 61.762965 -406.320002)
			(xy 61.687825 -406.30994) (xy 61.61418 -406.291948) (xy 61.542864 -406.26623) (xy 61.474687 -406.233078)
			(xy 61.410419 -406.192866) (xy 61.35079 -406.146051) (xy 61.296474 -406.093163) (xy 61.248088 -406.034801)
			(xy 61.20618 -405.971626) (xy 61.171224 -405.904355) (xy 61.143617 -405.83375) (xy 61.123671 -405.760609)
			(xy 61.111612 -405.685764) (xy 61.107577 -405.61006) (xy 59.991498 -405.61006) (xy 59.990994 -405.647966)
			(xy 59.982935 -405.723347) (xy 59.96691 -405.797445) (xy 59.9431 -405.86942) (xy 59.911774 -405.938456)
			(xy 59.873287 -406.003771) (xy 59.828076 -406.064626) (xy 59.776652 -406.12033) (xy 59.719599 -406.170252)
			(xy 59.657563 -406.213827) (xy 59.591246 -406.250562) (xy 59.5214 -406.280039) (xy 59.448817 -406.301925)
			(xy 59.374319 -406.315972) (xy 59.298749 -406.322021) (xy 59.222965 -406.320002) (xy 59.147825 -406.30994)
			(xy 59.07418 -406.291948) (xy 59.002864 -406.26623) (xy 58.934687 -406.233078) (xy 58.870419 -406.192866)
			(xy 58.81079 -406.146051) (xy 58.756474 -406.093163) (xy 58.708088 -406.034801) (xy 58.66618 -405.971626)
			(xy 58.631224 -405.904355) (xy 58.603617 -405.83375) (xy 58.583671 -405.760609) (xy 58.571612 -405.685764)
			(xy 58.567577 -405.61006) (xy 57.451498 -405.61006) (xy 57.450994 -405.647966) (xy 57.442935 -405.723347)
			(xy 57.42691 -405.797445) (xy 57.4031 -405.86942) (xy 57.371774 -405.938456) (xy 57.333287 -406.003771)
			(xy 57.288076 -406.064626) (xy 57.236652 -406.12033) (xy 57.179599 -406.170252) (xy 57.117563 -406.213827)
			(xy 57.051246 -406.250562) (xy 56.9814 -406.280039) (xy 56.908817 -406.301925) (xy 56.834319 -406.315972)
			(xy 56.758749 -406.322021) (xy 56.682965 -406.320002) (xy 56.607825 -406.30994) (xy 56.53418 -406.291948)
			(xy 56.462864 -406.26623) (xy 56.394687 -406.233078) (xy 56.330419 -406.192866) (xy 56.27079 -406.146051)
			(xy 56.216474 -406.093163) (xy 56.168088 -406.034801) (xy 56.12618 -405.971626) (xy 56.091224 -405.904355)
			(xy 56.063617 -405.83375) (xy 56.043671 -405.760609) (xy 56.031612 -405.685764) (xy 56.027577 -405.61006)
			(xy 54.911498 -405.61006) (xy 54.910994 -405.647966) (xy 54.902935 -405.723347) (xy 54.88691 -405.797445)
			(xy 54.8631 -405.86942) (xy 54.831774 -405.938456) (xy 54.793287 -406.003771) (xy 54.748076 -406.064626)
			(xy 54.696652 -406.12033) (xy 54.639599 -406.170252) (xy 54.577563 -406.213827) (xy 54.511246 -406.250562)
			(xy 54.4414 -406.280039) (xy 54.368817 -406.301925) (xy 54.294319 -406.315972) (xy 54.218749 -406.322021)
			(xy 54.142965 -406.320002) (xy 54.067825 -406.30994) (xy 53.99418 -406.291948) (xy 53.922864 -406.26623)
			(xy 53.854687 -406.233078) (xy 53.790419 -406.192866) (xy 53.73079 -406.146051) (xy 53.676474 -406.093163)
			(xy 53.628088 -406.034801) (xy 53.58618 -405.971626) (xy 53.551224 -405.904355) (xy 53.523617 -405.83375)
			(xy 53.503671 -405.760609) (xy 53.491612 -405.685764) (xy 53.487577 -405.61006) (xy 52.371498 -405.61006)
			(xy 52.370994 -405.647966) (xy 52.362935 -405.723347) (xy 52.34691 -405.797445) (xy 52.3231 -405.86942)
			(xy 52.291774 -405.938456) (xy 52.253287 -406.003771) (xy 52.208076 -406.064626) (xy 52.156652 -406.12033)
			(xy 52.099599 -406.170252) (xy 52.037563 -406.213827) (xy 51.971246 -406.250562) (xy 51.9014 -406.280039)
			(xy 51.828817 -406.301925) (xy 51.754319 -406.315972) (xy 51.678749 -406.322021) (xy 51.602965 -406.320002)
			(xy 51.527825 -406.30994) (xy 51.45418 -406.291948) (xy 51.382864 -406.26623) (xy 51.314687 -406.233078)
			(xy 51.250419 -406.192866) (xy 51.19079 -406.146051) (xy 51.136474 -406.093163) (xy 51.088088 -406.034801)
			(xy 51.04618 -405.971626) (xy 51.011224 -405.904355) (xy 50.983617 -405.83375) (xy 50.963671 -405.760609)
			(xy 50.951612 -405.685764) (xy 50.947577 -405.61006) (xy 49.831498 -405.61006) (xy 49.830994 -405.647966)
			(xy 49.822935 -405.723347) (xy 49.80691 -405.797445) (xy 49.7831 -405.86942) (xy 49.751774 -405.938456)
			(xy 49.713287 -406.003771) (xy 49.668076 -406.064626) (xy 49.616652 -406.12033) (xy 49.559599 -406.170252)
			(xy 49.497563 -406.213827) (xy 49.431246 -406.250562) (xy 49.3614 -406.280039) (xy 49.288817 -406.301925)
			(xy 49.214319 -406.315972) (xy 49.138749 -406.322021) (xy 49.062965 -406.320002) (xy 48.987825 -406.30994)
			(xy 48.91418 -406.291948) (xy 48.842864 -406.26623) (xy 48.774687 -406.233078) (xy 48.710419 -406.192866)
			(xy 48.65079 -406.146051) (xy 48.596474 -406.093163) (xy 48.548088 -406.034801) (xy 48.50618 -405.971626)
			(xy 48.471224 -405.904355) (xy 48.443617 -405.83375) (xy 48.423671 -405.760609) (xy 48.411612 -405.685764)
			(xy 48.407577 -405.61006) (xy 47.291498 -405.61006) (xy 47.290994 -405.647966) (xy 47.282935 -405.723347)
			(xy 47.26691 -405.797445) (xy 47.2431 -405.86942) (xy 47.211774 -405.938456) (xy 47.173287 -406.003771)
			(xy 47.128076 -406.064626) (xy 47.076652 -406.12033) (xy 47.019599 -406.170252) (xy 46.957563 -406.213827)
			(xy 46.891246 -406.250562) (xy 46.8214 -406.280039) (xy 46.748817 -406.301925) (xy 46.674319 -406.315972)
			(xy 46.598749 -406.322021) (xy 46.522965 -406.320002) (xy 46.447825 -406.30994) (xy 46.37418 -406.291948)
			(xy 46.302864 -406.26623) (xy 46.234687 -406.233078) (xy 46.170419 -406.192866) (xy 46.11079 -406.146051)
			(xy 46.056474 -406.093163) (xy 46.008088 -406.034801) (xy 45.96618 -405.971626) (xy 45.931224 -405.904355)
			(xy 45.903617 -405.83375) (xy 45.883671 -405.760609) (xy 45.871612 -405.685764) (xy 45.867577 -405.61006)
			(xy 44.751498 -405.61006) (xy 44.750994 -405.647966) (xy 44.742935 -405.723347) (xy 44.72691 -405.797445)
			(xy 44.7031 -405.86942) (xy 44.671774 -405.938456) (xy 44.633287 -406.003771) (xy 44.588076 -406.064626)
			(xy 44.536652 -406.12033) (xy 44.479599 -406.170252) (xy 44.417563 -406.213827) (xy 44.351246 -406.250562)
			(xy 44.2814 -406.280039) (xy 44.208817 -406.301925) (xy 44.134319 -406.315972) (xy 44.058749 -406.322021)
			(xy 43.982965 -406.320002) (xy 43.907825 -406.30994) (xy 43.83418 -406.291948) (xy 43.762864 -406.26623)
			(xy 43.694687 -406.233078) (xy 43.630419 -406.192866) (xy 43.57079 -406.146051) (xy 43.516474 -406.093163)
			(xy 43.468088 -406.034801) (xy 43.42618 -405.971626) (xy 43.391224 -405.904355) (xy 43.363617 -405.83375)
			(xy 43.343671 -405.760609) (xy 43.331612 -405.685764) (xy 43.327577 -405.61006) (xy 42.501239 -405.61006)
			(xy 42.515699 -405.620266) (xy 42.604766 -405.692723) (xy 42.688681 -405.771089) (xy 42.767054 -405.854998)
			(xy 42.839517 -405.94406) (xy 42.905734 -406.037859) (xy 42.965396 -406.135958) (xy 43.018225 -406.2379)
			(xy 43.056094 -406.32507) (xy 84.927697 -406.32507) (xy 84.931732 -406.249366) (xy 84.943791 -406.174521)
			(xy 84.963737 -406.10138) (xy 84.991344 -406.030775) (xy 85.0263 -405.963504) (xy 85.068208 -405.900329)
			(xy 85.116594 -405.841967) (xy 85.17091 -405.789079) (xy 85.230539 -405.742264) (xy 85.294807 -405.702052)
			(xy 85.362984 -405.6689) (xy 85.4343 -405.643182) (xy 85.507945 -405.62519) (xy 85.583085 -405.615128)
			(xy 85.658869 -405.613109) (xy 85.734439 -405.619158) (xy 85.808937 -405.633205) (xy 85.88152 -405.655091)
			(xy 85.951366 -405.684568) (xy 86.017683 -405.721303) (xy 86.079719 -405.764878) (xy 86.136772 -405.8148)
			(xy 86.188196 -405.870504) (xy 86.233407 -405.931359) (xy 86.271894 -405.996674) (xy 86.30322 -406.06571)
			(xy 86.32703 -406.137685) (xy 86.343055 -406.211783) (xy 86.351114 -406.287164) (xy 86.351618 -406.32507)
			(xy 87.467697 -406.32507) (xy 87.471732 -406.249366) (xy 87.483791 -406.174521) (xy 87.503737 -406.10138)
			(xy 87.531344 -406.030775) (xy 87.5663 -405.963504) (xy 87.608208 -405.900329) (xy 87.656594 -405.841967)
			(xy 87.71091 -405.789079) (xy 87.770539 -405.742264) (xy 87.834807 -405.702052) (xy 87.902984 -405.6689)
			(xy 87.9743 -405.643182) (xy 88.047945 -405.62519) (xy 88.123085 -405.615128) (xy 88.198869 -405.613109)
			(xy 88.274439 -405.619158) (xy 88.348937 -405.633205) (xy 88.42152 -405.655091) (xy 88.491366 -405.684568)
			(xy 88.557683 -405.721303) (xy 88.619719 -405.764878) (xy 88.676772 -405.8148) (xy 88.728196 -405.870504)
			(xy 88.773407 -405.931359) (xy 88.811894 -405.996674) (xy 88.84322 -406.06571) (xy 88.86703 -406.137685)
			(xy 88.883055 -406.211783) (xy 88.891114 -406.287164) (xy 88.891618 -406.32507) (xy 90.007697 -406.32507)
			(xy 90.011732 -406.249366) (xy 90.023791 -406.174521) (xy 90.043737 -406.10138) (xy 90.071344 -406.030775)
			(xy 90.1063 -405.963504) (xy 90.148208 -405.900329) (xy 90.196594 -405.841967) (xy 90.25091 -405.789079)
			(xy 90.310539 -405.742264) (xy 90.374807 -405.702052) (xy 90.442984 -405.6689) (xy 90.5143 -405.643182)
			(xy 90.587945 -405.62519) (xy 90.663085 -405.615128) (xy 90.738869 -405.613109) (xy 90.814439 -405.619158)
			(xy 90.888937 -405.633205) (xy 90.96152 -405.655091) (xy 91.031366 -405.684568) (xy 91.097683 -405.721303)
			(xy 91.159719 -405.764878) (xy 91.216772 -405.8148) (xy 91.268196 -405.870504) (xy 91.313407 -405.931359)
			(xy 91.351894 -405.996674) (xy 91.38322 -406.06571) (xy 91.40703 -406.137685) (xy 91.423055 -406.211783)
			(xy 91.431114 -406.287164) (xy 91.431618 -406.32507) (xy 91.431114 -406.362976) (xy 91.423055 -406.438357)
			(xy 91.40703 -406.512455) (xy 91.38322 -406.58443) (xy 91.351894 -406.653466) (xy 91.313407 -406.718781)
			(xy 91.268196 -406.779636) (xy 91.216772 -406.83534) (xy 91.159719 -406.885262) (xy 91.097683 -406.928837)
			(xy 91.031366 -406.965572) (xy 90.96152 -406.995049) (xy 90.888937 -407.016935) (xy 90.814439 -407.030982)
			(xy 90.738869 -407.037031) (xy 90.663085 -407.035012) (xy 90.587945 -407.02495) (xy 90.5143 -407.006958)
			(xy 90.442984 -406.98124) (xy 90.374807 -406.948088) (xy 90.310539 -406.907876) (xy 90.25091 -406.861061)
			(xy 90.196594 -406.808173) (xy 90.148208 -406.749811) (xy 90.1063 -406.686636) (xy 90.071344 -406.619365)
			(xy 90.043737 -406.54876) (xy 90.023791 -406.475619) (xy 90.011732 -406.400774) (xy 90.007697 -406.32507)
			(xy 88.891618 -406.32507) (xy 88.891114 -406.362976) (xy 88.883055 -406.438357) (xy 88.86703 -406.512455)
			(xy 88.84322 -406.58443) (xy 88.811894 -406.653466) (xy 88.773407 -406.718781) (xy 88.728196 -406.779636)
			(xy 88.676772 -406.83534) (xy 88.619719 -406.885262) (xy 88.557683 -406.928837) (xy 88.491366 -406.965572)
			(xy 88.42152 -406.995049) (xy 88.348937 -407.016935) (xy 88.274439 -407.030982) (xy 88.198869 -407.037031)
			(xy 88.123085 -407.035012) (xy 88.047945 -407.02495) (xy 87.9743 -407.006958) (xy 87.902984 -406.98124)
			(xy 87.834807 -406.948088) (xy 87.770539 -406.907876) (xy 87.71091 -406.861061) (xy 87.656594 -406.808173)
			(xy 87.608208 -406.749811) (xy 87.5663 -406.686636) (xy 87.531344 -406.619365) (xy 87.503737 -406.54876)
			(xy 87.483791 -406.475619) (xy 87.471732 -406.400774) (xy 87.467697 -406.32507) (xy 86.351618 -406.32507)
			(xy 86.351114 -406.362976) (xy 86.343055 -406.438357) (xy 86.32703 -406.512455) (xy 86.30322 -406.58443)
			(xy 86.271894 -406.653466) (xy 86.233407 -406.718781) (xy 86.188196 -406.779636) (xy 86.136772 -406.83534)
			(xy 86.079719 -406.885262) (xy 86.017683 -406.928837) (xy 85.951366 -406.965572) (xy 85.88152 -406.995049)
			(xy 85.808937 -407.016935) (xy 85.734439 -407.030982) (xy 85.658869 -407.037031) (xy 85.583085 -407.035012)
			(xy 85.507945 -407.02495) (xy 85.4343 -407.006958) (xy 85.362984 -406.98124) (xy 85.294807 -406.948088)
			(xy 85.230539 -406.907876) (xy 85.17091 -406.861061) (xy 85.116594 -406.808173) (xy 85.068208 -406.749811)
			(xy 85.0263 -406.686636) (xy 84.991344 -406.619365) (xy 84.963737 -406.54876) (xy 84.943791 -406.475619)
			(xy 84.931732 -406.400774) (xy 84.927697 -406.32507) (xy 43.056094 -406.32507) (xy 43.063974 -406.343209)
			(xy 43.10243 -406.451394) (xy 43.133415 -406.561952) (xy 43.156782 -406.674366) (xy 43.172424 -406.788113)
			(xy 43.180268 -406.902661) (xy 43.180762 -406.96007) (xy 43.180576 -406.993253) (xy 43.177909 -407.059567)
			(xy 43.175428 -407.092658) (xy 43.170272 -407.150942) (xy 43.152948 -407.266671) (xy 43.127616 -407.380914)
			(xy 43.094401 -407.493119) (xy 43.056327 -407.59507) (xy 86.197697 -407.59507) (xy 86.201732 -407.519366)
			(xy 86.213791 -407.444521) (xy 86.233737 -407.37138) (xy 86.261344 -407.300775) (xy 86.2963 -407.233504)
			(xy 86.338208 -407.170329) (xy 86.386594 -407.111967) (xy 86.44091 -407.059079) (xy 86.500539 -407.012264)
			(xy 86.564807 -406.972052) (xy 86.632984 -406.9389) (xy 86.7043 -406.913182) (xy 86.777945 -406.89519)
			(xy 86.853085 -406.885128) (xy 86.928869 -406.883109) (xy 87.004439 -406.889158) (xy 87.078937 -406.903205)
			(xy 87.15152 -406.925091) (xy 87.221366 -406.954568) (xy 87.287683 -406.991303) (xy 87.349719 -407.034878)
			(xy 87.406772 -407.0848) (xy 87.458196 -407.140504) (xy 87.503407 -407.201359) (xy 87.541894 -407.266674)
			(xy 87.57322 -407.33571) (xy 87.59703 -407.407685) (xy 87.613055 -407.481783) (xy 87.621114 -407.557164)
			(xy 87.621618 -407.59507) (xy 88.737697 -407.59507) (xy 88.741732 -407.519366) (xy 88.753791 -407.444521)
			(xy 88.773737 -407.37138) (xy 88.801344 -407.300775) (xy 88.8363 -407.233504) (xy 88.878208 -407.170329)
			(xy 88.926594 -407.111967) (xy 88.98091 -407.059079) (xy 89.040539 -407.012264) (xy 89.104807 -406.972052)
			(xy 89.172984 -406.9389) (xy 89.2443 -406.913182) (xy 89.317945 -406.89519) (xy 89.393085 -406.885128)
			(xy 89.468869 -406.883109) (xy 89.544439 -406.889158) (xy 89.618937 -406.903205) (xy 89.69152 -406.925091)
			(xy 89.761366 -406.954568) (xy 89.827683 -406.991303) (xy 89.889719 -407.034878) (xy 89.946772 -407.0848)
			(xy 89.998196 -407.140504) (xy 90.043407 -407.201359) (xy 90.081894 -407.266674) (xy 90.11322 -407.33571)
			(xy 90.13703 -407.407685) (xy 90.153055 -407.481783) (xy 90.161114 -407.557164) (xy 90.161618 -407.59507)
			(xy 91.277697 -407.59507) (xy 91.281732 -407.519366) (xy 91.293791 -407.444521) (xy 91.313737 -407.37138)
			(xy 91.341344 -407.300775) (xy 91.3763 -407.233504) (xy 91.418208 -407.170329) (xy 91.466594 -407.111967)
			(xy 91.52091 -407.059079) (xy 91.580539 -407.012264) (xy 91.644807 -406.972052) (xy 91.712984 -406.9389)
			(xy 91.7843 -406.913182) (xy 91.857945 -406.89519) (xy 91.933085 -406.885128) (xy 92.008869 -406.883109)
			(xy 92.084439 -406.889158) (xy 92.158937 -406.903205) (xy 92.23152 -406.925091) (xy 92.301366 -406.954568)
			(xy 92.367683 -406.991303) (xy 92.429719 -407.034878) (xy 92.486772 -407.0848) (xy 92.538196 -407.140504)
			(xy 92.583407 -407.201359) (xy 92.621894 -407.266674) (xy 92.65322 -407.33571) (xy 92.67703 -407.407685)
			(xy 92.693055 -407.481783) (xy 92.701114 -407.557164) (xy 92.701618 -407.59507) (xy 92.701114 -407.632976)
			(xy 92.693055 -407.708357) (xy 92.67703 -407.782455) (xy 92.65322 -407.85443) (xy 92.621894 -407.923466)
			(xy 92.583407 -407.988781) (xy 92.538196 -408.049636) (xy 92.486772 -408.10534) (xy 92.429719 -408.155262)
			(xy 92.367683 -408.198837) (xy 92.301366 -408.235572) (xy 92.23152 -408.265049) (xy 92.158937 -408.286935)
			(xy 92.084439 -408.300982) (xy 92.008869 -408.307031) (xy 91.933085 -408.305012) (xy 91.857945 -408.29495)
			(xy 91.7843 -408.276958) (xy 91.712984 -408.25124) (xy 91.644807 -408.218088) (xy 91.580539 -408.177876)
			(xy 91.52091 -408.131061) (xy 91.466594 -408.078173) (xy 91.418208 -408.019811) (xy 91.3763 -407.956636)
			(xy 91.341344 -407.889365) (xy 91.313737 -407.81876) (xy 91.293791 -407.745619) (xy 91.281732 -407.670774)
			(xy 91.277697 -407.59507) (xy 90.161618 -407.59507) (xy 90.161114 -407.632976) (xy 90.153055 -407.708357)
			(xy 90.13703 -407.782455) (xy 90.11322 -407.85443) (xy 90.081894 -407.923466) (xy 90.043407 -407.988781)
			(xy 89.998196 -408.049636) (xy 89.946772 -408.10534) (xy 89.889719 -408.155262) (xy 89.827683 -408.198837)
			(xy 89.761366 -408.235572) (xy 89.69152 -408.265049) (xy 89.618937 -408.286935) (xy 89.544439 -408.300982)
			(xy 89.468869 -408.307031) (xy 89.393085 -408.305012) (xy 89.317945 -408.29495) (xy 89.2443 -408.276958)
			(xy 89.172984 -408.25124) (xy 89.104807 -408.218088) (xy 89.040539 -408.177876) (xy 88.98091 -408.131061)
			(xy 88.926594 -408.078173) (xy 88.878208 -408.019811) (xy 88.8363 -407.956636) (xy 88.801344 -407.889365)
			(xy 88.773737 -407.81876) (xy 88.753791 -407.745619) (xy 88.741732 -407.670774) (xy 88.737697 -407.59507)
			(xy 87.621618 -407.59507) (xy 87.621114 -407.632976) (xy 87.613055 -407.708357) (xy 87.59703 -407.782455)
			(xy 87.57322 -407.85443) (xy 87.541894 -407.923466) (xy 87.503407 -407.988781) (xy 87.458196 -408.049636)
			(xy 87.406772 -408.10534) (xy 87.349719 -408.155262) (xy 87.287683 -408.198837) (xy 87.221366 -408.235572)
			(xy 87.15152 -408.265049) (xy 87.078937 -408.286935) (xy 87.004439 -408.300982) (xy 86.928869 -408.307031)
			(xy 86.853085 -408.305012) (xy 86.777945 -408.29495) (xy 86.7043 -408.276958) (xy 86.632984 -408.25124)
			(xy 86.564807 -408.218088) (xy 86.500539 -408.177876) (xy 86.44091 -408.131061) (xy 86.386594 -408.078173)
			(xy 86.338208 -408.019811) (xy 86.2963 -407.956636) (xy 86.261344 -407.889365) (xy 86.233737 -407.81876)
			(xy 86.213791 -407.745619) (xy 86.201732 -407.670774) (xy 86.197697 -407.59507) (xy 43.056327 -407.59507)
			(xy 43.055094 -407.598372) (xy 43.328336 -407.598372) (xy 44.751244 -407.598372) (xy 44.751244 -408.31008)
			(xy 45.867577 -408.31008) (xy 45.871612 -408.234376) (xy 45.883671 -408.159531) (xy 45.903617 -408.08639)
			(xy 45.931224 -408.015785) (xy 45.96618 -407.948514) (xy 46.008088 -407.885339) (xy 46.056474 -407.826977)
			(xy 46.11079 -407.774089) (xy 46.170419 -407.727274) (xy 46.234687 -407.687062) (xy 46.302864 -407.65391)
			(xy 46.37418 -407.628192) (xy 46.447825 -407.6102) (xy 46.522965 -407.600138) (xy 46.598749 -407.598119)
			(xy 46.674319 -407.604168) (xy 46.748817 -407.618215) (xy 46.8214 -407.640101) (xy 46.891246 -407.669578)
			(xy 46.957563 -407.706313) (xy 47.019599 -407.749888) (xy 47.076652 -407.79981) (xy 47.128076 -407.855514)
			(xy 47.173287 -407.916369) (xy 47.211774 -407.981684) (xy 47.2431 -408.05072) (xy 47.26691 -408.122695)
			(xy 47.282935 -408.196793) (xy 47.290994 -408.272174) (xy 47.291498 -408.31008) (xy 48.407577 -408.31008)
			(xy 48.411612 -408.234376) (xy 48.423671 -408.159531) (xy 48.443617 -408.08639) (xy 48.471224 -408.015785)
			(xy 48.50618 -407.948514) (xy 48.548088 -407.885339) (xy 48.596474 -407.826977) (xy 48.65079 -407.774089)
			(xy 48.710419 -407.727274) (xy 48.774687 -407.687062) (xy 48.842864 -407.65391) (xy 48.91418 -407.628192)
			(xy 48.987825 -407.6102) (xy 49.062965 -407.600138) (xy 49.138749 -407.598119) (xy 49.214319 -407.604168)
			(xy 49.288817 -407.618215) (xy 49.3614 -407.640101) (xy 49.431246 -407.669578) (xy 49.497563 -407.706313)
			(xy 49.559599 -407.749888) (xy 49.616652 -407.79981) (xy 49.668076 -407.855514) (xy 49.713287 -407.916369)
			(xy 49.751774 -407.981684) (xy 49.7831 -408.05072) (xy 49.80691 -408.122695) (xy 49.822935 -408.196793)
			(xy 49.830994 -408.272174) (xy 49.831498 -408.31008) (xy 50.947577 -408.31008) (xy 50.951612 -408.234376)
			(xy 50.963671 -408.159531) (xy 50.983617 -408.08639) (xy 51.011224 -408.015785) (xy 51.04618 -407.948514)
			(xy 51.088088 -407.885339) (xy 51.136474 -407.826977) (xy 51.19079 -407.774089) (xy 51.250419 -407.727274)
			(xy 51.314687 -407.687062) (xy 51.382864 -407.65391) (xy 51.45418 -407.628192) (xy 51.527825 -407.6102)
			(xy 51.602965 -407.600138) (xy 51.678749 -407.598119) (xy 51.754319 -407.604168) (xy 51.828817 -407.618215)
			(xy 51.9014 -407.640101) (xy 51.971246 -407.669578) (xy 52.037563 -407.706313) (xy 52.099599 -407.749888)
			(xy 52.156652 -407.79981) (xy 52.208076 -407.855514) (xy 52.253287 -407.916369) (xy 52.291774 -407.981684)
			(xy 52.3231 -408.05072) (xy 52.34691 -408.122695) (xy 52.362935 -408.196793) (xy 52.370994 -408.272174)
			(xy 52.371498 -408.31008) (xy 53.487577 -408.31008) (xy 53.491612 -408.234376) (xy 53.503671 -408.159531)
			(xy 53.523617 -408.08639) (xy 53.551224 -408.015785) (xy 53.58618 -407.948514) (xy 53.628088 -407.885339)
			(xy 53.676474 -407.826977) (xy 53.73079 -407.774089) (xy 53.790419 -407.727274) (xy 53.854687 -407.687062)
			(xy 53.922864 -407.65391) (xy 53.99418 -407.628192) (xy 54.067825 -407.6102) (xy 54.142965 -407.600138)
			(xy 54.218749 -407.598119) (xy 54.294319 -407.604168) (xy 54.368817 -407.618215) (xy 54.4414 -407.640101)
			(xy 54.511246 -407.669578) (xy 54.577563 -407.706313) (xy 54.639599 -407.749888) (xy 54.696652 -407.79981)
			(xy 54.748076 -407.855514) (xy 54.793287 -407.916369) (xy 54.831774 -407.981684) (xy 54.8631 -408.05072)
			(xy 54.88691 -408.122695) (xy 54.902935 -408.196793) (xy 54.910994 -408.272174) (xy 54.911498 -408.31008)
			(xy 56.027577 -408.31008) (xy 56.031612 -408.234376) (xy 56.043671 -408.159531) (xy 56.063617 -408.08639)
			(xy 56.091224 -408.015785) (xy 56.12618 -407.948514) (xy 56.168088 -407.885339) (xy 56.216474 -407.826977)
			(xy 56.27079 -407.774089) (xy 56.330419 -407.727274) (xy 56.394687 -407.687062) (xy 56.462864 -407.65391)
			(xy 56.53418 -407.628192) (xy 56.607825 -407.6102) (xy 56.682965 -407.600138) (xy 56.758749 -407.598119)
			(xy 56.834319 -407.604168) (xy 56.908817 -407.618215) (xy 56.9814 -407.640101) (xy 57.051246 -407.669578)
			(xy 57.117563 -407.706313) (xy 57.179599 -407.749888) (xy 57.236652 -407.79981) (xy 57.288076 -407.855514)
			(xy 57.333287 -407.916369) (xy 57.371774 -407.981684) (xy 57.4031 -408.05072) (xy 57.42691 -408.122695)
			(xy 57.442935 -408.196793) (xy 57.450994 -408.272174) (xy 57.451498 -408.31008) (xy 58.567577 -408.31008)
			(xy 58.571612 -408.234376) (xy 58.583671 -408.159531) (xy 58.603617 -408.08639) (xy 58.631224 -408.015785)
			(xy 58.66618 -407.948514) (xy 58.708088 -407.885339) (xy 58.756474 -407.826977) (xy 58.81079 -407.774089)
			(xy 58.870419 -407.727274) (xy 58.934687 -407.687062) (xy 59.002864 -407.65391) (xy 59.07418 -407.628192)
			(xy 59.147825 -407.6102) (xy 59.222965 -407.600138) (xy 59.298749 -407.598119) (xy 59.374319 -407.604168)
			(xy 59.448817 -407.618215) (xy 59.5214 -407.640101) (xy 59.591246 -407.669578) (xy 59.657563 -407.706313)
			(xy 59.719599 -407.749888) (xy 59.776652 -407.79981) (xy 59.828076 -407.855514) (xy 59.873287 -407.916369)
			(xy 59.911774 -407.981684) (xy 59.9431 -408.05072) (xy 59.96691 -408.122695) (xy 59.982935 -408.196793)
			(xy 59.990994 -408.272174) (xy 59.991498 -408.31008) (xy 61.107577 -408.31008) (xy 61.111612 -408.234376)
			(xy 61.123671 -408.159531) (xy 61.143617 -408.08639) (xy 61.171224 -408.015785) (xy 61.20618 -407.948514)
			(xy 61.248088 -407.885339) (xy 61.296474 -407.826977) (xy 61.35079 -407.774089) (xy 61.410419 -407.727274)
			(xy 61.474687 -407.687062) (xy 61.542864 -407.65391) (xy 61.61418 -407.628192) (xy 61.687825 -407.6102)
			(xy 61.762965 -407.600138) (xy 61.838749 -407.598119) (xy 61.914319 -407.604168) (xy 61.988817 -407.618215)
			(xy 62.0614 -407.640101) (xy 62.131246 -407.669578) (xy 62.197563 -407.706313) (xy 62.259599 -407.749888)
			(xy 62.316652 -407.79981) (xy 62.368076 -407.855514) (xy 62.413287 -407.916369) (xy 62.451774 -407.981684)
			(xy 62.4831 -408.05072) (xy 62.50691 -408.122695) (xy 62.522935 -408.196793) (xy 62.530994 -408.272174)
			(xy 62.531498 -408.31008) (xy 62.530994 -408.347986) (xy 62.522935 -408.423367) (xy 62.50691 -408.497465)
			(xy 62.4831 -408.56944) (xy 62.451774 -408.638476) (xy 62.413287 -408.703791) (xy 62.368076 -408.764646)
			(xy 62.316652 -408.82035) (xy 62.265544 -408.86507) (xy 84.927697 -408.86507) (xy 84.931732 -408.789366)
			(xy 84.943791 -408.714521) (xy 84.963737 -408.64138) (xy 84.991344 -408.570775) (xy 85.0263 -408.503504)
			(xy 85.068208 -408.440329) (xy 85.116594 -408.381967) (xy 85.17091 -408.329079) (xy 85.230539 -408.282264)
			(xy 85.294807 -408.242052) (xy 85.362984 -408.2089) (xy 85.4343 -408.183182) (xy 85.507945 -408.16519)
			(xy 85.583085 -408.155128) (xy 85.658869 -408.153109) (xy 85.734439 -408.159158) (xy 85.808937 -408.173205)
			(xy 85.88152 -408.195091) (xy 85.951366 -408.224568) (xy 86.017683 -408.261303) (xy 86.079719 -408.304878)
			(xy 86.136772 -408.3548) (xy 86.188196 -408.410504) (xy 86.233407 -408.471359) (xy 86.271894 -408.536674)
			(xy 86.30322 -408.60571) (xy 86.32703 -408.677685) (xy 86.343055 -408.751783) (xy 86.351114 -408.827164)
			(xy 86.351618 -408.86507) (xy 87.467697 -408.86507) (xy 87.471732 -408.789366) (xy 87.483791 -408.714521)
			(xy 87.503737 -408.64138) (xy 87.531344 -408.570775) (xy 87.5663 -408.503504) (xy 87.608208 -408.440329)
			(xy 87.656594 -408.381967) (xy 87.71091 -408.329079) (xy 87.770539 -408.282264) (xy 87.834807 -408.242052)
			(xy 87.902984 -408.2089) (xy 87.9743 -408.183182) (xy 88.047945 -408.16519) (xy 88.123085 -408.155128)
			(xy 88.198869 -408.153109) (xy 88.274439 -408.159158) (xy 88.348937 -408.173205) (xy 88.42152 -408.195091)
			(xy 88.491366 -408.224568) (xy 88.557683 -408.261303) (xy 88.619719 -408.304878) (xy 88.676772 -408.3548)
			(xy 88.728196 -408.410504) (xy 88.773407 -408.471359) (xy 88.811894 -408.536674) (xy 88.84322 -408.60571)
			(xy 88.86703 -408.677685) (xy 88.883055 -408.751783) (xy 88.891114 -408.827164) (xy 88.891618 -408.86507)
			(xy 90.007697 -408.86507) (xy 90.011732 -408.789366) (xy 90.023791 -408.714521) (xy 90.043737 -408.64138)
			(xy 90.071344 -408.570775) (xy 90.1063 -408.503504) (xy 90.148208 -408.440329) (xy 90.196594 -408.381967)
			(xy 90.25091 -408.329079) (xy 90.310539 -408.282264) (xy 90.374807 -408.242052) (xy 90.442984 -408.2089)
			(xy 90.5143 -408.183182) (xy 90.587945 -408.16519) (xy 90.663085 -408.155128) (xy 90.738869 -408.153109)
			(xy 90.814439 -408.159158) (xy 90.888937 -408.173205) (xy 90.96152 -408.195091) (xy 91.031366 -408.224568)
			(xy 91.097683 -408.261303) (xy 91.159719 -408.304878) (xy 91.165664 -408.31008) (xy 93.154506 -408.31008)
			(xy 93.158522 -408.19381) (xy 93.170549 -408.078095) (xy 93.190531 -407.963485) (xy 93.218373 -407.850526)
			(xy 93.253942 -407.739758) (xy 93.297068 -407.631707) (xy 93.347545 -407.526889) (xy 93.405134 -407.425804)
			(xy 93.46956 -407.328932) (xy 93.540515 -407.236736) (xy 93.617662 -407.149655) (xy 93.700633 -407.068104)
			(xy 93.789033 -406.992472) (xy 93.88244 -406.923118) (xy 93.980409 -406.860375) (xy 94.082473 -406.804539)
			(xy 94.188147 -406.755878) (xy 94.296926 -406.714624) (xy 94.408291 -406.680973) (xy 94.521714 -406.655085)
			(xy 94.636651 -406.637084) (xy 94.752557 -406.627055) (xy 94.868879 -406.625047) (xy 94.985062 -406.631069)
			(xy 95.100553 -406.645092) (xy 95.214801 -406.66705) (xy 95.327262 -406.696837) (xy 95.4374 -406.734312)
			(xy 95.54469 -406.779297) (xy 95.648621 -406.831576) (xy 95.748697 -406.890901) (xy 95.844443 -406.956989)
			(xy 95.9354 -407.029525) (xy 96.021136 -407.108164) (xy 96.101243 -407.19253) (xy 96.175339 -407.282222)
			(xy 96.243069 -407.376812) (xy 96.304113 -407.47585) (xy 96.358178 -407.578863) (xy 96.405008 -407.68536)
			(xy 96.444379 -407.794835) (xy 96.476103 -407.906765) (xy 96.500029 -408.020617) (xy 96.516043 -408.135849)
			(xy 96.52407 -408.251911) (xy 96.524572 -408.31008) (xy 96.52407 -408.368249) (xy 96.516043 -408.484311)
			(xy 96.500029 -408.599543) (xy 96.476103 -408.713395) (xy 96.444379 -408.825325) (xy 96.405008 -408.9348)
			(xy 96.358178 -409.041297) (xy 96.304113 -409.14431) (xy 96.243069 -409.243348) (xy 96.175339 -409.337938)
			(xy 96.101243 -409.42763) (xy 96.021136 -409.511996) (xy 95.9354 -409.590635) (xy 95.844443 -409.663171)
			(xy 95.748697 -409.729259) (xy 95.648621 -409.788584) (xy 95.54469 -409.840863) (xy 95.4374 -409.885848)
			(xy 95.327262 -409.923323) (xy 95.214801 -409.95311) (xy 95.100553 -409.975068) (xy 94.985062 -409.989091)
			(xy 94.868879 -409.995113) (xy 94.752557 -409.993105) (xy 94.636651 -409.983076) (xy 94.521714 -409.965075)
			(xy 94.408291 -409.939187) (xy 94.296926 -409.905536) (xy 94.188147 -409.864282) (xy 94.082473 -409.815621)
			(xy 93.980409 -409.759785) (xy 93.88244 -409.697042) (xy 93.789033 -409.627688) (xy 93.700633 -409.552056)
			(xy 93.617662 -409.470505) (xy 93.540515 -409.383424) (xy 93.46956 -409.291228) (xy 93.405134 -409.194356)
			(xy 93.347545 -409.093271) (xy 93.297068 -408.988453) (xy 93.253942 -408.880402) (xy 93.218373 -408.769634)
			(xy 93.190531 -408.656675) (xy 93.170549 -408.542065) (xy 93.158522 -408.42635) (xy 93.154506 -408.31008)
			(xy 91.165664 -408.31008) (xy 91.216772 -408.3548) (xy 91.268196 -408.410504) (xy 91.313407 -408.471359)
			(xy 91.351894 -408.536674) (xy 91.38322 -408.60571) (xy 91.40703 -408.677685) (xy 91.423055 -408.751783)
			(xy 91.431114 -408.827164) (xy 91.431618 -408.86507) (xy 91.431114 -408.902976) (xy 91.423055 -408.978357)
			(xy 91.40703 -409.052455) (xy 91.38322 -409.12443) (xy 91.351894 -409.193466) (xy 91.313407 -409.258781)
			(xy 91.268196 -409.319636) (xy 91.216772 -409.37534) (xy 91.159719 -409.425262) (xy 91.097683 -409.468837)
			(xy 91.031366 -409.505572) (xy 90.96152 -409.535049) (xy 90.888937 -409.556935) (xy 90.814439 -409.570982)
			(xy 90.738869 -409.577031) (xy 90.663085 -409.575012) (xy 90.587945 -409.56495) (xy 90.5143 -409.546958)
			(xy 90.442984 -409.52124) (xy 90.374807 -409.488088) (xy 90.310539 -409.447876) (xy 90.25091 -409.401061)
			(xy 90.196594 -409.348173) (xy 90.148208 -409.289811) (xy 90.1063 -409.226636) (xy 90.071344 -409.159365)
			(xy 90.043737 -409.08876) (xy 90.023791 -409.015619) (xy 90.011732 -408.940774) (xy 90.007697 -408.86507)
			(xy 88.891618 -408.86507) (xy 88.891114 -408.902976) (xy 88.883055 -408.978357) (xy 88.86703 -409.052455)
			(xy 88.84322 -409.12443) (xy 88.811894 -409.193466) (xy 88.773407 -409.258781) (xy 88.728196 -409.319636)
			(xy 88.676772 -409.37534) (xy 88.619719 -409.425262) (xy 88.557683 -409.468837) (xy 88.491366 -409.505572)
			(xy 88.42152 -409.535049) (xy 88.348937 -409.556935) (xy 88.274439 -409.570982) (xy 88.198869 -409.577031)
			(xy 88.123085 -409.575012) (xy 88.047945 -409.56495) (xy 87.9743 -409.546958) (xy 87.902984 -409.52124)
			(xy 87.834807 -409.488088) (xy 87.770539 -409.447876) (xy 87.71091 -409.401061) (xy 87.656594 -409.348173)
			(xy 87.608208 -409.289811) (xy 87.5663 -409.226636) (xy 87.531344 -409.159365) (xy 87.503737 -409.08876)
			(xy 87.483791 -409.015619) (xy 87.471732 -408.940774) (xy 87.467697 -408.86507) (xy 86.351618 -408.86507)
			(xy 86.351114 -408.902976) (xy 86.343055 -408.978357) (xy 86.32703 -409.052455) (xy 86.30322 -409.12443)
			(xy 86.271894 -409.193466) (xy 86.233407 -409.258781) (xy 86.188196 -409.319636) (xy 86.136772 -409.37534)
			(xy 86.079719 -409.425262) (xy 86.017683 -409.468837) (xy 85.951366 -409.505572) (xy 85.88152 -409.535049)
			(xy 85.808937 -409.556935) (xy 85.734439 -409.570982) (xy 85.658869 -409.577031) (xy 85.583085 -409.575012)
			(xy 85.507945 -409.56495) (xy 85.4343 -409.546958) (xy 85.362984 -409.52124) (xy 85.294807 -409.488088)
			(xy 85.230539 -409.447876) (xy 85.17091 -409.401061) (xy 85.116594 -409.348173) (xy 85.068208 -409.289811)
			(xy 85.0263 -409.226636) (xy 84.991344 -409.159365) (xy 84.963737 -409.08876) (xy 84.943791 -409.015619)
			(xy 84.931732 -408.940774) (xy 84.927697 -408.86507) (xy 62.265544 -408.86507) (xy 62.259599 -408.870272)
			(xy 62.197563 -408.913847) (xy 62.131246 -408.950582) (xy 62.0614 -408.980059) (xy 61.988817 -409.001945)
			(xy 61.914319 -409.015992) (xy 61.838749 -409.022041) (xy 61.762965 -409.020022) (xy 61.687825 -409.00996)
			(xy 61.61418 -408.991968) (xy 61.542864 -408.96625) (xy 61.474687 -408.933098) (xy 61.410419 -408.892886)
			(xy 61.35079 -408.846071) (xy 61.296474 -408.793183) (xy 61.248088 -408.734821) (xy 61.20618 -408.671646)
			(xy 61.171224 -408.604375) (xy 61.143617 -408.53377) (xy 61.123671 -408.460629) (xy 61.111612 -408.385784)
			(xy 61.107577 -408.31008) (xy 59.991498 -408.31008) (xy 59.990994 -408.347986) (xy 59.982935 -408.423367)
			(xy 59.96691 -408.497465) (xy 59.9431 -408.56944) (xy 59.911774 -408.638476) (xy 59.873287 -408.703791)
			(xy 59.828076 -408.764646) (xy 59.776652 -408.82035) (xy 59.719599 -408.870272) (xy 59.657563 -408.913847)
			(xy 59.591246 -408.950582) (xy 59.5214 -408.980059) (xy 59.448817 -409.001945) (xy 59.374319 -409.015992)
			(xy 59.298749 -409.022041) (xy 59.222965 -409.020022) (xy 59.147825 -409.00996) (xy 59.07418 -408.991968)
			(xy 59.002864 -408.96625) (xy 58.934687 -408.933098) (xy 58.870419 -408.892886) (xy 58.81079 -408.846071)
			(xy 58.756474 -408.793183) (xy 58.708088 -408.734821) (xy 58.66618 -408.671646) (xy 58.631224 -408.604375)
			(xy 58.603617 -408.53377) (xy 58.583671 -408.460629) (xy 58.571612 -408.385784) (xy 58.567577 -408.31008)
			(xy 57.451498 -408.31008) (xy 57.450994 -408.347986) (xy 57.442935 -408.423367) (xy 57.42691 -408.497465)
			(xy 57.4031 -408.56944) (xy 57.371774 -408.638476) (xy 57.333287 -408.703791) (xy 57.288076 -408.764646)
			(xy 57.236652 -408.82035) (xy 57.179599 -408.870272) (xy 57.117563 -408.913847) (xy 57.051246 -408.950582)
			(xy 56.9814 -408.980059) (xy 56.908817 -409.001945) (xy 56.834319 -409.015992) (xy 56.758749 -409.022041)
			(xy 56.682965 -409.020022) (xy 56.607825 -409.00996) (xy 56.53418 -408.991968) (xy 56.462864 -408.96625)
			(xy 56.394687 -408.933098) (xy 56.330419 -408.892886) (xy 56.27079 -408.846071) (xy 56.216474 -408.793183)
			(xy 56.168088 -408.734821) (xy 56.12618 -408.671646) (xy 56.091224 -408.604375) (xy 56.063617 -408.53377)
			(xy 56.043671 -408.460629) (xy 56.031612 -408.385784) (xy 56.027577 -408.31008) (xy 54.911498 -408.31008)
			(xy 54.910994 -408.347986) (xy 54.902935 -408.423367) (xy 54.88691 -408.497465) (xy 54.8631 -408.56944)
			(xy 54.831774 -408.638476) (xy 54.793287 -408.703791) (xy 54.748076 -408.764646) (xy 54.696652 -408.82035)
			(xy 54.639599 -408.870272) (xy 54.577563 -408.913847) (xy 54.511246 -408.950582) (xy 54.4414 -408.980059)
			(xy 54.368817 -409.001945) (xy 54.294319 -409.015992) (xy 54.218749 -409.022041) (xy 54.142965 -409.020022)
			(xy 54.067825 -409.00996) (xy 53.99418 -408.991968) (xy 53.922864 -408.96625) (xy 53.854687 -408.933098)
			(xy 53.790419 -408.892886) (xy 53.73079 -408.846071) (xy 53.676474 -408.793183) (xy 53.628088 -408.734821)
			(xy 53.58618 -408.671646) (xy 53.551224 -408.604375) (xy 53.523617 -408.53377) (xy 53.503671 -408.460629)
			(xy 53.491612 -408.385784) (xy 53.487577 -408.31008) (xy 52.371498 -408.31008) (xy 52.370994 -408.347986)
			(xy 52.362935 -408.423367) (xy 52.34691 -408.497465) (xy 52.3231 -408.56944) (xy 52.291774 -408.638476)
			(xy 52.253287 -408.703791) (xy 52.208076 -408.764646) (xy 52.156652 -408.82035) (xy 52.099599 -408.870272)
			(xy 52.037563 -408.913847) (xy 51.971246 -408.950582) (xy 51.9014 -408.980059) (xy 51.828817 -409.001945)
			(xy 51.754319 -409.015992) (xy 51.678749 -409.022041) (xy 51.602965 -409.020022) (xy 51.527825 -409.00996)
			(xy 51.45418 -408.991968) (xy 51.382864 -408.96625) (xy 51.314687 -408.933098) (xy 51.250419 -408.892886)
			(xy 51.19079 -408.846071) (xy 51.136474 -408.793183) (xy 51.088088 -408.734821) (xy 51.04618 -408.671646)
			(xy 51.011224 -408.604375) (xy 50.983617 -408.53377) (xy 50.963671 -408.460629) (xy 50.951612 -408.385784)
			(xy 50.947577 -408.31008) (xy 49.831498 -408.31008) (xy 49.830994 -408.347986) (xy 49.822935 -408.423367)
			(xy 49.80691 -408.497465) (xy 49.7831 -408.56944) (xy 49.751774 -408.638476) (xy 49.713287 -408.703791)
			(xy 49.668076 -408.764646) (xy 49.616652 -408.82035) (xy 49.559599 -408.870272) (xy 49.497563 -408.913847)
			(xy 49.431246 -408.950582) (xy 49.3614 -408.980059) (xy 49.288817 -409.001945) (xy 49.214319 -409.015992)
			(xy 49.138749 -409.022041) (xy 49.062965 -409.020022) (xy 48.987825 -409.00996) (xy 48.91418 -408.991968)
			(xy 48.842864 -408.96625) (xy 48.774687 -408.933098) (xy 48.710419 -408.892886) (xy 48.65079 -408.846071)
			(xy 48.596474 -408.793183) (xy 48.548088 -408.734821) (xy 48.50618 -408.671646) (xy 48.471224 -408.604375)
			(xy 48.443617 -408.53377) (xy 48.423671 -408.460629) (xy 48.411612 -408.385784) (xy 48.407577 -408.31008)
			(xy 47.291498 -408.31008) (xy 47.290994 -408.347986) (xy 47.282935 -408.423367) (xy 47.26691 -408.497465)
			(xy 47.2431 -408.56944) (xy 47.211774 -408.638476) (xy 47.173287 -408.703791) (xy 47.128076 -408.764646)
			(xy 47.076652 -408.82035) (xy 47.019599 -408.870272) (xy 46.957563 -408.913847) (xy 46.891246 -408.950582)
			(xy 46.8214 -408.980059) (xy 46.748817 -409.001945) (xy 46.674319 -409.015992) (xy 46.598749 -409.022041)
			(xy 46.522965 -409.020022) (xy 46.447825 -409.00996) (xy 46.37418 -408.991968) (xy 46.302864 -408.96625)
			(xy 46.234687 -408.933098) (xy 46.170419 -408.892886) (xy 46.11079 -408.846071) (xy 46.056474 -408.793183)
			(xy 46.008088 -408.734821) (xy 45.96618 -408.671646) (xy 45.931224 -408.604375) (xy 45.903617 -408.53377)
			(xy 45.883671 -408.460629) (xy 45.871612 -408.385784) (xy 45.867577 -408.31008) (xy 44.751244 -408.31008)
			(xy 44.751244 -409.021788) (xy 43.328336 -409.021788) (xy 43.328336 -407.598372) (xy 43.055094 -407.598372)
			(xy 43.053462 -407.602742) (xy 43.004999 -407.709253) (xy 42.949245 -407.812135) (xy 42.886471 -407.910891)
			(xy 42.816981 -408.005042) (xy 42.741111 -408.094132) (xy 42.659229 -408.177729) (xy 42.571732 -408.25543)
			(xy 42.479042 -408.326857) (xy 42.381609 -408.391665) (xy 42.279905 -408.44954) (xy 42.174422 -408.500202)
			(xy 42.065671 -408.543404) (xy 41.954179 -408.578939) (xy 41.840485 -408.606634) (xy 41.725141 -408.626354)
			(xy 41.608704 -408.638005) (xy 41.491739 -408.64153) (xy 41.374812 -408.636912) (xy 41.258489 -408.624173)
			(xy 41.143334 -408.603375) (xy 41.029905 -408.574618) (xy 40.91875 -408.538042) (xy 40.810407 -408.493825)
			(xy 40.705403 -408.442179) (xy 40.604244 -408.383356) (xy 40.507421 -408.31764) (xy 40.415403 -408.245349)
			(xy 40.328636 -408.166834) (xy 40.247539 -408.082474) (xy 40.172506 -407.992679) (xy 40.103899 -407.897883)
			(xy 40.042051 -407.798544) (xy 39.987262 -407.695145) (xy 39.939796 -407.588186) (xy 39.899884 -407.478185)
			(xy 39.86772 -407.365674) (xy 39.843457 -407.251199) (xy 39.827215 -407.135313) (xy 39.819072 -407.018579)
			(xy 39.818564 -406.96007) (xy 36.329254 -406.96007) (xy 36.315846 -406.981724) (xy 36.263477 -407.051071)
			(xy 36.204933 -407.115291) (xy 36.140713 -407.173835) (xy 36.071366 -407.226204) (xy 35.997482 -407.271951)
			(xy 35.919693 -407.310685) (xy 35.838661 -407.342077) (xy 35.755079 -407.365858) (xy 35.669659 -407.381826)
			(xy 35.58313 -407.389844) (xy 35.49623 -407.389844) (xy 35.409701 -407.381826) (xy 35.324281 -407.365858)
			(xy 35.240699 -407.342077) (xy 35.159667 -407.310685) (xy 35.081878 -407.271951) (xy 35.007994 -407.226204)
			(xy 34.938647 -407.173835) (xy 34.874427 -407.115291) (xy 34.815883 -407.051071) (xy 34.763514 -406.981724)
			(xy 34.717767 -406.90784) (xy 34.679033 -406.830051) (xy 34.647641 -406.749019) (xy 34.62386 -406.665437)
			(xy 34.607892 -406.580017) (xy 34.599874 -406.493488) (xy 31.3995 -406.493488) (xy 31.391522 -406.579749)
			(xy 31.375606 -406.66504) (xy 31.351902 -406.748501) (xy 31.320609 -406.829424) (xy 31.281995 -406.907119)
			(xy 31.236387 -406.980928) (xy 31.184174 -407.05022) (xy 31.125799 -407.114409) (xy 31.061759 -407.172946)
			(xy 30.992599 -407.225335) (xy 30.918907 -407.27113) (xy 30.84131 -407.309942) (xy 30.760467 -407.34144)
			(xy 30.677066 -407.365357) (xy 30.591817 -407.381489) (xy 30.505444 -407.389699) (xy 30.418681 -407.389917)
			(xy 30.332268 -407.382141) (xy 30.246939 -407.366438) (xy 30.163419 -407.342941) (xy 30.082418 -407.31185)
			(xy 30.004627 -407.273429) (xy 29.930705 -407.228005) (xy 29.861283 -407.175964) (xy 29.828744 -407.147268)
			(xy 29.811703 -407.132502) (xy 29.773459 -407.108621) (xy 29.731602 -407.091862) (xy 29.687444 -407.082753)
			(xy 29.642372 -407.081577) (xy 29.5978 -407.088373) (xy 29.555126 -407.102928) (xy 29.51569 -407.124783)
			(xy 29.48073 -407.153254) (xy 29.451341 -407.187447) (xy 29.428447 -407.22629) (xy 29.412766 -407.268562)
			(xy 29.404789 -407.312939) (xy 29.40431 -407.335482) (xy 29.40431 -417.811204) (xy 51.478688 -417.811204)
			(xy 53.130196 -417.811204) (xy 53.130196 -419.462712) (xy 51.478688 -419.462712) (xy 51.478688 -417.811204)
			(xy 29.40431 -417.811204) (xy 29.40431 -418.677513) (xy 47.978812 -418.677513) (xy 47.978812 -418.596403)
			(xy 47.986762 -418.515684) (xy 48.002585 -418.436133) (xy 48.02613 -418.358517) (xy 48.057169 -418.283581)
			(xy 48.095404 -418.212049) (xy 48.140466 -418.144609) (xy 48.191921 -418.08191) (xy 48.249274 -418.024557)
			(xy 48.311973 -417.973102) (xy 48.379413 -417.92804) (xy 48.450945 -417.889805) (xy 48.525881 -417.858766)
			(xy 48.603497 -417.835221) (xy 48.683048 -417.819398) (xy 48.763767 -417.811448) (xy 48.844877 -417.811448)
			(xy 48.925596 -417.819398) (xy 49.005147 -417.835221) (xy 49.082763 -417.858766) (xy 49.157699 -417.889805)
			(xy 49.229231 -417.92804) (xy 49.296671 -417.973102) (xy 49.35937 -418.024557) (xy 49.416723 -418.08191)
			(xy 49.468178 -418.144609) (xy 49.51324 -418.212049) (xy 49.551475 -418.283581) (xy 49.582514 -418.358517)
			(xy 49.606059 -418.436133) (xy 49.621882 -418.515684) (xy 49.629832 -418.596403) (xy 49.63033 -418.636958)
			(xy 49.629832 -418.677513) (xy 49.621882 -418.758232) (xy 49.606059 -418.837783) (xy 49.582514 -418.915399)
			(xy 49.551475 -418.990335) (xy 49.51324 -419.061867) (xy 49.468178 -419.129307) (xy 49.416723 -419.192006)
			(xy 49.35937 -419.249359) (xy 49.296671 -419.300814) (xy 49.229231 -419.345876) (xy 49.157699 -419.384111)
			(xy 49.082763 -419.41515) (xy 49.005147 -419.438695) (xy 48.925596 -419.454518) (xy 48.844877 -419.462468)
			(xy 48.763767 -419.462468) (xy 48.683048 -419.454518) (xy 48.603497 -419.438695) (xy 48.525881 -419.41515)
			(xy 48.450945 -419.384111) (xy 48.379413 -419.345876) (xy 48.311973 -419.300814) (xy 48.249274 -419.249359)
			(xy 48.191921 -419.192006) (xy 48.140466 -419.129307) (xy 48.095404 -419.061867) (xy 48.057169 -418.990335)
			(xy 48.02613 -418.915399) (xy 48.002585 -418.837783) (xy 47.986762 -418.758232) (xy 47.978812 -418.677513)
			(xy 29.40431 -418.677513) (xy 29.40431 -421.610282) (xy 71.649336 -421.610282) (xy 71.649336 -420.533322)
			(xy 71.650025 -420.497256) (xy 71.660349 -420.425864) (xy 71.66991 -420.391082) (xy 71.674736 -420.373556)
			(xy 71.674736 -419.999668) (xy 72.640952 -419.999668) (xy 72.640952 -420.373556) (xy 72.645778 -420.391082)
			(xy 72.655331 -420.425866) (xy 72.665651 -420.497257) (xy 72.666352 -420.533322) (xy 72.666352 -420.765732)
			(xy 73.00468 -420.765732) (xy 73.00468 -419.688772) (xy 73.005163 -419.656045) (xy 73.013561 -419.591132)
			(xy 73.030216 -419.527833) (xy 73.054851 -419.467192) (xy 73.08706 -419.410211) (xy 73.10628 -419.383718)
			(xy 73.13168 -419.349936) (xy 73.13168 -419.332664) (xy 73.14692 -419.332664) (xy 73.182734 -419.302438)
			(xy 73.207911 -419.281585) (xy 73.262643 -419.245834) (xy 73.321508 -419.217395) (xy 73.383533 -419.19674)
			(xy 73.447695 -419.184209) (xy 73.512934 -419.180009) (xy 73.578173 -419.184209) (xy 73.642335 -419.19674)
			(xy 73.70436 -419.217395) (xy 73.763225 -419.245834) (xy 73.817957 -419.281585) (xy 73.843134 -419.302438)
			(xy 73.878948 -419.332664) (xy 73.894188 -419.332664) (xy 73.894188 -419.349936) (xy 73.919588 -419.383718)
			(xy 73.940197 -419.412156) (xy 73.974225 -419.473593) (xy 73.987406 -419.506146) (xy 73.993349 -419.520233)
			(xy 74.010856 -419.545289) (xy 74.033821 -419.56546) (xy 74.060926 -419.579588) (xy 74.090614 -419.58686)
			(xy 74.12118 -419.58686) (xy 74.150868 -419.579588) (xy 74.177973 -419.56546) (xy 74.200938 -419.545289)
			(xy 74.218445 -419.520233) (xy 74.224388 -419.506146) (xy 74.237568 -419.473592) (xy 74.271597 -419.412156)
			(xy 74.292206 -419.383718) (xy 74.317352 -419.349936) (xy 74.317352 -419.332664) (xy 74.332846 -419.332664)
			(xy 74.36866 -419.302438) (xy 74.393837 -419.281585) (xy 74.448569 -419.245834) (xy 74.507434 -419.217395)
			(xy 74.569459 -419.19674) (xy 74.633621 -419.184209) (xy 74.69886 -419.180009) (xy 74.764099 -419.184209)
			(xy 74.828261 -419.19674) (xy 74.890286 -419.217395) (xy 74.949151 -419.245834) (xy 75.003883 -419.281585)
			(xy 75.02906 -419.302438) (xy 75.064874 -419.332664) (xy 75.080368 -419.332664) (xy 75.080368 -419.349936)
			(xy 75.105514 -419.383718) (xy 75.124768 -419.410197) (xy 75.157032 -419.467166) (xy 75.181716 -419.527805)
			(xy 75.198412 -419.591111) (xy 75.206845 -419.656037) (xy 75.207368 -419.688772) (xy 75.207368 -420.06012)
			(xy 86.39887 -420.06012) (xy 86.402874 -419.860022) (xy 86.414881 -419.660244) (xy 86.434872 -419.461107)
			(xy 86.462814 -419.262929) (xy 86.498662 -419.066027) (xy 86.54236 -418.870718) (xy 86.593837 -418.677313)
			(xy 86.653011 -418.486123) (xy 86.719787 -418.297453) (xy 86.794059 -418.111606) (xy 86.875706 -417.928879)
			(xy 86.964599 -417.749566) (xy 87.060595 -417.573952) (xy 87.16354 -417.40232) (xy 87.27327 -417.234944)
			(xy 87.389608 -417.072093) (xy 87.512369 -416.914026) (xy 87.641356 -416.760998) (xy 87.776363 -416.613253)
			(xy 87.917172 -416.471027) (xy 88.063559 -416.33455) (xy 88.215289 -416.204038) (xy 88.37212 -416.079702)
			(xy 88.533799 -415.96174) (xy 88.700069 -415.850341) (xy 88.870662 -415.745684) (xy 89.045306 -415.647936)
			(xy 89.223722 -415.557253) (xy 89.405622 -415.473782) (xy 89.590717 -415.397655) (xy 89.778709 -415.328995)
			(xy 89.969298 -415.267911) (xy 90.162178 -415.214501) (xy 90.35704 -415.168852) (xy 90.553573 -415.131035)
			(xy 90.751462 -415.101111) (xy 90.950389 -415.079129) (xy 91.150037 -415.065124) (xy 91.350085 -415.059118)
			(xy 91.550213 -415.06112) (xy 91.750101 -415.071128) (xy 91.949428 -415.089125) (xy 92.147876 -415.115083)
			(xy 92.345126 -415.14896) (xy 92.540863 -415.190702) (xy 92.734773 -415.240241) (xy 92.926546 -415.297499)
			(xy 93.115875 -415.362384) (xy 93.302455 -415.434792) (xy 93.48599 -415.514608) (xy 93.666184 -415.601702)
			(xy 93.842749 -415.695936) (xy 94.015402 -415.797159) (xy 94.183867 -415.905209) (xy 94.347875 -416.019912)
			(xy 94.507162 -416.141086) (xy 94.661473 -416.268535) (xy 94.810561 -416.402056) (xy 94.954188 -416.541436)
			(xy 95.092124 -416.68645) (xy 95.224147 -416.836867) (xy 95.350046 -416.992445) (xy 95.46962 -417.152937)
			(xy 95.582676 -417.318083) (xy 95.689035 -417.487621) (xy 95.788526 -417.661279) (xy 95.880989 -417.838778)
			(xy 95.966276 -418.019834) (xy 96.044251 -418.204158) (xy 96.114788 -418.391454) (xy 96.177776 -418.581422)
			(xy 96.233113 -418.773758) (xy 96.28071 -418.968154) (xy 96.320491 -419.164299) (xy 96.352393 -419.361878)
			(xy 96.376364 -419.560575) (xy 96.392366 -419.760073) (xy 96.400373 -419.960051) (xy 96.400874 -420.06012)
			(xy 96.400373 -420.160189) (xy 96.392366 -420.360167) (xy 96.376364 -420.559665) (xy 96.352393 -420.758362)
			(xy 96.320491 -420.955941) (xy 96.28071 -421.152086) (xy 96.233113 -421.346482) (xy 96.177776 -421.538818)
			(xy 96.114788 -421.728786) (xy 96.044251 -421.916082) (xy 95.966276 -422.100406) (xy 95.880989 -422.281462)
			(xy 95.788526 -422.458961) (xy 95.689035 -422.632619) (xy 95.582676 -422.802157) (xy 95.46962 -422.967303)
			(xy 95.350046 -423.127795) (xy 95.224147 -423.283373) (xy 95.092124 -423.43379) (xy 94.954188 -423.578804)
			(xy 94.810561 -423.718184) (xy 94.661473 -423.851705) (xy 94.507162 -423.979154) (xy 94.347875 -424.100328)
			(xy 94.183867 -424.215031) (xy 94.015402 -424.323081) (xy 93.842749 -424.424304) (xy 93.666184 -424.518538)
			(xy 93.48599 -424.605632) (xy 93.302455 -424.685448) (xy 93.115875 -424.757856) (xy 92.926546 -424.822741)
			(xy 92.734773 -424.879999) (xy 92.540863 -424.929538) (xy 92.345126 -424.97128) (xy 92.147876 -425.005157)
			(xy 91.949428 -425.031115) (xy 91.750101 -425.049112) (xy 91.550213 -425.05912) (xy 91.350085 -425.061122)
			(xy 91.150037 -425.055116) (xy 90.950389 -425.041111) (xy 90.751462 -425.019129) (xy 90.553573 -424.989205)
			(xy 90.35704 -424.951388) (xy 90.162178 -424.905739) (xy 89.969298 -424.852329) (xy 89.778709 -424.791245)
			(xy 89.590717 -424.722585) (xy 89.405622 -424.646458) (xy 89.223722 -424.562987) (xy 89.045306 -424.472304)
			(xy 88.870662 -424.374556) (xy 88.700069 -424.269899) (xy 88.533799 -424.1585) (xy 88.37212 -424.040538)
			(xy 88.215289 -423.916202) (xy 88.063559 -423.78569) (xy 87.917172 -423.649213) (xy 87.776363 -423.506987)
			(xy 87.641356 -423.359242) (xy 87.512369 -423.206214) (xy 87.389608 -423.048147) (xy 87.27327 -422.885296)
			(xy 87.16354 -422.71792) (xy 87.060595 -422.546288) (xy 86.964599 -422.370674) (xy 86.875706 -422.191361)
			(xy 86.794059 -422.008634) (xy 86.719787 -421.822787) (xy 86.653011 -421.634117) (xy 86.593837 -421.442927)
			(xy 86.54236 -421.249522) (xy 86.498662 -421.054213) (xy 86.462814 -420.857311) (xy 86.434872 -420.659133)
			(xy 86.414881 -420.459996) (xy 86.402874 -420.260218) (xy 86.39887 -420.06012) (xy 75.207368 -420.06012)
			(xy 75.207368 -420.765732) (xy 75.206901 -420.797038) (xy 75.199209 -420.859177) (xy 75.183945 -420.919901)
			(xy 75.161341 -420.978292) (xy 75.131738 -421.033465) (xy 75.095585 -421.084586) (xy 75.053428 -421.13088)
			(xy 75.005906 -421.171648) (xy 74.953738 -421.206273) (xy 74.897713 -421.23423) (xy 74.838679 -421.255096)
			(xy 74.77753 -421.268556) (xy 74.715191 -421.274406) (xy 74.652605 -421.272557) (xy 74.59072 -421.263037)
			(xy 74.530472 -421.245991) (xy 74.472773 -421.221676) (xy 74.418497 -421.19046) (xy 74.368463 -421.152816)
			(xy 74.323431 -421.109313) (xy 74.303382 -421.085264) (xy 74.288768 -421.06796) (xy 74.254515 -421.038333)
			(xy 74.215551 -421.015249) (xy 74.173112 -420.999441) (xy 74.128541 -420.99141) (xy 74.083253 -420.99141)
			(xy 74.038682 -420.999441) (xy 73.996243 -421.015249) (xy 73.957279 -421.038333) (xy 73.923026 -421.06796)
			(xy 73.908412 -421.085264) (xy 73.888387 -421.109318) (xy 73.843355 -421.152787) (xy 73.793327 -421.1904)
			(xy 73.739061 -421.221587) (xy 73.681376 -421.245876) (xy 73.621146 -421.262901) (xy 73.559282 -421.272403)
			(xy 73.496719 -421.274239) (xy 73.434404 -421.268381) (xy 73.373279 -421.254918) (xy 73.314269 -421.234053)
			(xy 73.258267 -421.206103) (xy 73.20612 -421.171489) (xy 73.158616 -421.130735) (xy 73.116474 -421.084458)
			(xy 73.080332 -421.033358) (xy 73.050736 -420.978207) (xy 73.028134 -420.919841) (xy 73.012868 -420.859141)
			(xy 73.005168 -420.797027) (xy 73.00468 -420.765732) (xy 72.666352 -420.765732) (xy 72.666352 -421.610282)
			(xy 72.66585 -421.642243) (xy 72.657839 -421.705661) (xy 72.641942 -421.767575) (xy 72.61841 -421.827008)
			(xy 72.587616 -421.883023) (xy 72.550043 -421.934738) (xy 72.506286 -421.981335) (xy 72.457033 -422.02208)
			(xy 72.403062 -422.056331) (xy 72.345223 -422.083548) (xy 72.28443 -422.103301) (xy 72.22164 -422.115279)
			(xy 72.157844 -422.119293) (xy 72.094048 -422.115279) (xy 72.031258 -422.103301) (xy 71.970465 -422.083548)
			(xy 71.912626 -422.056331) (xy 71.858655 -422.02208) (xy 71.809402 -421.981335) (xy 71.765645 -421.934738)
			(xy 71.728072 -421.883023) (xy 71.697278 -421.827008) (xy 71.673746 -421.767575) (xy 71.657849 -421.705661)
			(xy 71.649838 -421.642243) (xy 71.649336 -421.610282) (xy 29.40431 -421.610282) (xy 29.40431 -422.444389)
			(xy 55.277413 -422.444389) (xy 55.281302 -422.39004) (xy 55.292886 -422.336797) (xy 55.31193 -422.285745)
			(xy 55.338045 -422.237923) (xy 55.3707 -422.194305) (xy 55.409231 -422.155778) (xy 55.452853 -422.123126)
			(xy 55.500677 -422.097015) (xy 55.551731 -422.077976) (xy 55.604974 -422.066397) (xy 55.659324 -422.062513)
			(xy 55.713673 -422.066404) (xy 55.766915 -422.07799) (xy 55.817967 -422.097035) (xy 55.865788 -422.123152)
			(xy 55.887874 -422.13911) (xy 55.906886 -422.152706) (xy 55.948769 -422.173438) (xy 55.993737 -422.186164)
			(xy 56.040274 -422.190454) (xy 56.086811 -422.186164) (xy 56.131779 -422.173438) (xy 56.173662 -422.152706)
			(xy 56.192674 -422.13911) (xy 56.214746 -422.123124) (xy 56.262574 -422.096996) (xy 56.313634 -422.077942)
			(xy 56.366886 -422.066349) (xy 56.421246 -422.062453) (xy 56.475607 -422.066334) (xy 56.528863 -422.077912)
			(xy 56.579928 -422.096952) (xy 56.627764 -422.123066) (xy 56.671396 -422.155722) (xy 56.709936 -422.194255)
			(xy 56.7426 -422.237882) (xy 56.768721 -422.285713) (xy 56.78777 -422.336775) (xy 56.799357 -422.390029)
			(xy 56.803247 -422.444389) (xy 57.164106 -422.444389) (xy 57.167995 -422.390038) (xy 57.17958 -422.336794)
			(xy 57.198624 -422.285741) (xy 57.22474 -422.237917) (xy 57.257397 -422.194298) (xy 57.295929 -422.15577)
			(xy 57.339553 -422.123118) (xy 57.387379 -422.097007) (xy 57.438434 -422.077968) (xy 57.49168 -422.066389)
			(xy 57.546031 -422.062506) (xy 57.600382 -422.066398) (xy 57.653625 -422.077985) (xy 57.704677 -422.097032)
			(xy 57.752499 -422.123151) (xy 57.774586 -422.13911) (xy 57.793598 -422.152706) (xy 57.835481 -422.173438)
			(xy 57.880449 -422.186164) (xy 57.926986 -422.190454) (xy 57.973523 -422.186164) (xy 58.018491 -422.173438)
			(xy 58.060374 -422.152706) (xy 58.079386 -422.13911) (xy 58.101458 -422.123125) (xy 58.149285 -422.096999)
			(xy 58.200344 -422.077947) (xy 58.253595 -422.066355) (xy 58.307953 -422.062461) (xy 58.362313 -422.066342)
			(xy 58.415566 -422.077921) (xy 58.46663 -422.09696) (xy 58.514464 -422.123074) (xy 58.558094 -422.15573)
			(xy 58.596633 -422.194262) (xy 58.629295 -422.237888) (xy 58.655416 -422.285718) (xy 58.674463 -422.336779)
			(xy 58.68605 -422.39003) (xy 58.689939 -422.444389) (xy 58.686053 -422.498748) (xy 58.674469 -422.552001)
			(xy 58.655425 -422.603062) (xy 58.629307 -422.650894) (xy 58.596647 -422.694521) (xy 58.55811 -422.733056)
			(xy 58.514482 -422.765714) (xy 58.466649 -422.791831) (xy 58.415587 -422.810873) (xy 58.362334 -422.822455)
			(xy 58.307975 -422.826339) (xy 58.253616 -422.822448) (xy 58.200365 -422.810859) (xy 58.149305 -422.79181)
			(xy 58.101476 -422.765687) (xy 58.079386 -422.749726) (xy 58.060374 -422.73613) (xy 58.018491 -422.715398)
			(xy 57.973523 -422.702672) (xy 57.926986 -422.698382) (xy 57.880449 -422.702672) (xy 57.835481 -422.715398)
			(xy 57.793598 -422.73613) (xy 57.774586 -422.749726) (xy 57.752481 -422.76566) (xy 57.704658 -422.791777)
			(xy 57.653604 -422.810821) (xy 57.60036 -422.822405) (xy 57.546009 -422.826294) (xy 57.491658 -422.822408)
			(xy 57.438414 -422.810826) (xy 57.387359 -422.791784) (xy 57.339534 -422.765671) (xy 57.295913 -422.733016)
			(xy 57.257383 -422.694486) (xy 57.224729 -422.650864) (xy 57.198615 -422.60304) (xy 57.179574 -422.551985)
			(xy 57.167992 -422.49874) (xy 57.164106 -422.444389) (xy 56.803247 -422.444389) (xy 56.79936 -422.49875)
			(xy 56.787776 -422.552004) (xy 56.76873 -422.603067) (xy 56.742611 -422.6509) (xy 56.70995 -422.694528)
			(xy 56.671412 -422.733064) (xy 56.627782 -422.765723) (xy 56.579948 -422.791839) (xy 56.528884 -422.810882)
			(xy 56.475629 -422.822463) (xy 56.421268 -422.826347) (xy 56.366908 -422.822454) (xy 56.313655 -422.810864)
			(xy 56.262594 -422.791813) (xy 56.214764 -422.765688) (xy 56.192674 -422.749726) (xy 56.173662 -422.73613)
			(xy 56.131779 -422.715398) (xy 56.086811 -422.702672) (xy 56.040274 -422.698382) (xy 55.993737 -422.702672)
			(xy 55.948769 -422.715398) (xy 55.906886 -422.73613) (xy 55.887874 -422.749726) (xy 55.86577 -422.765659)
			(xy 55.817947 -422.791774) (xy 55.766895 -422.810816) (xy 55.713652 -422.822399) (xy 55.659302 -422.826287)
			(xy 55.604953 -422.8224) (xy 55.55171 -422.810817) (xy 55.500658 -422.791776) (xy 55.452835 -422.765662)
			(xy 55.409215 -422.733008) (xy 55.370686 -422.694479) (xy 55.338033 -422.650858) (xy 55.311921 -422.603035)
			(xy 55.29288 -422.551982) (xy 55.281299 -422.498739) (xy 55.277413 -422.444389) (xy 29.40431 -422.444389)
			(xy 29.40431 -424.277974) (xy 55.277434 -424.277974) (xy 55.281325 -424.223628) (xy 55.292911 -424.170388)
			(xy 55.311955 -424.11934) (xy 55.338071 -424.071522) (xy 55.370726 -424.027907) (xy 55.409257 -423.989383)
			(xy 55.452877 -423.956735) (xy 55.5007 -423.930628) (xy 55.551752 -423.911592) (xy 55.604993 -423.900016)
			(xy 55.65934 -423.896134) (xy 55.713686 -423.900027) (xy 55.766924 -423.911614) (xy 55.817972 -423.930661)
			(xy 55.86579 -423.956778) (xy 55.887874 -423.972736) (xy 55.906886 -423.986332) (xy 55.948769 -424.007064)
			(xy 55.993737 -424.01979) (xy 56.040274 -424.02408) (xy 56.086811 -424.01979) (xy 56.131779 -424.007064)
			(xy 56.173662 -423.986332) (xy 56.192674 -423.972736) (xy 56.214722 -423.956715) (xy 56.262551 -423.930584)
			(xy 56.313613 -423.911527) (xy 56.366868 -423.899931) (xy 56.421231 -423.896033) (xy 56.475595 -423.899911)
			(xy 56.528854 -423.911488) (xy 56.579923 -423.930526) (xy 56.627762 -423.95664) (xy 56.671398 -423.989296)
			(xy 56.709942 -424.02783) (xy 56.742609 -424.071458) (xy 56.768734 -424.11929) (xy 56.787785 -424.170355)
			(xy 56.799375 -424.22361) (xy 56.803267 -424.277974) (xy 57.164127 -424.277974) (xy 57.168018 -424.223626)
			(xy 57.179604 -424.170385) (xy 57.198649 -424.119335) (xy 57.224766 -424.071516) (xy 57.257423 -424.0279)
			(xy 57.295955 -423.989375) (xy 57.339577 -423.956727) (xy 57.387402 -423.930619) (xy 57.438455 -423.911584)
			(xy 57.491698 -423.900008) (xy 57.546046 -423.896127) (xy 57.600394 -423.900021) (xy 57.653634 -423.91161)
			(xy 57.704683 -423.930658) (xy 57.752501 -423.956777) (xy 57.774586 -423.972736) (xy 57.793598 -423.986332)
			(xy 57.835481 -424.007064) (xy 57.880449 -424.01979) (xy 57.926986 -424.02408) (xy 57.973523 -424.01979)
			(xy 58.018491 -424.007064) (xy 58.060374 -423.986332) (xy 58.079386 -423.972736) (xy 58.101433 -423.956716)
			(xy 58.149262 -423.930587) (xy 58.200323 -423.911531) (xy 58.253576 -423.899937) (xy 58.307938 -423.89604)
			(xy 58.3623 -423.899919) (xy 58.415557 -423.911496) (xy 58.466624 -423.930535) (xy 58.514462 -423.956648)
			(xy 58.558096 -423.989304) (xy 58.596638 -424.027837) (xy 58.629304 -424.071464) (xy 58.655428 -424.119295)
			(xy 58.674479 -424.170358) (xy 58.686068 -424.223612) (xy 58.68996 -424.277974) (xy 59.405102 -424.277974)
			(xy 59.408993 -424.22362) (xy 59.420581 -424.170374) (xy 59.439629 -424.119319) (xy 59.46575 -424.071495)
			(xy 59.498411 -424.027875) (xy 59.536948 -423.989348) (xy 59.580576 -423.956697) (xy 59.628407 -423.930589)
			(xy 59.679467 -423.911554) (xy 59.732716 -423.89998) (xy 59.78707 -423.896102) (xy 59.841423 -423.9)
			(xy 59.894668 -423.911594) (xy 59.945721 -423.930648) (xy 59.993542 -423.956774) (xy 60.015628 -423.972736)
			(xy 60.03464 -423.986332) (xy 60.076523 -424.007064) (xy 60.121491 -424.01979) (xy 60.168028 -424.02408)
			(xy 60.214565 -424.01979) (xy 60.259533 -424.007064) (xy 60.301416 -423.986332) (xy 60.320428 -423.972736)
			(xy 60.342474 -423.956719) (xy 60.3903 -423.930597) (xy 60.441357 -423.911548) (xy 60.494606 -423.899958)
			(xy 60.548961 -423.896065) (xy 60.603318 -423.899947) (xy 60.656569 -423.911526) (xy 60.707629 -423.930565)
			(xy 60.755461 -423.956677) (xy 60.799089 -423.989331) (xy 60.837626 -424.027862) (xy 60.870287 -424.071484)
			(xy 60.896408 -424.119311) (xy 60.915456 -424.170369) (xy 60.927044 -424.223618) (xy 60.930935 -424.277974)
			(xy 61.309112 -424.277974) (xy 61.313003 -424.223622) (xy 61.32459 -424.170378) (xy 61.343637 -424.119325)
			(xy 61.369756 -424.071503) (xy 61.402416 -424.027884) (xy 61.440951 -423.989358) (xy 61.484576 -423.956709)
			(xy 61.532405 -423.930601) (xy 61.583462 -423.911565) (xy 61.636709 -423.89999) (xy 61.691061 -423.896112)
			(xy 61.745412 -423.900008) (xy 61.798655 -423.9116) (xy 61.849707 -423.930651) (xy 61.897527 -423.956775)
			(xy 61.919612 -423.972736) (xy 61.938624 -423.986332) (xy 61.980507 -424.007064) (xy 62.025475 -424.01979)
			(xy 62.072012 -424.02408) (xy 62.118549 -424.01979) (xy 62.163517 -424.007064) (xy 62.2054 -423.986332)
			(xy 62.224412 -423.972736) (xy 62.246459 -423.956718) (xy 62.294286 -423.930593) (xy 62.345344 -423.911541)
			(xy 62.398595 -423.89995) (xy 62.452952 -423.896055) (xy 62.507311 -423.899937) (xy 62.560564 -423.911515)
			(xy 62.611627 -423.930554) (xy 62.659461 -423.956666) (xy 62.703092 -423.989321) (xy 62.741631 -424.027852)
			(xy 62.774294 -424.071476) (xy 62.800416 -424.119305) (xy 62.819465 -424.170365) (xy 62.831053 -424.223616)
			(xy 62.834945 -424.277974) (xy 62.83106 -424.332332) (xy 62.819479 -424.385585) (xy 62.800438 -424.436647)
			(xy 62.774322 -424.484479) (xy 62.741665 -424.528108) (xy 62.703132 -424.566645) (xy 62.659506 -424.599305)
			(xy 62.611675 -424.625424) (xy 62.560615 -424.644471) (xy 62.507363 -424.656056) (xy 62.453005 -424.659945)
			(xy 62.398647 -424.656057) (xy 62.345395 -424.644473) (xy 62.294334 -424.625429) (xy 62.246503 -424.599311)
			(xy 62.224412 -424.583352) (xy 62.2054 -424.569756) (xy 62.163517 -424.549024) (xy 62.118549 -424.536298)
			(xy 62.072012 -424.532008) (xy 62.025475 -424.536298) (xy 61.980507 -424.549024) (xy 61.938624 -424.569756)
			(xy 61.919612 -424.583352) (xy 61.897482 -424.599254) (xy 61.849659 -424.625371) (xy 61.798605 -424.644415)
			(xy 61.74536 -424.656) (xy 61.691008 -424.659888) (xy 61.636657 -424.656002) (xy 61.583412 -424.64442)
			(xy 61.532357 -424.625378) (xy 61.484532 -424.599263) (xy 61.440911 -424.566607) (xy 61.402381 -424.528076)
			(xy 61.369728 -424.484453) (xy 61.343615 -424.436627) (xy 61.324575 -424.385571) (xy 61.312995 -424.332325)
			(xy 61.309112 -424.277974) (xy 60.930935 -424.277974) (xy 60.927051 -424.33233) (xy 60.915471 -424.38558)
			(xy 60.89643 -424.436641) (xy 60.870316 -424.484471) (xy 60.837661 -424.528098) (xy 60.799129 -424.566634)
			(xy 60.755505 -424.599294) (xy 60.707678 -424.625413) (xy 60.656619 -424.644459) (xy 60.60337 -424.656045)
			(xy 60.549014 -424.659935) (xy 60.494658 -424.656049) (xy 60.441408 -424.644467) (xy 60.390348 -424.625425)
			(xy 60.342519 -424.599309) (xy 60.320428 -424.583352) (xy 60.301416 -424.569756) (xy 60.259533 -424.549024)
			(xy 60.214565 -424.536298) (xy 60.168028 -424.532008) (xy 60.121491 -424.536298) (xy 60.076523 -424.549024)
			(xy 60.03464 -424.569756) (xy 60.015628 -424.583352) (xy 59.993498 -424.599255) (xy 59.945673 -424.625374)
			(xy 59.894618 -424.644421) (xy 59.841371 -424.656008) (xy 59.787018 -424.659898) (xy 59.732664 -424.656013)
			(xy 59.679416 -424.644431) (xy 59.628359 -424.625389) (xy 59.580532 -424.599274) (xy 59.536908 -424.566618)
			(xy 59.498376 -424.528085) (xy 59.465721 -424.484461) (xy 59.439607 -424.436633) (xy 59.420566 -424.385575)
			(xy 59.408986 -424.332328) (xy 59.405102 -424.277974) (xy 58.68996 -424.277974) (xy 58.686076 -424.332336)
			(xy 58.674494 -424.385592) (xy 58.65545 -424.436657) (xy 58.629333 -424.484492) (xy 58.596673 -424.528123)
			(xy 58.558136 -424.566662) (xy 58.514506 -424.599323) (xy 58.466672 -424.625443) (xy 58.415608 -424.644489)
			(xy 58.362352 -424.656073) (xy 58.30799 -424.65996) (xy 58.253629 -424.65607) (xy 58.200374 -424.644484)
			(xy 58.14931 -424.625435) (xy 58.101478 -424.599313) (xy 58.079386 -424.583352) (xy 58.060374 -424.569756)
			(xy 58.018491 -424.549024) (xy 57.973523 -424.536298) (xy 57.926986 -424.532008) (xy 57.880449 -424.536298)
			(xy 57.835481 -424.549024) (xy 57.793598 -424.569756) (xy 57.774586 -424.583352) (xy 57.752457 -424.599251)
			(xy 57.704635 -424.625364) (xy 57.653583 -424.644405) (xy 57.600342 -424.655987) (xy 57.545994 -424.659873)
			(xy 57.491646 -424.655985) (xy 57.438404 -424.644402) (xy 57.387354 -424.625359) (xy 57.339532 -424.599245)
			(xy 57.295915 -424.56659) (xy 57.257388 -424.528061) (xy 57.224738 -424.48444) (xy 57.198627 -424.436617)
			(xy 57.179589 -424.385564) (xy 57.168011 -424.332322) (xy 57.164127 -424.277974) (xy 56.803267 -424.277974)
			(xy 56.799383 -424.332337) (xy 56.7878 -424.385595) (xy 56.768756 -424.436662) (xy 56.742637 -424.484498)
			(xy 56.709976 -424.52813) (xy 56.671438 -424.56667) (xy 56.627806 -424.599332) (xy 56.579971 -424.625452)
			(xy 56.528904 -424.644497) (xy 56.475647 -424.656081) (xy 56.421284 -424.659967) (xy 56.36692 -424.656077)
			(xy 56.313664 -424.644488) (xy 56.262599 -424.625438) (xy 56.214766 -424.599314) (xy 56.192674 -424.583352)
			(xy 56.173662 -424.569756) (xy 56.131779 -424.549024) (xy 56.086811 -424.536298) (xy 56.040274 -424.532008)
			(xy 55.993737 -424.536298) (xy 55.948769 -424.549024) (xy 55.906886 -424.569756) (xy 55.887874 -424.583352)
			(xy 55.865745 -424.59925) (xy 55.817924 -424.625361) (xy 55.766874 -424.6444) (xy 55.713633 -424.655981)
			(xy 55.659287 -424.659866) (xy 55.604941 -424.655977) (xy 55.551701 -424.644393) (xy 55.500652 -424.62535)
			(xy 55.452833 -424.599236) (xy 55.409217 -424.566582) (xy 55.370692 -424.528053) (xy 55.338042 -424.484434)
			(xy 55.311933 -424.436612) (xy 55.292896 -424.385561) (xy 55.281318 -424.33232) (xy 55.277434 -424.277974)
			(xy 29.40431 -424.277974) (xy 29.40431 -426.179012) (xy 55.277383 -426.179012) (xy 55.281269 -426.124658)
			(xy 55.292851 -426.071411) (xy 55.311893 -426.020354) (xy 55.338007 -425.972526) (xy 55.370663 -425.928902)
			(xy 55.409194 -425.89037) (xy 55.452817 -425.857713) (xy 55.500644 -425.831597) (xy 55.5517 -425.812554)
			(xy 55.604948 -425.80097) (xy 55.659301 -425.797083) (xy 55.713655 -425.800971) (xy 55.766902 -425.812554)
			(xy 55.817958 -425.831598) (xy 55.865785 -425.857714) (xy 55.887874 -425.873672) (xy 55.906886 -425.887268)
			(xy 55.948769 -425.908) (xy 55.993737 -425.920726) (xy 56.040274 -425.925016) (xy 56.086811 -425.920726)
			(xy 56.131779 -425.908) (xy 56.173662 -425.887268) (xy 56.192674 -425.873672) (xy 56.214782 -425.857737)
			(xy 56.262608 -425.831615) (xy 56.313665 -425.812565) (xy 56.366913 -425.800976) (xy 56.421269 -425.797084)
			(xy 56.475626 -425.800967) (xy 56.528876 -425.812548) (xy 56.579936 -425.831589) (xy 56.627767 -425.857703)
			(xy 56.671393 -425.89036) (xy 56.709928 -425.928893) (xy 56.742586 -425.972518) (xy 56.768703 -426.020347)
			(xy 56.787747 -426.071406) (xy 56.79933 -426.124656) (xy 56.803216 -426.179012) (xy 57.164076 -426.179012)
			(xy 57.167962 -426.124657) (xy 57.179544 -426.071408) (xy 57.198587 -426.020349) (xy 57.224702 -425.97252)
			(xy 57.257359 -425.928895) (xy 57.295892 -425.890362) (xy 57.339517 -425.857705) (xy 57.387345 -425.831589)
			(xy 57.438404 -425.812545) (xy 57.491653 -425.800962) (xy 57.546008 -425.797076) (xy 57.600363 -425.800965)
			(xy 57.653612 -425.81255) (xy 57.704669 -425.831595) (xy 57.752497 -425.857713) (xy 57.774586 -425.873672)
			(xy 57.793598 -425.887268) (xy 57.835481 -425.908) (xy 57.880449 -425.920726) (xy 57.926986 -425.925016)
			(xy 57.973523 -425.920726) (xy 58.018491 -425.908) (xy 58.060374 -425.887268) (xy 58.079386 -425.873672)
			(xy 58.101493 -425.857738) (xy 58.149319 -425.831617) (xy 58.200375 -425.81257) (xy 58.253622 -425.800982)
			(xy 58.307976 -425.797091) (xy 58.362331 -425.800975) (xy 58.415579 -425.812556) (xy 58.466638 -425.831598)
			(xy 58.514466 -425.857712) (xy 58.558091 -425.890368) (xy 58.596625 -425.9289) (xy 58.629282 -425.972524)
			(xy 58.655397 -426.020351) (xy 58.67444 -426.071409) (xy 58.686023 -426.124657) (xy 58.689909 -426.179012)
			(xy 59.405051 -426.179012) (xy 59.408937 -426.124651) (xy 59.420521 -426.071396) (xy 59.439567 -426.020333)
			(xy 59.465686 -425.972499) (xy 59.498347 -425.92887) (xy 59.536885 -425.890334) (xy 59.580516 -425.857675)
			(xy 59.628351 -425.831558) (xy 59.679415 -425.812516) (xy 59.732671 -425.800934) (xy 59.787032 -425.797051)
			(xy 59.841393 -425.800943) (xy 59.894646 -425.812534) (xy 59.945707 -425.831585) (xy 59.993538 -425.85771)
			(xy 60.015628 -425.873672) (xy 60.03464 -425.887268) (xy 60.076523 -425.908) (xy 60.121491 -425.920726)
			(xy 60.168028 -425.925016) (xy 60.214565 -425.920726) (xy 60.259533 -425.908) (xy 60.301416 -425.887268)
			(xy 60.320428 -425.873672) (xy 60.342534 -425.857741) (xy 60.390357 -425.831628) (xy 60.441409 -425.812586)
			(xy 60.494651 -425.801003) (xy 60.549 -425.797116) (xy 60.603349 -425.801003) (xy 60.656591 -425.812586)
			(xy 60.707643 -425.831628) (xy 60.755466 -425.857741) (xy 60.799085 -425.890395) (xy 60.837613 -425.928924)
			(xy 60.870265 -425.972544) (xy 60.896377 -426.020368) (xy 60.915418 -426.07142) (xy 60.926998 -426.124663)
			(xy 60.930884 -426.179012) (xy 61.30906 -426.179012) (xy 61.312947 -426.124653) (xy 61.32453 -426.071401)
			(xy 61.343574 -426.020339) (xy 61.369692 -425.972507) (xy 61.402352 -425.92888) (xy 61.440888 -425.890345)
			(xy 61.484516 -425.857686) (xy 61.532349 -425.83157) (xy 61.583411 -425.812527) (xy 61.636664 -425.800945)
			(xy 61.691023 -425.79706) (xy 61.745381 -425.800952) (xy 61.798633 -425.81254) (xy 61.849693 -425.831589)
			(xy 61.897522 -425.857711) (xy 61.919612 -425.873672) (xy 61.938624 -425.887268) (xy 61.980507 -425.908)
			(xy 62.025475 -425.920726) (xy 62.072012 -425.925016) (xy 62.118549 -425.920726) (xy 62.163517 -425.908)
			(xy 62.2054 -425.887268) (xy 62.224412 -425.873672) (xy 62.246519 -425.85774) (xy 62.294342 -425.831624)
			(xy 62.345396 -425.81258) (xy 62.39864 -425.800995) (xy 62.452991 -425.797107) (xy 62.507342 -425.800993)
			(xy 62.560587 -425.812575) (xy 62.611641 -425.831616) (xy 62.659466 -425.85773) (xy 62.703087 -425.890385)
			(xy 62.741617 -425.928915) (xy 62.774271 -425.972536) (xy 62.800385 -426.020361) (xy 62.819426 -426.071416)
			(xy 62.831008 -426.124661) (xy 62.834893 -426.179012) (xy 62.831004 -426.233363) (xy 62.819419 -426.286607)
			(xy 62.800375 -426.33766) (xy 62.774258 -426.385484) (xy 62.741602 -426.429103) (xy 62.703069 -426.467631)
			(xy 62.659446 -426.500283) (xy 62.611619 -426.526394) (xy 62.560564 -426.545432) (xy 62.507318 -426.557011)
			(xy 62.452967 -426.560893) (xy 62.398616 -426.557001) (xy 62.345373 -426.545414) (xy 62.29432 -426.526366)
			(xy 62.246498 -426.500247) (xy 62.224412 -426.484288) (xy 62.2054 -426.470692) (xy 62.163517 -426.44996)
			(xy 62.118549 -426.437234) (xy 62.072012 -426.432944) (xy 62.025475 -426.437234) (xy 61.980507 -426.44996)
			(xy 61.938624 -426.470692) (xy 61.919612 -426.484288) (xy 61.897542 -426.500276) (xy 61.849715 -426.526401)
			(xy 61.798656 -426.545453) (xy 61.745405 -426.557045) (xy 61.691047 -426.56094) (xy 61.636688 -426.557058)
			(xy 61.583434 -426.54548) (xy 61.53237 -426.52644) (xy 61.484537 -426.500327) (xy 61.440906 -426.467671)
			(xy 61.402367 -426.429138) (xy 61.369705 -426.385513) (xy 61.343584 -426.337683) (xy 61.324537 -426.286622)
			(xy 61.31295 -426.233371) (xy 61.30906 -426.179012) (xy 60.930884 -426.179012) (xy 60.926995 -426.233361)
			(xy 60.915411 -426.286603) (xy 60.896367 -426.337654) (xy 60.870252 -426.385476) (xy 60.837597 -426.429094)
			(xy 60.799067 -426.467621) (xy 60.755445 -426.500272) (xy 60.707621 -426.526382) (xy 60.656568 -426.545421)
			(xy 60.603325 -426.557) (xy 60.548976 -426.560884) (xy 60.494627 -426.556993) (xy 60.441386 -426.545407)
			(xy 60.390335 -426.526362) (xy 60.342514 -426.500246) (xy 60.320428 -426.484288) (xy 60.301416 -426.470692)
			(xy 60.259533 -426.44996) (xy 60.214565 -426.437234) (xy 60.168028 -426.432944) (xy 60.121491 -426.437234)
			(xy 60.076523 -426.44996) (xy 60.03464 -426.470692) (xy 60.015628 -426.484288) (xy 59.993558 -426.500277)
			(xy 59.945729 -426.526405) (xy 59.894669 -426.54546) (xy 59.841416 -426.557053) (xy 59.787056 -426.560949)
			(xy 59.732694 -426.557069) (xy 59.679438 -426.545491) (xy 59.628373 -426.526452) (xy 59.580536 -426.500338)
			(xy 59.536904 -426.467682) (xy 59.498363 -426.429148) (xy 59.465699 -426.385521) (xy 59.439577 -426.337689)
			(xy 59.420528 -426.286627) (xy 59.408941 -426.233373) (xy 59.405051 -426.179012) (xy 58.689909 -426.179012)
			(xy 58.686019 -426.233366) (xy 58.674434 -426.286614) (xy 58.655387 -426.337671) (xy 58.629269 -426.385497)
			(xy 58.596609 -426.429119) (xy 58.558073 -426.467648) (xy 58.514446 -426.500301) (xy 58.466616 -426.526412)
			(xy 58.415556 -426.545451) (xy 58.362307 -426.557028) (xy 58.307952 -426.560909) (xy 58.253598 -426.557014)
			(xy 58.200351 -426.545424) (xy 58.149297 -426.526373) (xy 58.101473 -426.500249) (xy 58.079386 -426.484288)
			(xy 58.060374 -426.470692) (xy 58.018491 -426.44996) (xy 57.973523 -426.437234) (xy 57.926986 -426.432944)
			(xy 57.880449 -426.437234) (xy 57.835481 -426.44996) (xy 57.793598 -426.470692) (xy 57.774586 -426.484288)
			(xy 57.752517 -426.500274) (xy 57.704691 -426.526395) (xy 57.653635 -426.545443) (xy 57.600387 -426.557032)
			(xy 57.546032 -426.560924) (xy 57.491676 -426.557041) (xy 57.438427 -426.545462) (xy 57.387367 -426.526421)
			(xy 57.339537 -426.500308) (xy 57.29591 -426.467654) (xy 57.257375 -426.429123) (xy 57.224715 -426.3855)
			(xy 57.198597 -426.337673) (xy 57.179551 -426.286615) (xy 57.167965 -426.233367) (xy 57.164076 -426.179012)
			(xy 56.803216 -426.179012) (xy 56.799326 -426.233368) (xy 56.78774 -426.286617) (xy 56.768693 -426.337675)
			(xy 56.742573 -426.385503) (xy 56.709912 -426.429126) (xy 56.671375 -426.467656) (xy 56.627746 -426.500309)
			(xy 56.579914 -426.526421) (xy 56.528853 -426.545459) (xy 56.475602 -426.557036) (xy 56.421245 -426.560916)
			(xy 56.36689 -426.55702) (xy 56.313642 -426.545428) (xy 56.262586 -426.526375) (xy 56.214761 -426.50025)
			(xy 56.192674 -426.484288) (xy 56.173662 -426.470692) (xy 56.131779 -426.44996) (xy 56.086811 -426.437234)
			(xy 56.040274 -426.432944) (xy 55.993737 -426.437234) (xy 55.948769 -426.44996) (xy 55.906886 -426.470692)
			(xy 55.887874 -426.484288) (xy 55.865805 -426.500273) (xy 55.81798 -426.526392) (xy 55.766925 -426.545439)
			(xy 55.713679 -426.557026) (xy 55.659325 -426.560917) (xy 55.604971 -426.557033) (xy 55.551723 -426.545453)
			(xy 55.500666 -426.526413) (xy 55.452837 -426.5003) (xy 55.409212 -426.467646) (xy 55.370678 -426.429116)
			(xy 55.33802 -426.385494) (xy 55.311903 -426.337668) (xy 55.292857 -426.286612) (xy 55.281272 -426.233366)
			(xy 55.277383 -426.179012) (xy 29.40431 -426.179012) (xy 29.40431 -427.854094) (xy 55.277407 -427.854094)
			(xy 55.281295 -427.799744) (xy 55.292879 -427.7465) (xy 55.311922 -427.695447) (xy 55.338037 -427.647624)
			(xy 55.370692 -427.604004) (xy 55.409223 -427.565476) (xy 55.452845 -427.532823) (xy 55.50067 -427.506711)
			(xy 55.551724 -427.487672) (xy 55.604969 -427.476092) (xy 55.659319 -427.472207) (xy 55.713669 -427.476097)
			(xy 55.766912 -427.487683) (xy 55.817965 -427.506727) (xy 55.865787 -427.532844) (xy 55.887874 -427.548802)
			(xy 55.906886 -427.562398) (xy 55.948769 -427.58313) (xy 55.993737 -427.595856) (xy 56.040274 -427.600146)
			(xy 56.086811 -427.595856) (xy 56.131779 -427.58313) (xy 56.173662 -427.562398) (xy 56.192674 -427.548802)
			(xy 56.214753 -427.532826) (xy 56.262581 -427.5067) (xy 56.313641 -427.487647) (xy 56.366892 -427.476055)
			(xy 56.421251 -427.47216) (xy 56.475611 -427.476041) (xy 56.528866 -427.48762) (xy 56.57993 -427.50666)
			(xy 56.627764 -427.532774) (xy 56.671395 -427.56543) (xy 56.709934 -427.603963) (xy 56.742597 -427.647589)
			(xy 56.768718 -427.69542) (xy 56.787765 -427.746482) (xy 56.799351 -427.799734) (xy 56.80324 -427.854094)
			(xy 57.1641 -427.854094) (xy 57.167988 -427.799742) (xy 57.179572 -427.746497) (xy 57.198616 -427.695443)
			(xy 57.224732 -427.647618) (xy 57.257389 -427.603997) (xy 57.295921 -427.565468) (xy 57.339545 -427.532815)
			(xy 57.387372 -427.506703) (xy 57.438428 -427.487663) (xy 57.491674 -427.476084) (xy 57.546026 -427.4722)
			(xy 57.600378 -427.476091) (xy 57.653622 -427.487678) (xy 57.704676 -427.506725) (xy 57.752499 -427.532843)
			(xy 57.774586 -427.548802) (xy 57.793598 -427.562398) (xy 57.835481 -427.58313) (xy 57.880449 -427.595856)
			(xy 57.926986 -427.600146) (xy 57.973523 -427.595856) (xy 58.018491 -427.58313) (xy 58.060374 -427.562398)
			(xy 58.079386 -427.548802) (xy 58.101465 -427.532827) (xy 58.149292 -427.506703) (xy 58.20035 -427.487652)
			(xy 58.2536 -427.476061) (xy 58.307958 -427.472167) (xy 58.362316 -427.476049) (xy 58.415569 -427.487628)
			(xy 58.466631 -427.506668) (xy 58.514464 -427.532782) (xy 58.558093 -427.565438) (xy 58.596631 -427.60397)
			(xy 58.629292 -427.647595) (xy 58.655412 -427.695425) (xy 58.674458 -427.746485) (xy 58.686044 -427.799736)
			(xy 58.689933 -427.854094) (xy 59.405075 -427.854094) (xy 59.408964 -427.799736) (xy 59.420549 -427.746486)
			(xy 59.439596 -427.695426) (xy 59.465716 -427.647597) (xy 59.498377 -427.603972) (xy 59.536915 -427.56544)
			(xy 59.580544 -427.532786) (xy 59.628377 -427.506673) (xy 59.679439 -427.487634) (xy 59.732692 -427.476056)
			(xy 59.78705 -427.472175) (xy 59.841407 -427.47607) (xy 59.894656 -427.487662) (xy 59.945714 -427.506714)
			(xy 59.99354 -427.53284) (xy 60.015628 -427.548802) (xy 60.03464 -427.562398) (xy 60.076523 -427.58313)
			(xy 60.121491 -427.595856) (xy 60.168028 -427.600146) (xy 60.214565 -427.595856) (xy 60.259533 -427.58313)
			(xy 60.301416 -427.562398) (xy 60.320428 -427.548802) (xy 60.342506 -427.532831) (xy 60.39033 -427.506713)
			(xy 60.441385 -427.487668) (xy 60.49463 -427.476082) (xy 60.548982 -427.472192) (xy 60.603334 -427.476077)
			(xy 60.656581 -427.487658) (xy 60.707637 -427.506698) (xy 60.755463 -427.532811) (xy 60.799087 -427.565465)
			(xy 60.837619 -427.603995) (xy 60.870276 -427.647616) (xy 60.896392 -427.695441) (xy 60.915435 -427.746496)
			(xy 60.927019 -427.799742) (xy 60.930908 -427.854094) (xy 61.309084 -427.854094) (xy 61.312973 -427.799739)
			(xy 61.324558 -427.74649) (xy 61.343604 -427.695432) (xy 61.369722 -427.647605) (xy 61.402382 -427.603982)
			(xy 61.440917 -427.565451) (xy 61.484544 -427.532797) (xy 61.532375 -427.506684) (xy 61.583435 -427.487645)
			(xy 61.636685 -427.476066) (xy 61.691041 -427.472184) (xy 61.745396 -427.476078) (xy 61.798643 -427.487668)
			(xy 61.849699 -427.506718) (xy 61.897524 -427.532841) (xy 61.919612 -427.548802) (xy 61.938624 -427.562398)
			(xy 61.980507 -427.58313) (xy 62.025475 -427.595856) (xy 62.072012 -427.600146) (xy 62.118549 -427.595856)
			(xy 62.163517 -427.58313) (xy 62.2054 -427.562398) (xy 62.224412 -427.548802) (xy 62.246491 -427.53283)
			(xy 62.294316 -427.506709) (xy 62.345372 -427.487662) (xy 62.398619 -427.476074) (xy 62.452973 -427.472183)
			(xy 62.507327 -427.476066) (xy 62.560576 -427.487646) (xy 62.611635 -427.506687) (xy 62.659464 -427.5328)
			(xy 62.703089 -427.565455) (xy 62.741624 -427.603986) (xy 62.774282 -427.647608) (xy 62.800399 -427.695435)
			(xy 62.819444 -427.746492) (xy 62.831029 -427.79974) (xy 62.834917 -427.854094) (xy 62.831031 -427.908448)
			(xy 62.819448 -427.961696) (xy 62.800404 -428.012754) (xy 62.774288 -428.060582) (xy 62.741631 -428.104205)
			(xy 62.703098 -428.142738) (xy 62.659474 -428.175393) (xy 62.611646 -428.201508) (xy 62.560588 -428.22055)
			(xy 62.507339 -428.232132) (xy 62.452985 -428.236017) (xy 62.398631 -428.232128) (xy 62.345383 -428.220542)
			(xy 62.294327 -428.201496) (xy 62.246501 -428.175377) (xy 62.224412 -428.159418) (xy 62.2054 -428.145822)
			(xy 62.163517 -428.12509) (xy 62.118549 -428.112364) (xy 62.072012 -428.108074) (xy 62.025475 -428.112364)
			(xy 61.980507 -428.12509) (xy 61.938624 -428.145822) (xy 61.919612 -428.159418) (xy 61.897514 -428.175365)
			(xy 61.849688 -428.201487) (xy 61.798632 -428.220536) (xy 61.745384 -428.232124) (xy 61.691029 -428.236016)
			(xy 61.636673 -428.232132) (xy 61.583424 -428.220552) (xy 61.532364 -428.201511) (xy 61.484534 -428.175397)
			(xy 61.440908 -428.142741) (xy 61.402374 -428.104209) (xy 61.369716 -428.060585) (xy 61.343599 -428.012757)
			(xy 61.324555 -427.961698) (xy 61.312971 -427.908449) (xy 61.309084 -427.854094) (xy 60.930908 -427.854094)
			(xy 60.927021 -427.908446) (xy 60.915439 -427.961692) (xy 60.896397 -428.012748) (xy 60.870282 -428.060574)
			(xy 60.837627 -428.104196) (xy 60.799096 -428.142727) (xy 60.755473 -428.175382) (xy 60.707648 -428.201497)
			(xy 60.656592 -428.220539) (xy 60.603346 -428.232121) (xy 60.548994 -428.236008) (xy 60.494642 -428.232119)
			(xy 60.441396 -428.220535) (xy 60.390341 -428.201492) (xy 60.342516 -428.175376) (xy 60.320428 -428.159418)
			(xy 60.301416 -428.145822) (xy 60.259533 -428.12509) (xy 60.214565 -428.112364) (xy 60.168028 -428.108074)
			(xy 60.121491 -428.112364) (xy 60.076523 -428.12509) (xy 60.03464 -428.145822) (xy 60.015628 -428.159418)
			(xy 59.99353 -428.175367) (xy 59.945703 -428.201491) (xy 59.894645 -428.220542) (xy 59.841395 -428.232132)
			(xy 59.787038 -428.236025) (xy 59.73268 -428.232143) (xy 59.679428 -428.220563) (xy 59.628366 -428.201522)
			(xy 59.580534 -428.175408) (xy 59.536906 -428.142752) (xy 59.498369 -428.104218) (xy 59.465709 -428.060593)
			(xy 59.439591 -428.012763) (xy 59.420546 -427.961703) (xy 59.408962 -427.908452) (xy 59.405075 -427.854094)
			(xy 58.689933 -427.854094) (xy 58.686046 -427.908452) (xy 58.674462 -427.961703) (xy 58.655417 -428.012764)
			(xy 58.629299 -428.060594) (xy 58.596639 -428.104221) (xy 58.558103 -428.142755) (xy 58.514474 -428.175412)
			(xy 58.466642 -428.201527) (xy 58.41558 -428.220569) (xy 58.362328 -428.232149) (xy 58.30797 -428.236033)
			(xy 58.253612 -428.232141) (xy 58.200362 -428.220552) (xy 58.149303 -428.201502) (xy 58.101475 -428.175379)
			(xy 58.079386 -428.159418) (xy 58.060374 -428.145822) (xy 58.018491 -428.12509) (xy 57.973523 -428.112364)
			(xy 57.926986 -428.108074) (xy 57.880449 -428.112364) (xy 57.835481 -428.12509) (xy 57.793598 -428.145822)
			(xy 57.774586 -428.159418) (xy 57.752489 -428.175363) (xy 57.704665 -428.20148) (xy 57.653611 -428.220525)
			(xy 57.600366 -428.232111) (xy 57.546014 -428.236) (xy 57.491662 -428.232115) (xy 57.438416 -428.220533)
			(xy 57.387361 -428.201492) (xy 57.339535 -428.175378) (xy 57.295912 -428.142724) (xy 57.257381 -428.104194)
			(xy 57.224726 -428.060572) (xy 57.198611 -428.012747) (xy 57.179569 -427.961691) (xy 57.167986 -427.908446)
			(xy 57.1641 -427.854094) (xy 56.80324 -427.854094) (xy 56.799353 -427.908454) (xy 56.787768 -427.961707)
			(xy 56.768723 -428.012769) (xy 56.742603 -428.0606) (xy 56.709942 -428.104228) (xy 56.671404 -428.142762)
			(xy 56.627775 -428.17542) (xy 56.579941 -428.201535) (xy 56.528877 -428.220577) (xy 56.475623 -428.232157)
			(xy 56.421263 -428.23604) (xy 56.366904 -428.232147) (xy 56.313652 -428.220556) (xy 56.262592 -428.201505)
			(xy 56.214763 -428.17538) (xy 56.192674 -428.159418) (xy 56.173662 -428.145822) (xy 56.131779 -428.12509)
			(xy 56.086811 -428.112364) (xy 56.040274 -428.108074) (xy 55.993737 -428.112364) (xy 55.948769 -428.12509)
			(xy 55.906886 -428.145822) (xy 55.887874 -428.159418) (xy 55.865777 -428.175362) (xy 55.817954 -428.201478)
			(xy 55.766901 -428.220521) (xy 55.713657 -428.232105) (xy 55.659307 -428.235993) (xy 55.604957 -428.232107)
			(xy 55.551713 -428.220525) (xy 55.500659 -428.201484) (xy 55.452835 -428.17537) (xy 55.409214 -428.142716)
			(xy 55.370685 -428.104187) (xy 55.338031 -428.060566) (xy 55.311917 -428.012742) (xy 55.292875 -427.961688)
			(xy 55.281294 -427.908444) (xy 55.277407 -427.854094) (xy 29.40431 -427.854094) (xy 29.40431 -429.865311)
			(xy 55.233845 -429.865311) (xy 55.237732 -429.810948) (xy 55.249317 -429.757692) (xy 55.268363 -429.706627)
			(xy 55.294483 -429.658793) (xy 55.327146 -429.615163) (xy 55.365686 -429.576627) (xy 55.409318 -429.543967)
			(xy 55.457154 -429.517851) (xy 55.50822 -429.498808) (xy 55.561477 -429.487228) (xy 55.61584 -429.483345)
			(xy 55.670202 -429.487239) (xy 55.723456 -429.498831) (xy 55.774519 -429.517884) (xy 55.82235 -429.544011)
			(xy 55.84444 -429.559974) (xy 55.863452 -429.57357) (xy 55.905335 -429.594302) (xy 55.950303 -429.607028)
			(xy 55.99684 -429.611318) (xy 56.043377 -429.607028) (xy 56.088345 -429.594302) (xy 56.130228 -429.57357)
			(xy 56.14924 -429.559974) (xy 56.171344 -429.544042) (xy 56.219166 -429.51793) (xy 56.270217 -429.498889)
			(xy 56.323458 -429.487308) (xy 56.377806 -429.483422) (xy 56.432153 -429.48731) (xy 56.485394 -429.498892)
			(xy 56.536444 -429.517934) (xy 56.584265 -429.544048) (xy 56.627883 -429.576701) (xy 56.66641 -429.615229)
			(xy 56.699061 -429.658849) (xy 56.725172 -429.706671) (xy 56.744212 -429.757722) (xy 56.755793 -429.810963)
			(xy 56.759678 -429.865311) (xy 57.120698 -429.865311) (xy 57.124584 -429.81096) (xy 57.136165 -429.757716)
			(xy 57.155205 -429.706662) (xy 57.181318 -429.658837) (xy 57.213971 -429.615215) (xy 57.252499 -429.576684)
			(xy 57.296119 -429.544029) (xy 57.343943 -429.517914) (xy 57.394996 -429.49887) (xy 57.44824 -429.487286)
			(xy 57.50259 -429.483398) (xy 57.55694 -429.487284) (xy 57.610185 -429.498865) (xy 57.661239 -429.517905)
			(xy 57.709064 -429.544018) (xy 57.731152 -429.559974) (xy 57.750164 -429.57357) (xy 57.792047 -429.594302)
			(xy 57.837015 -429.607028) (xy 57.883552 -429.611318) (xy 57.930089 -429.607028) (xy 57.975057 -429.594302)
			(xy 58.01694 -429.57357) (xy 58.035952 -429.559974) (xy 58.058058 -429.544034) (xy 58.105886 -429.517908)
			(xy 58.156945 -429.498855) (xy 58.210196 -429.487264) (xy 58.264555 -429.483369) (xy 58.318915 -429.487251)
			(xy 58.372169 -429.49883) (xy 58.423233 -429.517871) (xy 58.471067 -429.543986) (xy 58.514697 -429.576643)
			(xy 58.553235 -429.615178) (xy 58.585896 -429.658805) (xy 58.612015 -429.706636) (xy 58.63106 -429.757698)
			(xy 58.642644 -429.810951) (xy 58.646531 -429.865311) (xy 59.361673 -429.865311) (xy 59.365559 -429.810955)
			(xy 59.377142 -429.757705) (xy 59.396185 -429.706645) (xy 59.422301 -429.658816) (xy 59.454959 -429.61519)
			(xy 59.493493 -429.576657) (xy 59.537119 -429.544) (xy 59.584948 -429.517884) (xy 59.636008 -429.498841)
			(xy 59.689258 -429.487258) (xy 59.743614 -429.483373) (xy 59.79797 -429.487262) (xy 59.851219 -429.498849)
			(xy 59.902277 -429.517895) (xy 59.950105 -429.544015) (xy 59.972194 -429.559974) (xy 59.991206 -429.57357)
			(xy 60.033089 -429.594302) (xy 60.078057 -429.607028) (xy 60.124594 -429.611318) (xy 60.171131 -429.607028)
			(xy 60.216099 -429.594302) (xy 60.257982 -429.57357) (xy 60.276994 -429.559974) (xy 60.299099 -429.544038)
			(xy 60.346924 -429.517918) (xy 60.397979 -429.498872) (xy 60.451226 -429.487285) (xy 60.505579 -429.483394)
			(xy 60.559933 -429.487279) (xy 60.613181 -429.49886) (xy 60.664238 -429.517901) (xy 60.712066 -429.544015)
			(xy 60.75569 -429.576671) (xy 60.794223 -429.615202) (xy 60.826879 -429.658826) (xy 60.852995 -429.706653)
			(xy 60.872037 -429.75771) (xy 60.88362 -429.810957) (xy 60.887506 -429.865311) (xy 61.265682 -429.865311)
			(xy 61.269568 -429.810957) (xy 61.28115 -429.757709) (xy 61.300193 -429.706652) (xy 61.326308 -429.658824)
			(xy 61.358963 -429.6152) (xy 61.397495 -429.576667) (xy 61.441119 -429.544011) (xy 61.488946 -429.517895)
			(xy 61.540003 -429.498852) (xy 61.593251 -429.487269) (xy 61.647605 -429.483382) (xy 61.701959 -429.48727)
			(xy 61.755206 -429.498855) (xy 61.806263 -429.517899) (xy 61.854089 -429.544016) (xy 61.876178 -429.559974)
			(xy 61.89519 -429.57357) (xy 61.937073 -429.594302) (xy 61.982041 -429.607028) (xy 62.028578 -429.611318)
			(xy 62.075115 -429.607028) (xy 62.120083 -429.594302) (xy 62.161966 -429.57357) (xy 62.180978 -429.559974)
			(xy 62.203084 -429.544036) (xy 62.25091 -429.517915) (xy 62.301966 -429.498865) (xy 62.355215 -429.487277)
			(xy 62.40957 -429.483385) (xy 62.463926 -429.487268) (xy 62.517177 -429.498849) (xy 62.568236 -429.51789)
			(xy 62.616066 -429.544004) (xy 62.659693 -429.57666) (xy 62.698227 -429.615193) (xy 62.730885 -429.658818)
			(xy 62.757002 -429.706646) (xy 62.776046 -429.757705) (xy 62.787629 -429.810955) (xy 62.791515 -429.865311)
			(xy 62.787626 -429.919667) (xy 62.77604 -429.972915) (xy 62.756993 -430.023973) (xy 62.730874 -430.0718)
			(xy 62.698213 -430.115423) (xy 62.663615 -430.150016) (xy 69.997584 -430.150016) (xy 70.001572 -429.897396)
			(xy 70.013533 -429.645028) (xy 70.033455 -429.393164) (xy 70.061319 -429.142054) (xy 70.097095 -428.891948)
			(xy 70.140749 -428.643097) (xy 70.192238 -428.395748) (xy 70.251509 -428.150147) (xy 70.318504 -427.90654)
			(xy 70.393155 -427.66517) (xy 70.47539 -427.426276) (xy 70.565124 -427.190098) (xy 70.66227 -426.95687)
			(xy 70.76673 -426.726824) (xy 70.878401 -426.500192) (xy 70.99717 -426.277197) (xy 71.122919 -426.058063)
			(xy 71.255524 -425.843008) (xy 71.394851 -425.632246) (xy 71.540763 -425.425988) (xy 71.693113 -425.224439)
			(xy 71.851749 -425.027799) (xy 72.016514 -424.836266) (xy 72.187244 -424.650029) (xy 72.363768 -424.469275)
			(xy 72.54591 -424.294184) (xy 72.733488 -424.12493) (xy 72.926316 -423.961681) (xy 73.124201 -423.804602)
			(xy 73.326947 -423.653847) (xy 73.534351 -423.509569) (xy 73.746206 -423.371909) (xy 73.962301 -423.241006)
			(xy 74.182421 -423.11699) (xy 74.406346 -422.999985) (xy 74.633853 -422.890107) (xy 74.864715 -422.787466)
			(xy 75.098703 -422.692164) (xy 75.335582 -422.604297) (xy 75.575118 -422.52395) (xy 75.81707 -422.451206)
			(xy 76.061198 -422.386136) (xy 76.307259 -422.328806) (xy 76.555007 -422.279272) (xy 76.804195 -422.237583)
			(xy 77.054575 -422.203782) (xy 77.305897 -422.177901) (xy 77.557911 -422.159968) (xy 77.810365 -422.149999)
			(xy 78.063009 -422.148005) (xy 78.315589 -422.153987) (xy 78.567855 -422.16794) (xy 78.819554 -422.18985)
			(xy 79.070437 -422.219694) (xy 79.320252 -422.257444) (xy 79.568751 -422.303061) (xy 79.815686 -422.3565)
			(xy 80.060811 -422.417708) (xy 80.303881 -422.486623) (xy 80.544655 -422.563178) (xy 80.782892 -422.647295)
			(xy 81.018355 -422.738892) (xy 81.250809 -422.837876) (xy 81.480023 -422.944148) (xy 81.705767 -423.057604)
			(xy 81.927817 -423.178129) (xy 82.145951 -423.305605) (xy 82.359953 -423.439903) (xy 82.569609 -423.580889)
			(xy 82.774709 -423.728424) (xy 82.975049 -423.88236) (xy 83.17043 -424.042544) (xy 83.360657 -424.208816)
			(xy 83.54554 -424.381011) (xy 83.724896 -424.558955) (xy 83.898544 -424.742474) (xy 84.066312 -424.931382)
			(xy 84.228033 -425.125493) (xy 84.383546 -425.324612) (xy 84.532695 -425.528541) (xy 84.675332 -425.737077)
			(xy 84.811315 -425.950012) (xy 84.940508 -426.167134) (xy 85.062783 -426.388226) (xy 85.178017 -426.613067)
			(xy 85.286096 -426.841435) (xy 85.386911 -427.0731) (xy 85.480363 -427.307833) (xy 85.566358 -427.545398)
			(xy 85.644811 -427.78556) (xy 85.715643 -428.028079) (xy 85.778784 -428.272714) (xy 85.834171 -428.519219)
			(xy 85.881748 -428.76735) (xy 85.921468 -429.01686) (xy 85.953292 -429.267499) (xy 85.977188 -429.519017)
			(xy 85.993132 -429.771165) (xy 86.001107 -430.02369) (xy 86.001606 -430.150016) (xy 86.001107 -430.276342)
			(xy 85.993132 -430.528867) (xy 85.977188 -430.781015) (xy 85.953292 -431.032533) (xy 85.921468 -431.283172)
			(xy 85.881748 -431.532682) (xy 85.834171 -431.780813) (xy 85.778784 -432.027318) (xy 85.715643 -432.271953)
			(xy 85.644811 -432.514472) (xy 85.566358 -432.754634) (xy 85.480363 -432.992199) (xy 85.386911 -433.226932)
			(xy 85.286096 -433.458597) (xy 85.178017 -433.686965) (xy 85.062783 -433.911806) (xy 84.940508 -434.132898)
			(xy 84.811315 -434.35002) (xy 84.675332 -434.562955) (xy 84.532695 -434.771491) (xy 84.383546 -434.97542)
			(xy 84.228033 -435.174539) (xy 84.066312 -435.36865) (xy 83.898544 -435.557558) (xy 83.724896 -435.741077)
			(xy 83.54554 -435.919021) (xy 83.360657 -436.091216) (xy 83.17043 -436.257488) (xy 82.975049 -436.417672)
			(xy 82.774709 -436.571608) (xy 82.569609 -436.719143) (xy 82.359953 -436.860129) (xy 82.145951 -436.994427)
			(xy 81.927817 -437.121903) (xy 81.705767 -437.242428) (xy 81.480023 -437.355884) (xy 81.250809 -437.462156)
			(xy 81.018355 -437.56114) (xy 80.782892 -437.652737) (xy 80.544655 -437.736854) (xy 80.303881 -437.813409)
			(xy 80.060811 -437.882324) (xy 79.815686 -437.943532) (xy 79.568751 -437.996971) (xy 79.320252 -438.042588)
			(xy 79.070437 -438.080338) (xy 78.819554 -438.110182) (xy 78.567855 -438.132092) (xy 78.315589 -438.146045)
			(xy 78.063009 -438.152027) (xy 77.810365 -438.150033) (xy 77.557911 -438.140064) (xy 77.305897 -438.122131)
			(xy 77.054575 -438.09625) (xy 76.804195 -438.062449) (xy 76.555007 -438.02076) (xy 76.307259 -437.971226)
			(xy 76.061198 -437.913896) (xy 75.81707 -437.848826) (xy 75.575118 -437.776082) (xy 75.335582 -437.695735)
			(xy 75.098703 -437.607868) (xy 74.864715 -437.512566) (xy 74.633853 -437.409925) (xy 74.406346 -437.300047)
			(xy 74.182421 -437.183042) (xy 73.962301 -437.059026) (xy 73.746206 -436.928123) (xy 73.534351 -436.790463)
			(xy 73.326947 -436.646185) (xy 73.124201 -436.49543) (xy 72.926316 -436.338351) (xy 72.733488 -436.175102)
			(xy 72.54591 -436.005848) (xy 72.363768 -435.830757) (xy 72.187244 -435.650003) (xy 72.016514 -435.463766)
			(xy 71.851749 -435.272233) (xy 71.693113 -435.075593) (xy 71.540763 -434.874044) (xy 71.394851 -434.667786)
			(xy 71.255524 -434.457024) (xy 71.122919 -434.241969) (xy 70.99717 -434.022835) (xy 70.878401 -433.79984)
			(xy 70.76673 -433.573208) (xy 70.66227 -433.343162) (xy 70.565124 -433.109934) (xy 70.47539 -432.873756)
			(xy 70.393155 -432.634862) (xy 70.318504 -432.393492) (xy 70.251509 -432.149885) (xy 70.192238 -431.904284)
			(xy 70.140749 -431.656935) (xy 70.097095 -431.408084) (xy 70.061319 -431.157978) (xy 70.033455 -430.906868)
			(xy 70.013533 -430.655004) (xy 70.001572 -430.402636) (xy 69.997584 -430.150016) (xy 62.663615 -430.150016)
			(xy 62.659676 -430.153954) (xy 62.616048 -430.186607) (xy 62.568217 -430.212719) (xy 62.517156 -430.231757)
			(xy 62.463905 -430.243335) (xy 62.409549 -430.247215) (xy 62.355193 -430.24332) (xy 62.301946 -430.231728)
			(xy 62.25089 -430.212676) (xy 62.203065 -430.186552) (xy 62.180978 -430.17059) (xy 62.161966 -430.156994)
			(xy 62.120083 -430.136262) (xy 62.075115 -430.123536) (xy 62.028578 -430.119246) (xy 61.982041 -430.123536)
			(xy 61.937073 -430.136262) (xy 61.89519 -430.156994) (xy 61.876178 -430.17059) (xy 61.854107 -430.186572)
			(xy 61.806282 -430.212692) (xy 61.755227 -430.231739) (xy 61.70198 -430.243326) (xy 61.647626 -430.247218)
			(xy 61.593272 -430.243334) (xy 61.540024 -430.231754) (xy 61.488966 -430.212714) (xy 61.441137 -430.186601)
			(xy 61.397512 -430.153947) (xy 61.358978 -430.115416) (xy 61.326319 -430.071794) (xy 61.300202 -430.023968)
			(xy 61.281156 -429.972912) (xy 61.269571 -429.919665) (xy 61.265682 -429.865311) (xy 60.887506 -429.865311)
			(xy 60.883617 -429.919664) (xy 60.872031 -429.972911) (xy 60.852986 -430.023967) (xy 60.826868 -430.071793)
			(xy 60.794209 -430.115414) (xy 60.755674 -430.153943) (xy 60.712048 -430.186596) (xy 60.664219 -430.212708)
			(xy 60.61316 -430.231746) (xy 60.559912 -430.243324) (xy 60.505558 -430.247206) (xy 60.451204 -430.243312)
			(xy 60.397959 -430.231722) (xy 60.346904 -430.212673) (xy 60.299081 -430.18655) (xy 60.276994 -430.17059)
			(xy 60.257982 -430.156994) (xy 60.216099 -430.136262) (xy 60.171131 -430.123536) (xy 60.124594 -430.119246)
			(xy 60.078057 -430.123536) (xy 60.033089 -430.136262) (xy 59.991206 -430.156994) (xy 59.972194 -430.17059)
			(xy 59.950123 -430.186574) (xy 59.902297 -430.212696) (xy 59.85124 -430.231745) (xy 59.797991 -430.243335)
			(xy 59.743635 -430.247227) (xy 59.689279 -430.243345) (xy 59.636028 -430.231765) (xy 59.584968 -430.212725)
			(xy 59.537137 -430.186612) (xy 59.493509 -430.153957) (xy 59.454973 -430.115426) (xy 59.422313 -430.071802)
			(xy 59.396194 -430.023974) (xy 59.377148 -429.972916) (xy 59.365562 -429.919667) (xy 59.361673 -429.865311)
			(xy 58.646531 -429.865311) (xy 58.642641 -429.91967) (xy 58.631054 -429.972922) (xy 58.612006 -430.023983)
			(xy 58.585884 -430.071813) (xy 58.553221 -430.115439) (xy 58.514681 -430.153971) (xy 58.471049 -430.186626)
			(xy 58.423213 -430.212738) (xy 58.372149 -430.231776) (xy 58.318894 -430.243352) (xy 58.264534 -430.247231)
			(xy 58.210175 -430.243333) (xy 58.156925 -430.231739) (xy 58.105866 -430.212683) (xy 58.05804 -430.186554)
			(xy 58.035952 -430.17059) (xy 58.01694 -430.156994) (xy 57.975057 -430.136262) (xy 57.930089 -430.123536)
			(xy 57.883552 -430.119246) (xy 57.837015 -430.123536) (xy 57.792047 -430.136262) (xy 57.750164 -430.156994)
			(xy 57.731152 -430.17059) (xy 57.709082 -430.18657) (xy 57.661259 -430.212686) (xy 57.610205 -430.231729)
			(xy 57.556962 -430.243313) (xy 57.502612 -430.247202) (xy 57.448261 -430.243317) (xy 57.395017 -430.231736)
			(xy 57.343962 -430.212695) (xy 57.296138 -430.186583) (xy 57.252516 -430.15393) (xy 57.213985 -430.115401)
			(xy 57.181329 -430.071781) (xy 57.155214 -430.023958) (xy 57.136171 -429.972905) (xy 57.124587 -429.919661)
			(xy 57.120698 -429.865311) (xy 56.759678 -429.865311) (xy 56.75579 -429.919658) (xy 56.744206 -429.972899)
			(xy 56.725163 -430.023949) (xy 56.699049 -430.07177) (xy 56.666396 -430.115387) (xy 56.627867 -430.153913)
			(xy 56.584247 -430.186564) (xy 56.536425 -430.212675) (xy 56.485373 -430.231714) (xy 56.432131 -430.243293)
			(xy 56.377784 -430.247178) (xy 56.323437 -430.243289) (xy 56.270196 -430.231705) (xy 56.219146 -430.212661)
			(xy 56.171326 -430.186547) (xy 56.14924 -430.17059) (xy 56.130228 -430.156994) (xy 56.088345 -430.136262)
			(xy 56.043377 -430.123536) (xy 55.99684 -430.119246) (xy 55.950303 -430.123536) (xy 55.905335 -430.136262)
			(xy 55.863452 -430.156994) (xy 55.84444 -430.17059) (xy 55.822368 -430.186578) (xy 55.774538 -430.212707)
			(xy 55.723477 -430.231763) (xy 55.670223 -430.243358) (xy 55.615862 -430.247255) (xy 55.561499 -430.243375)
			(xy 55.508241 -430.231798) (xy 55.457174 -430.212758) (xy 55.409336 -430.186644) (xy 55.365702 -430.153987)
			(xy 55.32716 -430.115453) (xy 55.294495 -430.071825) (xy 55.268372 -430.023992) (xy 55.249323 -429.972928)
			(xy 55.237735 -429.919673) (xy 55.233845 -429.865311) (xy 29.40431 -429.865311) (xy 29.40431 -431.755798)
			(xy 55.233863 -431.755798) (xy 55.237751 -431.701438) (xy 55.249337 -431.648185) (xy 55.268384 -431.597123)
			(xy 55.294505 -431.549292) (xy 55.327168 -431.505665) (xy 55.365707 -431.467131) (xy 55.409338 -431.434475)
			(xy 55.457173 -431.408361) (xy 55.508238 -431.389321) (xy 55.561493 -431.377743) (xy 55.615853 -431.373863)
			(xy 55.670213 -431.377759) (xy 55.723464 -431.389351) (xy 55.774523 -431.408405) (xy 55.822351 -431.434533)
			(xy 55.84444 -431.450496) (xy 55.863452 -431.464092) (xy 55.905335 -431.484824) (xy 55.950303 -431.49755)
			(xy 55.99684 -431.50184) (xy 56.043377 -431.49755) (xy 56.088345 -431.484824) (xy 56.130228 -431.464092)
			(xy 56.14924 -431.450496) (xy 56.171323 -431.434534) (xy 56.219146 -431.408419) (xy 56.270199 -431.389376)
			(xy 56.323442 -431.377793) (xy 56.377792 -431.373904) (xy 56.432142 -431.37779) (xy 56.485386 -431.389372)
			(xy 56.53644 -431.408413) (xy 56.584264 -431.434526) (xy 56.627885 -431.467179) (xy 56.666414 -431.505708)
			(xy 56.699069 -431.549328) (xy 56.725183 -431.597151) (xy 56.744225 -431.648204) (xy 56.755808 -431.701448)
			(xy 56.759696 -431.755798) (xy 57.120715 -431.755798) (xy 57.124603 -431.70145) (xy 57.136185 -431.648208)
			(xy 57.155227 -431.597157) (xy 57.18134 -431.549335) (xy 57.213993 -431.505717) (xy 57.252521 -431.467189)
			(xy 57.29614 -431.434537) (xy 57.343962 -431.408424) (xy 57.395014 -431.389384) (xy 57.448255 -431.377802)
			(xy 57.502603 -431.373915) (xy 57.556951 -431.377803) (xy 57.610192 -431.389385) (xy 57.661244 -431.408427)
			(xy 57.709065 -431.43454) (xy 57.731152 -431.450496) (xy 57.750164 -431.464092) (xy 57.792047 -431.484824)
			(xy 57.837015 -431.49755) (xy 57.883552 -431.50184) (xy 57.930089 -431.49755) (xy 57.975057 -431.484824)
			(xy 58.01694 -431.464092) (xy 58.035952 -431.450496) (xy 58.058038 -431.434527) (xy 58.105867 -431.408398)
			(xy 58.156928 -431.389342) (xy 58.210181 -431.377748) (xy 58.264542 -431.373852) (xy 58.318905 -431.377732)
			(xy 58.372162 -431.38931) (xy 58.423228 -431.40835) (xy 58.471065 -431.434464) (xy 58.514698 -431.467121)
			(xy 58.553239 -431.505656) (xy 58.585903 -431.549284) (xy 58.612025 -431.597117) (xy 58.631073 -431.648181)
			(xy 58.64266 -431.701436) (xy 58.646548 -431.755798) (xy 59.36169 -431.755798) (xy 59.365578 -431.701444)
			(xy 59.377162 -431.648197) (xy 59.396206 -431.597141) (xy 59.422323 -431.549314) (xy 59.454981 -431.505692)
			(xy 59.493514 -431.467162) (xy 59.537139 -431.434507) (xy 59.584967 -431.408394) (xy 59.636025 -431.389354)
			(xy 59.689273 -431.377774) (xy 59.743627 -431.37389) (xy 59.79798 -431.377782) (xy 59.851227 -431.389369)
			(xy 59.902282 -431.408417) (xy 59.950106 -431.434537) (xy 59.972194 -431.450496) (xy 59.991206 -431.464092)
			(xy 60.033089 -431.484824) (xy 60.078057 -431.49755) (xy 60.124594 -431.50184) (xy 60.171131 -431.49755)
			(xy 60.216099 -431.484824) (xy 60.257982 -431.464092) (xy 60.276994 -431.450496) (xy 60.299079 -431.43453)
			(xy 60.346905 -431.408408) (xy 60.397962 -431.389358) (xy 60.45121 -431.377769) (xy 60.505566 -431.373877)
			(xy 60.559923 -431.37776) (xy 60.613173 -431.389339) (xy 60.664234 -431.40838) (xy 60.712064 -431.434494)
			(xy 60.755692 -431.467149) (xy 60.794227 -431.505681) (xy 60.826887 -431.549305) (xy 60.853005 -431.597133)
			(xy 60.87205 -431.648192) (xy 60.883635 -431.701441) (xy 60.887523 -431.755798) (xy 61.2657 -431.755798)
			(xy 61.269588 -431.701446) (xy 61.281171 -431.648201) (xy 61.300214 -431.597147) (xy 61.32633 -431.549322)
			(xy 61.358985 -431.505701) (xy 61.397517 -431.467172) (xy 61.44114 -431.434519) (xy 61.488965 -431.408406)
			(xy 61.540021 -431.389365) (xy 61.593266 -431.377785) (xy 61.647618 -431.3739) (xy 61.701969 -431.37779)
			(xy 61.755214 -431.389375) (xy 61.806267 -431.408421) (xy 61.854091 -431.434538) (xy 61.876178 -431.450496)
			(xy 61.89519 -431.464092) (xy 61.937073 -431.484824) (xy 61.982041 -431.49755) (xy 62.028578 -431.50184)
			(xy 62.075115 -431.49755) (xy 62.120083 -431.484824) (xy 62.161966 -431.464092) (xy 62.180978 -431.450496)
			(xy 62.203063 -431.434529) (xy 62.25089 -431.408404) (xy 62.301949 -431.389352) (xy 62.355199 -431.377761)
			(xy 62.409557 -431.373867) (xy 62.463916 -431.377749) (xy 62.517169 -431.389328) (xy 62.568232 -431.408368)
			(xy 62.616065 -431.434482) (xy 62.659694 -431.467138) (xy 62.698232 -431.505671) (xy 62.730893 -431.549297)
			(xy 62.757013 -431.597127) (xy 62.776059 -431.648188) (xy 62.787645 -431.701439) (xy 62.791533 -431.755798)
			(xy 62.787645 -431.810156) (xy 62.776061 -431.863408) (xy 62.757015 -431.914469) (xy 62.730896 -431.962299)
			(xy 62.698235 -432.005925) (xy 62.659698 -432.044459) (xy 62.616069 -432.077115) (xy 62.568236 -432.10323)
			(xy 62.517173 -432.122271) (xy 62.463921 -432.13385) (xy 62.409562 -432.137733) (xy 62.355204 -432.133839)
			(xy 62.301953 -432.122249) (xy 62.250895 -432.103198) (xy 62.203067 -432.077074) (xy 62.180978 -432.061112)
			(xy 62.161966 -432.047516) (xy 62.120083 -432.026784) (xy 62.075115 -432.014058) (xy 62.028578 -432.009768)
			(xy 61.982041 -432.014058) (xy 61.937073 -432.026784) (xy 61.89519 -432.047516) (xy 61.876178 -432.061112)
			(xy 61.854087 -432.077065) (xy 61.806263 -432.103181) (xy 61.755209 -432.122226) (xy 61.701964 -432.133811)
			(xy 61.647613 -432.1377) (xy 61.593262 -432.133815) (xy 61.540016 -432.122233) (xy 61.488961 -432.103192)
			(xy 61.441135 -432.077079) (xy 61.397513 -432.044425) (xy 61.358982 -432.005895) (xy 61.326327 -431.962274)
			(xy 61.300212 -431.914449) (xy 61.28117 -431.863394) (xy 61.269587 -431.810149) (xy 61.2657 -431.755798)
			(xy 60.887523 -431.755798) (xy 60.883636 -431.810154) (xy 60.872052 -431.863403) (xy 60.853007 -431.914462)
			(xy 60.826889 -431.962291) (xy 60.794231 -432.005916) (xy 60.755695 -432.044448) (xy 60.712069 -432.077104)
			(xy 60.664238 -432.103218) (xy 60.613178 -432.122259) (xy 60.559927 -432.13384) (xy 60.505571 -432.137723)
			(xy 60.451215 -432.133831) (xy 60.397966 -432.122243) (xy 60.346909 -432.103194) (xy 60.299083 -432.077072)
			(xy 60.276994 -432.061112) (xy 60.257982 -432.047516) (xy 60.216099 -432.026784) (xy 60.171131 -432.014058)
			(xy 60.124594 -432.009768) (xy 60.078057 -432.014058) (xy 60.033089 -432.026784) (xy 59.991206 -432.047516)
			(xy 59.972194 -432.061112) (xy 59.950102 -432.077066) (xy 59.902277 -432.103185) (xy 59.851222 -432.122232)
			(xy 59.797976 -432.133819) (xy 59.743622 -432.13771) (xy 59.689268 -432.133825) (xy 59.636021 -432.122245)
			(xy 59.584963 -432.103204) (xy 59.537135 -432.07709) (xy 59.493511 -432.044435) (xy 59.454978 -432.005904)
			(xy 59.422321 -431.962282) (xy 59.396204 -431.914455) (xy 59.377161 -431.863398) (xy 59.365578 -431.810151)
			(xy 59.36169 -431.755798) (xy 58.646548 -431.755798) (xy 58.64266 -431.81016) (xy 58.631075 -431.863415)
			(xy 58.612027 -431.914479) (xy 58.585906 -431.962312) (xy 58.553243 -432.00594) (xy 58.514702 -432.044476)
			(xy 58.471069 -432.077133) (xy 58.423233 -432.103248) (xy 58.372166 -432.122289) (xy 58.31891 -432.133868)
			(xy 58.264547 -432.137748) (xy 58.210186 -432.133853) (xy 58.156932 -432.122259) (xy 58.105871 -432.103204)
			(xy 58.058042 -432.077076) (xy 58.035952 -432.061112) (xy 58.01694 -432.047516) (xy 57.975057 -432.026784)
			(xy 57.930089 -432.014058) (xy 57.883552 -432.009768) (xy 57.837015 -432.014058) (xy 57.792047 -432.026784)
			(xy 57.750164 -432.047516) (xy 57.731152 -432.061112) (xy 57.709061 -432.077062) (xy 57.661239 -432.103175)
			(xy 57.610188 -432.122216) (xy 57.556946 -432.133798) (xy 57.502598 -432.137685) (xy 57.44825 -432.133797)
			(xy 57.395009 -432.122215) (xy 57.343958 -432.103174) (xy 57.296136 -432.077061) (xy 57.252517 -432.044408)
			(xy 57.21399 -432.00588) (xy 57.181337 -431.962261) (xy 57.155225 -431.914439) (xy 57.136184 -431.863387)
			(xy 57.124602 -431.810146) (xy 57.120715 -431.755798) (xy 56.759696 -431.755798) (xy 56.755809 -431.810148)
			(xy 56.744227 -431.863391) (xy 56.725185 -431.914444) (xy 56.699071 -431.962268) (xy 56.666418 -432.005889)
			(xy 56.627888 -432.044418) (xy 56.584268 -432.077072) (xy 56.536444 -432.103185) (xy 56.485391 -432.122227)
			(xy 56.432147 -432.133809) (xy 56.377797 -432.137696) (xy 56.323447 -432.133808) (xy 56.270204 -432.122225)
			(xy 56.219151 -432.103183) (xy 56.171328 -432.077069) (xy 56.14924 -432.061112) (xy 56.130228 -432.047516)
			(xy 56.088345 -432.026784) (xy 56.043377 -432.014058) (xy 55.99684 -432.009768) (xy 55.950303 -432.014058)
			(xy 55.905335 -432.026784) (xy 55.863452 -432.047516) (xy 55.84444 -432.061112) (xy 55.822347 -432.07707)
			(xy 55.774519 -432.103197) (xy 55.723459 -432.12225) (xy 55.670208 -432.133842) (xy 55.615848 -432.137737)
			(xy 55.561488 -432.133856) (xy 55.508233 -432.122277) (xy 55.457169 -432.103237) (xy 55.409334 -432.077122)
			(xy 55.365703 -432.044466) (xy 55.327165 -432.005931) (xy 55.294503 -431.962304) (xy 55.268382 -431.914473)
			(xy 55.249336 -431.863411) (xy 55.237751 -431.810158) (xy 55.233863 -431.755798) (xy 29.40431 -431.755798)
			(xy 29.40431 -433.796871) (xy 55.233898 -433.796871) (xy 55.23779 -433.742517) (xy 55.249378 -433.689269)
			(xy 55.268427 -433.638213) (xy 55.294549 -433.590388) (xy 55.327212 -433.546768) (xy 55.36575 -433.508241)
			(xy 55.40938 -433.47559) (xy 55.457212 -433.449482) (xy 55.508273 -433.430448) (xy 55.561524 -433.418874)
			(xy 55.61588 -433.414998) (xy 55.670234 -433.418897) (xy 55.723479 -433.430493) (xy 55.774533 -433.449548)
			(xy 55.822354 -433.475677) (xy 55.84444 -433.49164) (xy 55.863452 -433.505236) (xy 55.905335 -433.525968)
			(xy 55.950303 -433.538694) (xy 55.99684 -433.542984) (xy 56.043377 -433.538694) (xy 56.088345 -433.525968)
			(xy 56.130228 -433.505236) (xy 56.14924 -433.49164) (xy 56.171282 -433.475619) (xy 56.219108 -433.449498)
			(xy 56.270164 -433.43045) (xy 56.323411 -433.418861) (xy 56.377766 -433.414969) (xy 56.432121 -433.418852)
			(xy 56.485371 -433.430431) (xy 56.53643 -433.44947) (xy 56.58426 -433.475582) (xy 56.627888 -433.508235)
			(xy 56.666424 -433.546765) (xy 56.699084 -433.590387) (xy 56.725204 -433.638213) (xy 56.744252 -433.689269)
			(xy 56.755839 -433.742517) (xy 56.759731 -433.796871) (xy 57.120751 -433.796871) (xy 57.124641 -433.742529)
			(xy 57.136226 -433.689293) (xy 57.15527 -433.638248) (xy 57.181384 -433.590432) (xy 57.214037 -433.54682)
			(xy 57.252564 -433.508298) (xy 57.296181 -433.475652) (xy 57.344001 -433.449545) (xy 57.395049 -433.43051)
			(xy 57.448286 -433.418933) (xy 57.50263 -433.415051) (xy 57.556972 -433.418942) (xy 57.610208 -433.430527)
			(xy 57.661253 -433.44957) (xy 57.709068 -433.475684) (xy 57.731152 -433.49164) (xy 57.750164 -433.505236)
			(xy 57.792047 -433.525968) (xy 57.837015 -433.538694) (xy 57.883552 -433.542984) (xy 57.930089 -433.538694)
			(xy 57.975057 -433.525968) (xy 58.01694 -433.505236) (xy 58.035952 -433.49164) (xy 58.057996 -433.475611)
			(xy 58.105828 -433.449477) (xy 58.156892 -433.430416) (xy 58.21015 -433.418817) (xy 58.264516 -433.414916)
			(xy 58.318884 -433.418793) (xy 58.372146 -433.430368) (xy 58.423219 -433.449407) (xy 58.471062 -433.47552)
			(xy 58.514702 -433.508177) (xy 58.553249 -433.546713) (xy 58.585919 -433.590343) (xy 58.612046 -433.638178)
			(xy 58.6311 -433.689245) (xy 58.642691 -433.742505) (xy 58.646584 -433.796871) (xy 59.361725 -433.796871)
			(xy 59.365617 -433.742523) (xy 59.377203 -433.689282) (xy 59.396249 -433.638231) (xy 59.422367 -433.590411)
			(xy 59.455025 -433.546795) (xy 59.493557 -433.508271) (xy 59.53718 -433.475623) (xy 59.585006 -433.449515)
			(xy 59.63606 -433.43048) (xy 59.689304 -433.418905) (xy 59.743653 -433.415026) (xy 59.798002 -433.41892)
			(xy 59.851242 -433.43051) (xy 59.902291 -433.44956) (xy 59.950109 -433.47568) (xy 59.972194 -433.49164)
			(xy 59.991206 -433.505236) (xy 60.033089 -433.525968) (xy 60.078057 -433.538694) (xy 60.124594 -433.542984)
			(xy 60.171131 -433.538694) (xy 60.216099 -433.525968) (xy 60.257982 -433.505236) (xy 60.276994 -433.49164)
			(xy 60.299037 -433.475615) (xy 60.346866 -433.449487) (xy 60.397927 -433.430432) (xy 60.451179 -433.418838)
			(xy 60.50554 -433.414941) (xy 60.559902 -433.418821) (xy 60.613158 -433.430398) (xy 60.664224 -433.449437)
			(xy 60.712061 -433.47555) (xy 60.755695 -433.508205) (xy 60.794237 -433.546738) (xy 60.826902 -433.590364)
			(xy 60.853026 -433.638195) (xy 60.872077 -433.689257) (xy 60.883666 -433.74251) (xy 60.887559 -433.796871)
			(xy 61.265735 -433.796871) (xy 61.269626 -433.742525) (xy 61.281212 -433.689286) (xy 61.300257 -433.638238)
			(xy 61.326373 -433.590419) (xy 61.359029 -433.546805) (xy 61.39756 -433.508281) (xy 61.441181 -433.475634)
			(xy 61.489004 -433.449527) (xy 61.540056 -433.430492) (xy 61.593297 -433.418916) (xy 61.647644 -433.415035)
			(xy 61.70199 -433.418928) (xy 61.755229 -433.430517) (xy 61.806277 -433.449564) (xy 61.854094 -433.475682)
			(xy 61.876178 -433.49164) (xy 61.89519 -433.505236) (xy 61.937073 -433.525968) (xy 61.982041 -433.538694)
			(xy 62.028578 -433.542984) (xy 62.075115 -433.538694) (xy 62.120083 -433.525968) (xy 62.161966 -433.505236)
			(xy 62.180978 -433.49164) (xy 62.203022 -433.475613) (xy 62.250852 -433.449483) (xy 62.301914 -433.430426)
			(xy 62.355168 -433.41883) (xy 62.409531 -433.414932) (xy 62.463895 -433.41881) (xy 62.517153 -433.430387)
			(xy 62.568222 -433.449425) (xy 62.616062 -433.475538) (xy 62.659697 -433.508194) (xy 62.698241 -433.546728)
			(xy 62.730908 -433.590356) (xy 62.757034 -433.638188) (xy 62.776086 -433.689252) (xy 62.787676 -433.742508)
			(xy 62.791568 -433.796871) (xy 62.787684 -433.851235) (xy 62.776102 -433.904492) (xy 62.757058 -433.955559)
			(xy 62.73094 -434.003396) (xy 62.698279 -434.047028) (xy 62.659741 -434.085568) (xy 62.61611 -434.11823)
			(xy 62.568275 -434.144351) (xy 62.517209 -434.163397) (xy 62.463952 -434.174981) (xy 62.409588 -434.178868)
			(xy 62.355225 -434.174978) (xy 62.301969 -434.16339) (xy 62.250904 -434.144341) (xy 62.20307 -434.118218)
			(xy 62.180978 -434.102256) (xy 62.161966 -434.08866) (xy 62.120083 -434.067928) (xy 62.075115 -434.055202)
			(xy 62.028578 -434.050912) (xy 61.982041 -434.055202) (xy 61.937073 -434.067928) (xy 61.89519 -434.08866)
			(xy 61.876178 -434.102256) (xy 61.854045 -434.118149) (xy 61.806224 -434.14426) (xy 61.755174 -434.1633)
			(xy 61.701933 -434.17488) (xy 61.647587 -434.178765) (xy 61.59324 -434.174876) (xy 61.540001 -434.163292)
			(xy 61.488952 -434.144249) (xy 61.441132 -434.118135) (xy 61.397516 -434.085481) (xy 61.358992 -434.046952)
			(xy 61.326342 -434.003332) (xy 61.300233 -433.95551) (xy 61.281196 -433.904459) (xy 61.269618 -433.851218)
			(xy 61.265735 -433.796871) (xy 60.887559 -433.796871) (xy 60.883674 -433.851233) (xy 60.872093 -433.904488)
			(xy 60.85305 -433.955553) (xy 60.826933 -434.003388) (xy 60.794275 -434.047019) (xy 60.755738 -434.085557)
			(xy 60.71211 -434.118219) (xy 60.664277 -434.144339) (xy 60.613213 -434.163386) (xy 60.559959 -434.174971)
			(xy 60.505597 -434.178859) (xy 60.451236 -434.17497) (xy 60.397982 -434.163384) (xy 60.346918 -434.144337)
			(xy 60.299086 -434.118216) (xy 60.276994 -434.102256) (xy 60.257982 -434.08866) (xy 60.216099 -434.067928)
			(xy 60.171131 -434.055202) (xy 60.124594 -434.050912) (xy 60.078057 -434.055202) (xy 60.033089 -434.067928)
			(xy 59.991206 -434.08866) (xy 59.972194 -434.102256) (xy 59.950061 -434.118151) (xy 59.902239 -434.144264)
			(xy 59.851187 -434.163306) (xy 59.797944 -434.174888) (xy 59.743596 -434.178775) (xy 59.689247 -434.174887)
			(xy 59.636005 -434.163303) (xy 59.584954 -434.144261) (xy 59.537132 -434.118146) (xy 59.493514 -434.085491)
			(xy 59.454987 -434.046961) (xy 59.422336 -434.00334) (xy 59.396226 -433.955516) (xy 59.377187 -433.904463)
			(xy 59.365609 -433.85122) (xy 59.361725 -433.796871) (xy 58.646584 -433.796871) (xy 58.642699 -433.851238)
			(xy 58.631116 -433.904499) (xy 58.61207 -433.955569) (xy 58.58595 -434.003409) (xy 58.553286 -434.047043)
			(xy 58.514745 -434.085585) (xy 58.471111 -434.118249) (xy 58.423271 -434.144369) (xy 58.372201 -434.163415)
			(xy 58.318941 -434.174999) (xy 58.264573 -434.178884) (xy 58.210207 -434.174991) (xy 58.156948 -434.1634)
			(xy 58.10588 -434.144347) (xy 58.058045 -434.11822) (xy 58.035952 -434.102256) (xy 58.01694 -434.08866)
			(xy 57.975057 -434.067928) (xy 57.930089 -434.055202) (xy 57.883552 -434.050912) (xy 57.837015 -434.055202)
			(xy 57.792047 -434.067928) (xy 57.750164 -434.08866) (xy 57.731152 -434.102256) (xy 57.70902 -434.118147)
			(xy 57.661201 -434.144254) (xy 57.610153 -434.16329) (xy 57.556915 -434.174867) (xy 57.502572 -434.178749)
			(xy 57.448229 -434.174859) (xy 57.394994 -434.163274) (xy 57.343948 -434.144231) (xy 57.296133 -434.118117)
			(xy 57.25252 -434.085464) (xy 57.213999 -434.046937) (xy 57.181352 -434.003319) (xy 57.155246 -433.9555)
			(xy 57.13621 -433.904452) (xy 57.124633 -433.851214) (xy 57.120751 -433.796871) (xy 56.759731 -433.796871)
			(xy 56.755847 -433.851226) (xy 56.744268 -433.904476) (xy 56.725228 -433.955535) (xy 56.699115 -434.003365)
			(xy 56.666461 -434.046992) (xy 56.627931 -434.085527) (xy 56.584309 -434.118187) (xy 56.536483 -434.144306)
			(xy 56.485426 -434.163353) (xy 56.432178 -434.17494) (xy 56.377824 -434.178831) (xy 56.323468 -434.174947)
			(xy 56.270219 -434.163366) (xy 56.21916 -434.144326) (xy 56.171331 -434.118212) (xy 56.14924 -434.102256)
			(xy 56.130228 -434.08866) (xy 56.088345 -434.067928) (xy 56.043377 -434.055202) (xy 55.99684 -434.050912)
			(xy 55.950303 -434.055202) (xy 55.905335 -434.067928) (xy 55.863452 -434.08866) (xy 55.84444 -434.102256)
			(xy 55.822306 -434.118155) (xy 55.77448 -434.144275) (xy 55.723424 -434.163324) (xy 55.670177 -434.174911)
			(xy 55.615822 -434.178802) (xy 55.561467 -434.174917) (xy 55.508218 -434.163336) (xy 55.45716 -434.144294)
			(xy 55.409331 -434.118178) (xy 55.365706 -434.085522) (xy 55.327174 -434.046988) (xy 55.294518 -434.003363)
			(xy 55.268403 -433.955534) (xy 55.249362 -433.904475) (xy 55.237782 -433.851226) (xy 55.233898 -433.796871)
			(xy 29.40431 -433.796871) (xy 29.40431 -435.706816) (xy 55.233839 -435.706816) (xy 55.237725 -435.652452)
			(xy 55.249309 -435.599195) (xy 55.268355 -435.548129) (xy 55.294475 -435.500294) (xy 55.327138 -435.456663)
			(xy 55.365678 -435.418125) (xy 55.40931 -435.385465) (xy 55.457147 -435.359347) (xy 55.508214 -435.340303)
			(xy 55.561472 -435.328722) (xy 55.615835 -435.324839) (xy 55.670198 -435.328732) (xy 55.723454 -435.340323)
			(xy 55.774517 -435.359376) (xy 55.822349 -435.385503) (xy 55.84444 -435.401466) (xy 55.863452 -435.415062)
			(xy 55.905335 -435.435794) (xy 55.950303 -435.44852) (xy 55.99684 -435.45281) (xy 56.043377 -435.44852)
			(xy 56.088345 -435.435794) (xy 56.130228 -435.415062) (xy 56.14924 -435.401466) (xy 56.171352 -435.385545)
			(xy 56.219173 -435.359434) (xy 56.270223 -435.340394) (xy 56.323464 -435.328814) (xy 56.37781 -435.324928)
			(xy 56.432157 -435.328817) (xy 56.485397 -435.3404) (xy 56.536446 -435.359442) (xy 56.584266 -435.385556)
			(xy 56.627882 -435.418209) (xy 56.666408 -435.456737) (xy 56.699058 -435.500356) (xy 56.725169 -435.548178)
			(xy 56.744207 -435.599228) (xy 56.755787 -435.652469) (xy 56.759672 -435.706816) (xy 57.120691 -435.706816)
			(xy 57.124576 -435.652464) (xy 57.136157 -435.599219) (xy 57.155197 -435.548163) (xy 57.18131 -435.500338)
			(xy 57.213963 -435.456715) (xy 57.252492 -435.418183) (xy 57.296112 -435.385526) (xy 57.343936 -435.35941)
			(xy 57.39499 -435.340366) (xy 57.448234 -435.328781) (xy 57.502585 -435.324891) (xy 57.556937 -435.328777)
			(xy 57.610182 -435.340357) (xy 57.661237 -435.359398) (xy 57.709063 -435.38551) (xy 57.731152 -435.401466)
			(xy 57.750164 -435.415062) (xy 57.792047 -435.435794) (xy 57.837015 -435.44852) (xy 57.883552 -435.45281)
			(xy 57.930089 -435.44852) (xy 57.975057 -435.435794) (xy 58.01694 -435.415062) (xy 58.035952 -435.401466)
			(xy 58.058066 -435.385537) (xy 58.105893 -435.359412) (xy 58.156952 -435.34036) (xy 58.210202 -435.328769)
			(xy 58.26456 -435.324876) (xy 58.318919 -435.328758) (xy 58.372172 -435.340338) (xy 58.423235 -435.359379)
			(xy 58.471067 -435.385494) (xy 58.514696 -435.418151) (xy 58.553233 -435.456685) (xy 58.585893 -435.500312)
			(xy 58.612011 -435.548143) (xy 58.631055 -435.599205) (xy 58.642639 -435.652457) (xy 58.646524 -435.706816)
			(xy 59.361666 -435.706816) (xy 59.365552 -435.652458) (xy 59.377134 -435.599208) (xy 59.396177 -435.548147)
			(xy 59.422293 -435.500317) (xy 59.454951 -435.45669) (xy 59.493485 -435.418155) (xy 59.537111 -435.385497)
			(xy 59.584941 -435.35938) (xy 59.636001 -435.340336) (xy 59.689252 -435.328753) (xy 59.743609 -435.324866)
			(xy 59.797966 -435.328755) (xy 59.851216 -435.340341) (xy 59.902275 -435.359387) (xy 59.950104 -435.385507)
			(xy 59.972194 -435.401466) (xy 59.991206 -435.415062) (xy 60.033089 -435.435794) (xy 60.078057 -435.44852)
			(xy 60.124594 -435.45281) (xy 60.171131 -435.44852) (xy 60.216099 -435.435794) (xy 60.257982 -435.415062)
			(xy 60.276994 -435.401466) (xy 60.299107 -435.385541) (xy 60.346931 -435.359422) (xy 60.397986 -435.340376)
			(xy 60.451232 -435.328791) (xy 60.505584 -435.324901) (xy 60.559937 -435.328786) (xy 60.613184 -435.340367)
			(xy 60.66424 -435.359409) (xy 60.712067 -435.385523) (xy 60.75569 -435.418179) (xy 60.794221 -435.45671)
			(xy 60.826876 -435.500333) (xy 60.852991 -435.54816) (xy 60.872032 -435.599216) (xy 60.883614 -435.652463)
			(xy 60.887499 -435.706816) (xy 61.265676 -435.706816) (xy 61.269561 -435.652461) (xy 61.281143 -435.599212)
			(xy 61.300185 -435.548153) (xy 61.3263 -435.500325) (xy 61.358955 -435.456699) (xy 61.397487 -435.418166)
			(xy 61.441111 -435.385508) (xy 61.488939 -435.359391) (xy 61.539997 -435.340347) (xy 61.593245 -435.328763)
			(xy 61.6476 -435.324876) (xy 61.701955 -435.328763) (xy 61.755203 -435.340347) (xy 61.806261 -435.359391)
			(xy 61.854088 -435.385508) (xy 61.876178 -435.401466) (xy 61.89519 -435.415062) (xy 61.937073 -435.435794)
			(xy 61.982041 -435.44852) (xy 62.028578 -435.45281) (xy 62.075115 -435.44852) (xy 62.120083 -435.435794)
			(xy 62.161966 -435.415062) (xy 62.180978 -435.401466) (xy 62.203091 -435.385539) (xy 62.250917 -435.359418)
			(xy 62.301973 -435.34037) (xy 62.35522 -435.328782) (xy 62.409575 -435.324891) (xy 62.46393 -435.328775)
			(xy 62.517179 -435.340356) (xy 62.568238 -435.359398) (xy 62.616067 -435.385512) (xy 62.659692 -435.418168)
			(xy 62.698226 -435.456701) (xy 62.730883 -435.500325) (xy 62.756998 -435.548153) (xy 62.776041 -435.599212)
			(xy 62.787623 -435.65246) (xy 62.791509 -435.706816) (xy 62.787619 -435.76117) (xy 62.776032 -435.814418)
			(xy 62.756985 -435.865475) (xy 62.730866 -435.913301) (xy 62.698205 -435.956923) (xy 62.659669 -435.995452)
			(xy 62.616041 -436.028105) (xy 62.56821 -436.054215) (xy 62.517149 -436.073253) (xy 62.463899 -436.084829)
			(xy 62.409544 -436.088709) (xy 62.355189 -436.084813) (xy 62.301943 -436.073221) (xy 62.250888 -436.054169)
			(xy 62.203065 -436.028044) (xy 62.180978 -436.012082) (xy 62.161966 -435.998486) (xy 62.120083 -435.977754)
			(xy 62.075115 -435.965028) (xy 62.028578 -435.960738) (xy 61.982041 -435.965028) (xy 61.937073 -435.977754)
			(xy 61.89519 -435.998486) (xy 61.876178 -436.012082) (xy 61.854115 -436.028075) (xy 61.806289 -436.054196)
			(xy 61.755233 -436.073244) (xy 61.701986 -436.084832) (xy 61.647631 -436.088724) (xy 61.593276 -436.084841)
			(xy 61.540027 -436.073262) (xy 61.488967 -436.054222) (xy 61.441138 -436.028109) (xy 61.397511 -435.995455)
			(xy 61.358976 -435.956924) (xy 61.326316 -435.913302) (xy 61.300198 -435.865475) (xy 61.281152 -435.814418)
			(xy 61.269566 -435.76117) (xy 61.265676 -435.706816) (xy 60.887499 -435.706816) (xy 60.883609 -435.761168)
			(xy 60.872024 -435.814414) (xy 60.852978 -435.865469) (xy 60.82686 -435.913293) (xy 60.794201 -435.956913)
			(xy 60.755666 -435.995442) (xy 60.71204 -436.028093) (xy 60.664212 -436.054204) (xy 60.613154 -436.073241)
			(xy 60.559906 -436.084818) (xy 60.505553 -436.088699) (xy 60.451201 -436.084805) (xy 60.397956 -436.073215)
			(xy 60.346903 -436.054165) (xy 60.29908 -436.028043) (xy 60.276994 -436.012082) (xy 60.257982 -435.998486)
			(xy 60.216099 -435.977754) (xy 60.171131 -435.965028) (xy 60.124594 -435.960738) (xy 60.078057 -435.965028)
			(xy 60.033089 -435.977754) (xy 59.991206 -435.998486) (xy 59.972194 -436.012082) (xy 59.95013 -436.028077)
			(xy 59.902304 -436.0542) (xy 59.851246 -436.07325) (xy 59.797997 -436.08484) (xy 59.74364 -436.088734)
			(xy 59.689283 -436.084852) (xy 59.636031 -436.073273) (xy 59.584969 -436.054233) (xy 59.537137 -436.02812)
			(xy 59.493509 -435.995465) (xy 59.454971 -435.956934) (xy 59.42231 -435.91331) (xy 59.39619 -435.865481)
			(xy 59.377143 -435.814422) (xy 59.365556 -435.761173) (xy 59.361666 -435.706816) (xy 58.646524 -435.706816)
			(xy 58.642634 -435.761174) (xy 58.631047 -435.814425) (xy 58.611998 -435.865485) (xy 58.585876 -435.913314)
			(xy 58.553213 -435.956938) (xy 58.514673 -435.995469) (xy 58.471041 -436.028123) (xy 58.423206 -436.054234)
			(xy 58.372142 -436.073271) (xy 58.318888 -436.084846) (xy 58.264529 -436.088724) (xy 58.210171 -436.084826)
			(xy 58.156922 -436.073231) (xy 58.105865 -436.054175) (xy 58.058039 -436.028046) (xy 58.035952 -436.012082)
			(xy 58.01694 -435.998486) (xy 57.975057 -435.977754) (xy 57.930089 -435.965028) (xy 57.883552 -435.960738)
			(xy 57.837015 -435.965028) (xy 57.792047 -435.977754) (xy 57.750164 -435.998486) (xy 57.731152 -436.012082)
			(xy 57.709089 -436.028073) (xy 57.661266 -436.054189) (xy 57.610212 -436.073234) (xy 57.556967 -436.084819)
			(xy 57.502616 -436.088709) (xy 57.448265 -436.084824) (xy 57.395019 -436.073243) (xy 57.343964 -436.054203)
			(xy 57.296138 -436.028091) (xy 57.252515 -435.995438) (xy 57.213983 -435.956909) (xy 57.181327 -435.913289)
			(xy 57.15521 -435.865465) (xy 57.136166 -435.814411) (xy 57.124581 -435.761167) (xy 57.120691 -435.706816)
			(xy 56.759672 -435.706816) (xy 56.755783 -435.761162) (xy 56.744199 -435.814402) (xy 56.725156 -435.865451)
			(xy 56.699041 -435.91327) (xy 56.666388 -435.956886) (xy 56.627859 -435.995412) (xy 56.584239 -436.028061)
			(xy 56.536418 -436.054171) (xy 56.485367 -436.073209) (xy 56.432126 -436.084788) (xy 56.377779 -436.088672)
			(xy 56.323433 -436.084782) (xy 56.270193 -436.073197) (xy 56.219144 -436.054153) (xy 56.171325 -436.028039)
			(xy 56.14924 -436.012082) (xy 56.130228 -435.998486) (xy 56.088345 -435.977754) (xy 56.043377 -435.965028)
			(xy 55.99684 -435.960738) (xy 55.950303 -435.965028) (xy 55.905335 -435.977754) (xy 55.863452 -435.998486)
			(xy 55.84444 -436.012082) (xy 55.822375 -436.02808) (xy 55.774545 -436.054211) (xy 55.723484 -436.073268)
			(xy 55.670229 -436.084863) (xy 55.615866 -436.088761) (xy 55.561502 -436.084882) (xy 55.508244 -436.073305)
			(xy 55.457175 -436.054266) (xy 55.409336 -436.028152) (xy 55.365701 -435.995495) (xy 55.327158 -435.956961)
			(xy 55.294492 -435.913333) (xy 55.268368 -435.865499) (xy 55.249318 -435.814435) (xy 55.237729 -435.761179)
			(xy 55.233839 -435.706816) (xy 29.40431 -435.706816) (xy 29.40431 -438.63641) (xy 69.266308 -438.63641)
			(xy 69.266308 -437.691784) (xy 69.26681 -437.659823) (xy 69.274821 -437.596405) (xy 69.290718 -437.534491)
			(xy 69.31425 -437.475058) (xy 69.345044 -437.419043) (xy 69.382617 -437.367328) (xy 69.426374 -437.320731)
			(xy 69.475627 -437.279986) (xy 69.529598 -437.245735) (xy 69.587437 -437.218518) (xy 69.64823 -437.198765)
			(xy 69.71102 -437.186787) (xy 69.774816 -437.182774) (xy 69.838612 -437.186787) (xy 69.901402 -437.198765)
			(xy 69.962195 -437.218518) (xy 70.020034 -437.245735) (xy 70.074005 -437.279986) (xy 70.123258 -437.320731)
			(xy 70.167015 -437.367328) (xy 70.204588 -437.419043) (xy 70.235382 -437.475058) (xy 70.258914 -437.534491)
			(xy 70.274811 -437.596405) (xy 70.282822 -437.659823) (xy 70.283324 -437.691784) (xy 70.283324 -437.76011)
			(xy 70.357492 -437.834278) (xy 70.410324 -437.834278) (xy 70.426351 -437.833722) (xy 70.45739 -437.825725)
			(xy 70.485455 -437.81024) (xy 70.508773 -437.788247) (xy 70.525871 -437.761135) (xy 70.535668 -437.730616)
			(xy 70.53707 -437.714644) (xy 70.53707 -437.71439) (xy 70.53936 -437.682975) (xy 70.550648 -437.621007)
			(xy 70.569507 -437.560908) (xy 70.595648 -437.5036) (xy 70.628669 -437.449961) (xy 70.668064 -437.400814)
			(xy 70.713231 -437.35691) (xy 70.763476 -437.318925) (xy 70.81803 -437.287438) (xy 70.876056 -437.262934)
			(xy 70.936666 -437.245787) (xy 70.998929 -437.236261) (xy 71.061893 -437.234501) (xy 71.124591 -437.240534)
			(xy 71.186064 -437.254269) (xy 71.245369 -437.275493) (xy 71.301596 -437.303883) (xy 71.353885 -437.339003)
			(xy 71.401433 -437.380315) (xy 71.443513 -437.427185) (xy 71.461884 -437.45277) (xy 71.474809 -437.470501)
			(xy 71.505678 -437.501676) (xy 71.541444 -437.527086) (xy 71.581042 -437.545975) (xy 71.623295 -437.557782)
			(xy 71.666949 -437.562156) (xy 71.710706 -437.558967) (xy 71.753264 -437.54831) (xy 71.79336 -437.530502)
			(xy 71.829801 -437.506071) (xy 71.861504 -437.475744) (xy 71.874888 -437.458358) (xy 71.893629 -437.433631)
			(xy 71.93627 -437.388554) (xy 71.984079 -437.349002) (xy 72.036345 -437.315561) (xy 72.092293 -437.288729)
			(xy 72.151089 -437.268904) (xy 72.211862 -437.256382) (xy 72.273706 -437.251348) (xy 72.335703 -437.253877)
			(xy 72.396932 -437.263931) (xy 72.456483 -437.281362) (xy 72.51347 -437.305909) (xy 72.567046 -437.337209)
			(xy 72.616415 -437.374795) (xy 72.660844 -437.41811) (xy 72.699671 -437.46651) (xy 72.71639 -437.492648)
			(xy 72.728491 -437.511296) (xy 72.758099 -437.54445) (xy 72.793022 -437.571947) (xy 72.832198 -437.592949)
			(xy 72.87443 -437.606815) (xy 72.91843 -437.613121) (xy 72.962856 -437.611676) (xy 73.006354 -437.602523)
			(xy 73.047595 -437.585942) (xy 73.085323 -437.562439) (xy 73.118386 -437.53273) (xy 73.132442 -437.515508)
			(xy 73.152167 -437.490951) (xy 73.196816 -437.446519) (xy 73.246614 -437.407945) (xy 73.300797 -437.375819)
			(xy 73.358534 -437.350635) (xy 73.41894 -437.332778) (xy 73.48109 -437.322522) (xy 73.54403 -437.320024)
			(xy 73.606798 -437.325322) (xy 73.668429 -437.338335) (xy 73.72798 -437.358864) (xy 73.784539 -437.386594)
			(xy 73.837237 -437.421101) (xy 73.885268 -437.461854) (xy 73.927895 -437.50823) (xy 73.964465 -437.559518)
			(xy 73.994417 -437.614931) (xy 74.017293 -437.673621) (xy 74.032742 -437.734687) (xy 74.040526 -437.797195)
			(xy 74.041 -437.82869) (xy 74.041 -438.63641) (xy 74.040511 -438.669137) (xy 74.032115 -438.734049)
			(xy 74.015462 -438.797349) (xy 73.990828 -438.85799) (xy 73.95862 -438.914971) (xy 73.9394 -438.941464)
			(xy 73.914 -438.975246) (xy 73.914 -438.992264) (xy 73.89876 -438.992264) (xy 73.862946 -439.022744)
			(xy 73.837769 -439.043597) (xy 73.783037 -439.079348) (xy 73.724172 -439.107787) (xy 73.662147 -439.128442)
			(xy 73.597985 -439.140973) (xy 73.532746 -439.145173) (xy 73.467507 -439.140973) (xy 73.403345 -439.128442)
			(xy 73.34132 -439.107787) (xy 73.282455 -439.079348) (xy 73.227723 -439.043597) (xy 73.202546 -439.022744)
			(xy 73.166732 -438.992264) (xy 73.151492 -438.992264) (xy 73.151492 -438.975246) (xy 73.126092 -438.941464)
			(xy 73.11644 -438.928256) (xy 73.103319 -438.910376) (xy 73.071952 -438.87903) (xy 73.035619 -438.853605)
			(xy 72.995426 -438.834872) (xy 72.95259 -438.8234) (xy 72.908414 -438.819537) (xy 72.864238 -438.8234)
			(xy 72.821402 -438.834872) (xy 72.781209 -438.853605) (xy 72.744876 -438.87903) (xy 72.713509 -438.910376)
			(xy 72.700388 -438.928256) (xy 72.690736 -438.941464) (xy 72.665336 -438.975246) (xy 72.665336 -438.992264)
			(xy 72.650096 -438.992264) (xy 72.614282 -439.022744) (xy 72.589105 -439.043597) (xy 72.534373 -439.079348)
			(xy 72.475508 -439.107787) (xy 72.413483 -439.128442) (xy 72.349321 -439.140973) (xy 72.284082 -439.145173)
			(xy 72.218843 -439.140973) (xy 72.154681 -439.128442) (xy 72.092656 -439.107787) (xy 72.033791 -439.079348)
			(xy 71.979059 -439.043597) (xy 71.953882 -439.022744) (xy 71.918068 -438.992264) (xy 71.902828 -438.992264)
			(xy 71.902828 -438.975246) (xy 71.877428 -438.941464) (xy 71.870824 -438.932574) (xy 71.857679 -438.915006)
			(xy 71.826393 -438.88425) (xy 71.790289 -438.859325) (xy 71.75044 -438.840973) (xy 71.708031 -438.829738)
			(xy 71.664322 -438.825956) (xy 71.620613 -438.829738) (xy 71.578204 -438.840973) (xy 71.538355 -438.859325)
			(xy 71.502251 -438.88425) (xy 71.470965 -438.915006) (xy 71.45782 -438.932574) (xy 71.451216 -438.941464)
			(xy 71.425816 -438.975246) (xy 71.425816 -438.992264) (xy 71.410576 -438.992264) (xy 71.374762 -439.022744)
			(xy 71.349585 -439.043597) (xy 71.294853 -439.079348) (xy 71.235988 -439.107787) (xy 71.173963 -439.128442)
			(xy 71.109801 -439.140973) (xy 71.044562 -439.145173) (xy 70.979323 -439.140973) (xy 70.915161 -439.128442)
			(xy 70.853136 -439.107787) (xy 70.794271 -439.079348) (xy 70.739539 -439.043597) (xy 70.714362 -439.022744)
			(xy 70.678548 -438.992264) (xy 70.663308 -438.992264) (xy 70.663308 -438.975246) (xy 70.637908 -438.941464)
			(xy 70.621144 -438.917842) (xy 70.608143 -438.899185) (xy 70.576642 -438.866397) (xy 70.539807 -438.839741)
			(xy 70.498815 -438.820068) (xy 70.454975 -438.808007) (xy 70.409689 -438.803943) (xy 70.364403 -438.808007)
			(xy 70.320563 -438.820068) (xy 70.279571 -438.839741) (xy 70.242736 -438.866397) (xy 70.211235 -438.899185)
			(xy 70.198234 -438.917842) (xy 70.18147 -438.941464) (xy 70.156324 -438.975246) (xy 70.156324 -438.992264)
			(xy 70.14083 -438.992264) (xy 70.105016 -439.022744) (xy 70.079839 -439.043597) (xy 70.025107 -439.079348)
			(xy 69.966242 -439.107787) (xy 69.904217 -439.128442) (xy 69.840055 -439.140973) (xy 69.774816 -439.145173)
			(xy 69.709577 -439.140973) (xy 69.645415 -439.128442) (xy 69.58339 -439.107787) (xy 69.524525 -439.079348)
			(xy 69.469793 -439.043597) (xy 69.444616 -439.022744) (xy 69.408802 -438.992264) (xy 69.393308 -438.992264)
			(xy 69.393308 -438.975246) (xy 69.368162 -438.941464) (xy 69.348897 -438.914993) (xy 69.316636 -438.858021)
			(xy 69.291954 -438.79738) (xy 69.27526 -438.734072) (xy 69.26683 -438.669146) (xy 69.266308 -438.63641)
			(xy 29.40431 -438.63641) (xy 29.40431 -438.9374) (xy 51.342544 -438.9374) (xy 52.994052 -438.9374)
			(xy 52.994052 -440.588908) (xy 51.342544 -440.588908) (xy 51.342544 -438.9374) (xy 29.40431 -438.9374)
			(xy 29.40431 -440.157362) (xy 41.72661 -440.157362) (xy 41.730681 -440.10174) (xy 41.742807 -440.047303)
			(xy 41.76273 -439.995212) (xy 41.790026 -439.946577) (xy 41.824112 -439.902434) (xy 41.864261 -439.863725)
			(xy 41.909619 -439.831274) (xy 41.959219 -439.805773) (xy 42.012003 -439.787766) (xy 42.066846 -439.777636)
			(xy 42.12258 -439.775599) (xy 42.178017 -439.781699) (xy 42.231974 -439.795805) (xy 42.250574 -439.803709)
			(xy 47.842668 -439.803709) (xy 47.842668 -439.722599) (xy 47.850618 -439.64188) (xy 47.866441 -439.562329)
			(xy 47.889986 -439.484713) (xy 47.921025 -439.409777) (xy 47.95926 -439.338245) (xy 48.004322 -439.270805)
			(xy 48.055777 -439.208106) (xy 48.11313 -439.150753) (xy 48.175829 -439.099298) (xy 48.243269 -439.054236)
			(xy 48.314801 -439.016001) (xy 48.389737 -438.984962) (xy 48.467353 -438.961417) (xy 48.546904 -438.945594)
			(xy 48.627623 -438.937644) (xy 48.708733 -438.937644) (xy 48.789452 -438.945594) (xy 48.869003 -438.961417)
			(xy 48.946619 -438.984962) (xy 49.021555 -439.016001) (xy 49.093087 -439.054236) (xy 49.160527 -439.099298)
			(xy 49.223226 -439.150753) (xy 49.280579 -439.208106) (xy 49.332034 -439.270805) (xy 49.377096 -439.338245)
			(xy 49.415331 -439.409777) (xy 49.44637 -439.484713) (xy 49.469915 -439.562329) (xy 49.485738 -439.64188)
			(xy 49.493688 -439.722599) (xy 49.494186 -439.763154) (xy 49.493688 -439.803709) (xy 49.485738 -439.884428)
			(xy 49.469915 -439.963979) (xy 49.44637 -440.041595) (xy 49.415331 -440.116531) (xy 49.377096 -440.188063)
			(xy 49.332034 -440.255503) (xy 49.280579 -440.318202) (xy 49.223226 -440.375555) (xy 49.160527 -440.42701)
			(xy 49.093087 -440.472072) (xy 49.021555 -440.510307) (xy 48.946619 -440.541346) (xy 48.869003 -440.564891)
			(xy 48.789452 -440.580714) (xy 48.708733 -440.588664) (xy 48.627623 -440.588664) (xy 48.546904 -440.580714)
			(xy 48.467353 -440.564891) (xy 48.389737 -440.541346) (xy 48.314801 -440.510307) (xy 48.243269 -440.472072)
			(xy 48.175829 -440.42701) (xy 48.11313 -440.375555) (xy 48.055777 -440.318202) (xy 48.004322 -440.255503)
			(xy 47.95926 -440.188063) (xy 47.921025 -440.116531) (xy 47.889986 -440.041595) (xy 47.866441 -439.963979)
			(xy 47.850618 -439.884428) (xy 47.842668 -439.803709) (xy 42.250574 -439.803709) (xy 42.283303 -439.817617)
			(xy 42.330909 -439.846671) (xy 42.373777 -439.882346) (xy 42.410994 -439.923883) (xy 42.441767 -439.970396)
			(xy 42.465439 -440.020893) (xy 42.481507 -440.0743) (xy 42.489627 -440.129476) (xy 42.490136 -440.157362)
			(xy 42.489627 -440.185248) (xy 42.481507 -440.240424) (xy 42.465439 -440.293831) (xy 42.441767 -440.344328)
			(xy 42.410994 -440.390841) (xy 42.373777 -440.432378) (xy 42.330909 -440.468053) (xy 42.283303 -440.497107)
			(xy 42.231974 -440.518919) (xy 42.178017 -440.533025) (xy 42.12258 -440.539125) (xy 42.066846 -440.537088)
			(xy 42.012003 -440.526958) (xy 41.959219 -440.508951) (xy 41.909619 -440.48345) (xy 41.864261 -440.450999)
			(xy 41.824112 -440.41229) (xy 41.790026 -440.368147) (xy 41.76273 -440.319512) (xy 41.742807 -440.267421)
			(xy 41.730681 -440.212984) (xy 41.72661 -440.157362) (xy 29.40431 -440.157362) (xy 29.40431 -440.75096)
			(xy 39.288464 -440.75096) (xy 39.292535 -440.695338) (xy 39.304661 -440.640901) (xy 39.324584 -440.58881)
			(xy 39.35188 -440.540175) (xy 39.385966 -440.496032) (xy 39.426115 -440.457323) (xy 39.471473 -440.424872)
			(xy 39.521073 -440.399371) (xy 39.573857 -440.381364) (xy 39.6287 -440.371234) (xy 39.684434 -440.369197)
			(xy 39.739871 -440.375297) (xy 39.793828 -440.389403) (xy 39.845157 -440.411215) (xy 39.892763 -440.440269)
			(xy 39.935631 -440.475944) (xy 39.972848 -440.517481) (xy 40.003621 -440.563994) (xy 40.027293 -440.614491)
			(xy 40.043361 -440.667898) (xy 40.051481 -440.723074) (xy 40.05199 -440.75096) (xy 40.051481 -440.778846)
			(xy 40.043361 -440.834022) (xy 40.027293 -440.887429) (xy 40.003621 -440.937926) (xy 39.991032 -440.956954)
			(xy 43.660058 -440.956954) (xy 43.664129 -440.901332) (xy 43.676255 -440.846895) (xy 43.696178 -440.794804)
			(xy 43.723474 -440.746169) (xy 43.75756 -440.702026) (xy 43.797709 -440.663317) (xy 43.843067 -440.630866)
			(xy 43.892667 -440.605365) (xy 43.945451 -440.587358) (xy 44.000294 -440.577228) (xy 44.056028 -440.575191)
			(xy 44.111465 -440.581291) (xy 44.165422 -440.595397) (xy 44.216751 -440.617209) (xy 44.264357 -440.646263)
			(xy 44.307225 -440.681938) (xy 44.344442 -440.723475) (xy 44.375215 -440.769988) (xy 44.398887 -440.820485)
			(xy 44.414955 -440.873892) (xy 44.423075 -440.929068) (xy 44.423584 -440.956954) (xy 44.423075 -440.98484)
			(xy 44.414955 -441.040016) (xy 44.398887 -441.093423) (xy 44.375215 -441.14392) (xy 44.344442 -441.190433)
			(xy 44.307225 -441.23197) (xy 44.264357 -441.267645) (xy 44.216751 -441.296699) (xy 44.165422 -441.318511)
			(xy 44.111465 -441.332617) (xy 44.056028 -441.338717) (xy 44.000294 -441.33668) (xy 43.945451 -441.32655)
			(xy 43.892667 -441.308543) (xy 43.843067 -441.283042) (xy 43.797709 -441.250591) (xy 43.75756 -441.211882)
			(xy 43.723474 -441.167739) (xy 43.696178 -441.119104) (xy 43.676255 -441.067013) (xy 43.664129 -441.012576)
			(xy 43.660058 -440.956954) (xy 39.991032 -440.956954) (xy 39.972848 -440.984439) (xy 39.935631 -441.025976)
			(xy 39.892763 -441.061651) (xy 39.845157 -441.090705) (xy 39.793828 -441.112517) (xy 39.739871 -441.126623)
			(xy 39.684434 -441.132723) (xy 39.6287 -441.130686) (xy 39.573857 -441.120556) (xy 39.521073 -441.102549)
			(xy 39.471473 -441.077048) (xy 39.426115 -441.044597) (xy 39.385966 -441.005888) (xy 39.35188 -440.961745)
			(xy 39.324584 -440.91311) (xy 39.304661 -440.861019) (xy 39.292535 -440.806582) (xy 39.288464 -440.75096)
			(xy 29.40431 -440.75096) (xy 29.40431 -441.09259) (xy 29.4005 -441.0964) (xy 29.4005 -441.200286)
			(xy 37.796468 -441.200286) (xy 37.800539 -441.144664) (xy 37.812665 -441.090227) (xy 37.832588 -441.038136)
			(xy 37.859884 -440.989501) (xy 37.89397 -440.945358) (xy 37.934119 -440.906649) (xy 37.979477 -440.874198)
			(xy 38.029077 -440.848697) (xy 38.081861 -440.83069) (xy 38.136704 -440.82056) (xy 38.192438 -440.818523)
			(xy 38.247875 -440.824623) (xy 38.301832 -440.838729) (xy 38.353161 -440.860541) (xy 38.400767 -440.889595)
			(xy 38.443635 -440.92527) (xy 38.480852 -440.966807) (xy 38.511625 -441.01332) (xy 38.535297 -441.063817)
			(xy 38.551365 -441.117224) (xy 38.559485 -441.1724) (xy 38.559994 -441.200286) (xy 38.559485 -441.228172)
			(xy 38.551365 -441.283348) (xy 38.535297 -441.336755) (xy 38.526638 -441.355226) (xy 41.08526 -441.355226)
			(xy 41.089331 -441.299604) (xy 41.101457 -441.245167) (xy 41.12138 -441.193076) (xy 41.148676 -441.144441)
			(xy 41.182762 -441.100298) (xy 41.222911 -441.061589) (xy 41.268269 -441.029138) (xy 41.317869 -441.003637)
			(xy 41.370653 -440.98563) (xy 41.425496 -440.9755) (xy 41.48123 -440.973463) (xy 41.536667 -440.979563)
			(xy 41.590624 -440.993669) (xy 41.641953 -441.015481) (xy 41.689559 -441.044535) (xy 41.732427 -441.08021)
			(xy 41.769644 -441.121747) (xy 41.800417 -441.16826) (xy 41.824089 -441.218757) (xy 41.840157 -441.272164)
			(xy 41.848277 -441.32734) (xy 41.848786 -441.355226) (xy 41.848277 -441.383112) (xy 41.840157 -441.438288)
			(xy 41.824089 -441.491695) (xy 41.800417 -441.542192) (xy 41.769644 -441.588705) (xy 41.732427 -441.630242)
			(xy 41.689559 -441.665917) (xy 41.641953 -441.694971) (xy 41.590624 -441.716783) (xy 41.536667 -441.730889)
			(xy 41.48123 -441.736989) (xy 41.425496 -441.734952) (xy 41.370653 -441.724822) (xy 41.317869 -441.706815)
			(xy 41.268269 -441.681314) (xy 41.222911 -441.648863) (xy 41.182762 -441.610154) (xy 41.148676 -441.566011)
			(xy 41.12138 -441.517376) (xy 41.101457 -441.465285) (xy 41.089331 -441.410848) (xy 41.08526 -441.355226)
			(xy 38.526638 -441.355226) (xy 38.511625 -441.387252) (xy 38.480852 -441.433765) (xy 38.443635 -441.475302)
			(xy 38.400767 -441.510977) (xy 38.353161 -441.540031) (xy 38.301832 -441.561843) (xy 38.247875 -441.575949)
			(xy 38.192438 -441.582049) (xy 38.136704 -441.580012) (xy 38.081861 -441.569882) (xy 38.029077 -441.551875)
			(xy 37.979477 -441.526374) (xy 37.934119 -441.493923) (xy 37.89397 -441.455214) (xy 37.859884 -441.411071)
			(xy 37.832588 -441.362436) (xy 37.812665 -441.310345) (xy 37.800539 -441.255908) (xy 37.796468 -441.200286)
			(xy 29.4005 -441.200286) (xy 29.4005 -441.201048) (xy 29.870146 -441.670694) (xy 36.416994 -441.670694)
			(xy 36.421065 -441.615072) (xy 36.433191 -441.560635) (xy 36.453114 -441.508544) (xy 36.48041 -441.459909)
			(xy 36.514496 -441.415766) (xy 36.554645 -441.377057) (xy 36.600003 -441.344606) (xy 36.649603 -441.319105)
			(xy 36.702387 -441.301098) (xy 36.75723 -441.290968) (xy 36.812964 -441.288931) (xy 36.868401 -441.295031)
			(xy 36.922358 -441.309137) (xy 36.973687 -441.330949) (xy 37.021293 -441.360003) (xy 37.064161 -441.395678)
			(xy 37.101378 -441.437215) (xy 37.132151 -441.483728) (xy 37.155823 -441.534225) (xy 37.171891 -441.587632)
			(xy 37.180011 -441.642808) (xy 37.18052 -441.670694) (xy 37.180011 -441.69858) (xy 37.171891 -441.753756)
			(xy 37.170364 -441.758832) (xy 42.328336 -441.758832) (xy 42.332407 -441.70321) (xy 42.344533 -441.648773)
			(xy 42.364456 -441.596682) (xy 42.391752 -441.548047) (xy 42.425838 -441.503904) (xy 42.465987 -441.465195)
			(xy 42.511345 -441.432744) (xy 42.560945 -441.407243) (xy 42.613729 -441.389236) (xy 42.668572 -441.379106)
			(xy 42.724306 -441.377069) (xy 42.779743 -441.383169) (xy 42.8337 -441.397275) (xy 42.885029 -441.419087)
			(xy 42.932635 -441.448141) (xy 42.975503 -441.483816) (xy 43.01272 -441.525353) (xy 43.043493 -441.571866)
			(xy 43.067165 -441.622363) (xy 43.083233 -441.67577) (xy 43.091353 -441.730946) (xy 43.091862 -441.758832)
			(xy 43.091353 -441.786718) (xy 43.083233 -441.841894) (xy 43.067165 -441.895301) (xy 43.043493 -441.945798)
			(xy 43.01272 -441.992311) (xy 42.975503 -442.033848) (xy 42.932635 -442.069523) (xy 42.885029 -442.098577)
			(xy 42.8337 -442.120389) (xy 42.779743 -442.134495) (xy 42.724306 -442.140595) (xy 42.668572 -442.138558)
			(xy 42.613729 -442.128428) (xy 42.560945 -442.110421) (xy 42.511345 -442.08492) (xy 42.465987 -442.052469)
			(xy 42.425838 -442.01376) (xy 42.391752 -441.969617) (xy 42.364456 -441.920982) (xy 42.344533 -441.868891)
			(xy 42.332407 -441.814454) (xy 42.328336 -441.758832) (xy 37.170364 -441.758832) (xy 37.155823 -441.807163)
			(xy 37.132151 -441.85766) (xy 37.101378 -441.904173) (xy 37.064161 -441.94571) (xy 37.021293 -441.981385)
			(xy 36.973687 -442.010439) (xy 36.922358 -442.032251) (xy 36.868401 -442.046357) (xy 36.812964 -442.052457)
			(xy 36.75723 -442.05042) (xy 36.702387 -442.04029) (xy 36.649603 -442.022283) (xy 36.600003 -441.996782)
			(xy 36.554645 -441.964331) (xy 36.514496 -441.925622) (xy 36.48041 -441.881479) (xy 36.453114 -441.832844)
			(xy 36.433191 -441.780753) (xy 36.421065 -441.726316) (xy 36.416994 -441.670694) (xy 29.870146 -441.670694)
			(xy 31.79826 -443.598808) (xy 31.79826 -445.320674) (xy 81.866484 -445.320674) (xy 81.870555 -445.265052)
			(xy 81.882681 -445.210615) (xy 81.902604 -445.158524) (xy 81.9299 -445.109889) (xy 81.963986 -445.065746)
			(xy 82.004135 -445.027037) (xy 82.049493 -444.994586) (xy 82.099093 -444.969085) (xy 82.151877 -444.951078)
			(xy 82.20672 -444.940948) (xy 82.262454 -444.938911) (xy 82.317891 -444.945011) (xy 82.371848 -444.959117)
			(xy 82.423177 -444.980929) (xy 82.470783 -445.009983) (xy 82.493122 -445.028574) (xy 83.40928 -445.028574)
			(xy 83.413351 -444.972952) (xy 83.425477 -444.918515) (xy 83.4454 -444.866424) (xy 83.472696 -444.817789)
			(xy 83.506782 -444.773646) (xy 83.546931 -444.734937) (xy 83.592289 -444.702486) (xy 83.641889 -444.676985)
			(xy 83.694673 -444.658978) (xy 83.749516 -444.648848) (xy 83.80525 -444.646811) (xy 83.860687 -444.652911)
			(xy 83.914644 -444.667017) (xy 83.965973 -444.688829) (xy 84.013579 -444.717883) (xy 84.056447 -444.753558)
			(xy 84.093664 -444.795095) (xy 84.124437 -444.841608) (xy 84.148109 -444.892105) (xy 84.164177 -444.945512)
			(xy 84.172297 -445.000688) (xy 84.172806 -445.028574) (xy 84.172297 -445.05646) (xy 84.164177 -445.111636)
			(xy 84.148109 -445.165043) (xy 84.124437 -445.21554) (xy 84.093664 -445.262053) (xy 84.056447 -445.30359)
			(xy 84.013579 -445.339265) (xy 83.965973 -445.368319) (xy 83.914644 -445.390131) (xy 83.860687 -445.404237)
			(xy 83.80525 -445.410337) (xy 83.749516 -445.4083) (xy 83.694673 -445.39817) (xy 83.641889 -445.380163)
			(xy 83.592289 -445.354662) (xy 83.546931 -445.322211) (xy 83.506782 -445.283502) (xy 83.472696 -445.239359)
			(xy 83.4454 -445.190724) (xy 83.425477 -445.138633) (xy 83.413351 -445.084196) (xy 83.40928 -445.028574)
			(xy 82.493122 -445.028574) (xy 82.513651 -445.045658) (xy 82.550868 -445.087195) (xy 82.581641 -445.133708)
			(xy 82.605313 -445.184205) (xy 82.621381 -445.237612) (xy 82.629501 -445.292788) (xy 82.63001 -445.320674)
			(xy 82.629501 -445.34856) (xy 82.621381 -445.403736) (xy 82.605313 -445.457143) (xy 82.581641 -445.50764)
			(xy 82.550868 -445.554153) (xy 82.513651 -445.59569) (xy 82.470783 -445.631365) (xy 82.423177 -445.660419)
			(xy 82.371848 -445.682231) (xy 82.317891 -445.696337) (xy 82.262454 -445.702437) (xy 82.20672 -445.7004)
			(xy 82.151877 -445.69027) (xy 82.099093 -445.672263) (xy 82.049493 -445.646762) (xy 82.004135 -445.614311)
			(xy 81.963986 -445.575602) (xy 81.9299 -445.531459) (xy 81.902604 -445.482824) (xy 81.882681 -445.430733)
			(xy 81.870555 -445.376296) (xy 81.866484 -445.320674) (xy 31.79826 -445.320674) (xy 31.79826 -446.633362)
			(xy 34.599874 -446.633362) (xy 34.599874 -446.546462) (xy 34.607892 -446.459933) (xy 34.62386 -446.374513)
			(xy 34.647641 -446.290931) (xy 34.679033 -446.209899) (xy 34.717767 -446.13211) (xy 34.763514 -446.058226)
			(xy 34.815883 -445.988879) (xy 34.874427 -445.924659) (xy 34.938647 -445.866115) (xy 35.007994 -445.813746)
			(xy 35.081878 -445.767999) (xy 35.159667 -445.729265) (xy 35.240699 -445.697873) (xy 35.324281 -445.674092)
			(xy 35.409701 -445.658124) (xy 35.49623 -445.650106) (xy 35.58313 -445.650106) (xy 35.669659 -445.658124)
			(xy 35.755079 -445.674092) (xy 35.838661 -445.697873) (xy 35.919693 -445.729265) (xy 35.997482 -445.767999)
			(xy 36.071366 -445.813746) (xy 36.140713 -445.866115) (xy 36.204933 -445.924659) (xy 36.263477 -445.988879)
			(xy 36.315846 -446.058226) (xy 36.361593 -446.13211) (xy 36.400327 -446.209899) (xy 36.431719 -446.290931)
			(xy 36.4555 -446.374513) (xy 36.471468 -446.459933) (xy 36.479486 -446.546462) (xy 36.479988 -446.589912)
			(xy 36.479486 -446.633362) (xy 36.471468 -446.719891) (xy 36.4555 -446.805311) (xy 36.431719 -446.888893)
			(xy 36.400327 -446.969925) (xy 36.361593 -447.047714) (xy 36.315846 -447.121598) (xy 36.263477 -447.190945)
			(xy 36.204933 -447.255165) (xy 36.140713 -447.313709) (xy 36.071366 -447.366078) (xy 35.997482 -447.411825)
			(xy 35.919693 -447.450559) (xy 35.838661 -447.481951) (xy 35.755079 -447.505732) (xy 35.669659 -447.5217)
			(xy 35.58313 -447.529718) (xy 35.49623 -447.529718) (xy 35.409701 -447.5217) (xy 35.324281 -447.505732)
			(xy 35.240699 -447.481951) (xy 35.159667 -447.450559) (xy 35.081878 -447.411825) (xy 35.007994 -447.366078)
			(xy 34.938647 -447.313709) (xy 34.874427 -447.255165) (xy 34.815883 -447.190945) (xy 34.763514 -447.121598)
			(xy 34.717767 -447.047714) (xy 34.679033 -446.969925) (xy 34.647641 -446.888893) (xy 34.62386 -446.805311)
			(xy 34.607892 -446.719891) (xy 34.599874 -446.633362) (xy 31.79826 -446.633362) (xy 31.79826 -449.173362)
			(xy 34.599874 -449.173362) (xy 34.599874 -449.086462) (xy 34.607892 -448.999933) (xy 34.62386 -448.914513)
			(xy 34.647641 -448.830931) (xy 34.679033 -448.749899) (xy 34.717767 -448.67211) (xy 34.763514 -448.598226)
			(xy 34.815883 -448.528879) (xy 34.874427 -448.464659) (xy 34.938647 -448.406115) (xy 35.007994 -448.353746)
			(xy 35.081878 -448.307999) (xy 35.159667 -448.269265) (xy 35.240699 -448.237873) (xy 35.324281 -448.214092)
			(xy 35.409701 -448.198124) (xy 35.49623 -448.190106) (xy 35.58313 -448.190106) (xy 35.669659 -448.198124)
			(xy 35.755079 -448.214092) (xy 35.838661 -448.237873) (xy 35.919693 -448.269265) (xy 35.997482 -448.307999)
			(xy 36.071366 -448.353746) (xy 36.140713 -448.406115) (xy 36.204933 -448.464659) (xy 36.263477 -448.528879)
			(xy 36.315846 -448.598226) (xy 36.361593 -448.67211) (xy 36.400327 -448.749899) (xy 36.431719 -448.830931)
			(xy 36.4555 -448.914513) (xy 36.471468 -448.999933) (xy 36.479486 -449.086462) (xy 36.479988 -449.129912)
			(xy 36.479486 -449.173362) (xy 36.471468 -449.259891) (xy 36.4555 -449.345311) (xy 36.431719 -449.428893)
			(xy 36.400327 -449.509925) (xy 36.361593 -449.587714) (xy 36.315846 -449.661598) (xy 36.263477 -449.730945)
			(xy 36.204933 -449.795165) (xy 36.140713 -449.853709) (xy 36.071366 -449.906078) (xy 35.997482 -449.951825)
			(xy 35.919693 -449.990559) (xy 35.838661 -450.021951) (xy 35.755079 -450.045732) (xy 35.669659 -450.0617)
			(xy 35.58313 -450.069718) (xy 35.49623 -450.069718) (xy 35.409701 -450.0617) (xy 35.324281 -450.045732)
			(xy 35.240699 -450.021951) (xy 35.159667 -449.990559) (xy 35.081878 -449.951825) (xy 35.007994 -449.906078)
			(xy 34.938647 -449.853709) (xy 34.874427 -449.795165) (xy 34.815883 -449.730945) (xy 34.763514 -449.661598)
			(xy 34.717767 -449.587714) (xy 34.679033 -449.509925) (xy 34.647641 -449.428893) (xy 34.62386 -449.345311)
			(xy 34.607892 -449.259891) (xy 34.599874 -449.173362) (xy 31.79826 -449.173362) (xy 31.79826 -451.713362)
			(xy 34.599874 -451.713362) (xy 34.599874 -451.626462) (xy 34.607892 -451.539933) (xy 34.62386 -451.454513)
			(xy 34.647641 -451.370931) (xy 34.679033 -451.289899) (xy 34.717767 -451.21211) (xy 34.763514 -451.138226)
			(xy 34.815883 -451.068879) (xy 34.874427 -451.004659) (xy 34.938647 -450.946115) (xy 35.007994 -450.893746)
			(xy 35.081878 -450.847999) (xy 35.159667 -450.809265) (xy 35.240699 -450.777873) (xy 35.324281 -450.754092)
			(xy 35.409701 -450.738124) (xy 35.49623 -450.730106) (xy 35.58313 -450.730106) (xy 35.669659 -450.738124)
			(xy 35.755079 -450.754092) (xy 35.838661 -450.777873) (xy 35.919693 -450.809265) (xy 35.997482 -450.847999)
			(xy 36.071366 -450.893746) (xy 36.140713 -450.946115) (xy 36.204933 -451.004659) (xy 36.263477 -451.068879)
			(xy 36.315846 -451.138226) (xy 36.361593 -451.21211) (xy 36.400327 -451.289899) (xy 36.431719 -451.370931)
			(xy 36.442855 -451.41007) (xy 39.818564 -451.41007) (xy 39.819058 -451.352661) (xy 39.826902 -451.238113)
			(xy 39.842544 -451.124366) (xy 39.865911 -451.011952) (xy 39.896896 -450.901394) (xy 39.935352 -450.793209)
			(xy 39.981101 -450.6879) (xy 40.03393 -450.585958) (xy 40.093592 -450.487859) (xy 40.159809 -450.39406)
			(xy 40.232272 -450.304998) (xy 40.310645 -450.221089) (xy 40.39456 -450.142723) (xy 40.483627 -450.070266)
			(xy 40.577431 -450.004056) (xy 40.675535 -449.944402) (xy 40.777481 -449.891581) (xy 40.882793 -449.845839)
			(xy 40.990981 -449.807391) (xy 41.101541 -449.776415) (xy 41.213957 -449.753056) (xy 41.327705 -449.737423)
			(xy 41.442254 -449.729588) (xy 41.557072 -449.729588) (xy 41.671621 -449.737423) (xy 41.785369 -449.753056)
			(xy 41.897785 -449.776415) (xy 42.008345 -449.807391) (xy 42.116533 -449.845839) (xy 42.221845 -449.891581)
			(xy 42.323791 -449.944402) (xy 42.421895 -450.004056) (xy 42.501239 -450.06006) (xy 43.327577 -450.06006)
			(xy 43.331612 -449.984356) (xy 43.343671 -449.909511) (xy 43.363617 -449.83637) (xy 43.391224 -449.765765)
			(xy 43.42618 -449.698494) (xy 43.468088 -449.635319) (xy 43.516474 -449.576957) (xy 43.57079 -449.524069)
			(xy 43.630419 -449.477254) (xy 43.694687 -449.437042) (xy 43.762864 -449.40389) (xy 43.83418 -449.378172)
			(xy 43.907825 -449.36018) (xy 43.982965 -449.350118) (xy 44.058749 -449.348099) (xy 44.134319 -449.354148)
			(xy 44.208817 -449.368195) (xy 44.2814 -449.390081) (xy 44.351246 -449.419558) (xy 44.417563 -449.456293)
			(xy 44.479599 -449.499868) (xy 44.536652 -449.54979) (xy 44.588076 -449.605494) (xy 44.633287 -449.666349)
			(xy 44.671774 -449.731664) (xy 44.7031 -449.8007) (xy 44.72691 -449.872675) (xy 44.742935 -449.946773)
			(xy 44.750994 -450.022154) (xy 44.751498 -450.06006) (xy 45.867577 -450.06006) (xy 45.871612 -449.984356)
			(xy 45.883671 -449.909511) (xy 45.903617 -449.83637) (xy 45.931224 -449.765765) (xy 45.96618 -449.698494)
			(xy 46.008088 -449.635319) (xy 46.056474 -449.576957) (xy 46.11079 -449.524069) (xy 46.170419 -449.477254)
			(xy 46.234687 -449.437042) (xy 46.302864 -449.40389) (xy 46.37418 -449.378172) (xy 46.447825 -449.36018)
			(xy 46.522965 -449.350118) (xy 46.598749 -449.348099) (xy 46.674319 -449.354148) (xy 46.748817 -449.368195)
			(xy 46.8214 -449.390081) (xy 46.891246 -449.419558) (xy 46.957563 -449.456293) (xy 47.019599 -449.499868)
			(xy 47.076652 -449.54979) (xy 47.128076 -449.605494) (xy 47.173287 -449.666349) (xy 47.211774 -449.731664)
			(xy 47.2431 -449.8007) (xy 47.26691 -449.872675) (xy 47.282935 -449.946773) (xy 47.290994 -450.022154)
			(xy 47.291498 -450.06006) (xy 48.407577 -450.06006) (xy 48.411612 -449.984356) (xy 48.423671 -449.909511)
			(xy 48.443617 -449.83637) (xy 48.471224 -449.765765) (xy 48.50618 -449.698494) (xy 48.548088 -449.635319)
			(xy 48.596474 -449.576957) (xy 48.65079 -449.524069) (xy 48.710419 -449.477254) (xy 48.774687 -449.437042)
			(xy 48.842864 -449.40389) (xy 48.91418 -449.378172) (xy 48.987825 -449.36018) (xy 49.062965 -449.350118)
			(xy 49.138749 -449.348099) (xy 49.214319 -449.354148) (xy 49.288817 -449.368195) (xy 49.3614 -449.390081)
			(xy 49.431246 -449.419558) (xy 49.497563 -449.456293) (xy 49.559599 -449.499868) (xy 49.616652 -449.54979)
			(xy 49.668076 -449.605494) (xy 49.713287 -449.666349) (xy 49.751774 -449.731664) (xy 49.7831 -449.8007)
			(xy 49.80691 -449.872675) (xy 49.822935 -449.946773) (xy 49.830994 -450.022154) (xy 49.831498 -450.06006)
			(xy 50.947577 -450.06006) (xy 50.951612 -449.984356) (xy 50.963671 -449.909511) (xy 50.983617 -449.83637)
			(xy 51.011224 -449.765765) (xy 51.04618 -449.698494) (xy 51.088088 -449.635319) (xy 51.136474 -449.576957)
			(xy 51.19079 -449.524069) (xy 51.250419 -449.477254) (xy 51.314687 -449.437042) (xy 51.382864 -449.40389)
			(xy 51.45418 -449.378172) (xy 51.527825 -449.36018) (xy 51.602965 -449.350118) (xy 51.678749 -449.348099)
			(xy 51.754319 -449.354148) (xy 51.828817 -449.368195) (xy 51.9014 -449.390081) (xy 51.971246 -449.419558)
			(xy 52.037563 -449.456293) (xy 52.099599 -449.499868) (xy 52.156652 -449.54979) (xy 52.208076 -449.605494)
			(xy 52.253287 -449.666349) (xy 52.291774 -449.731664) (xy 52.3231 -449.8007) (xy 52.34691 -449.872675)
			(xy 52.362935 -449.946773) (xy 52.370994 -450.022154) (xy 52.371498 -450.06006) (xy 53.487577 -450.06006)
			(xy 53.491612 -449.984356) (xy 53.503671 -449.909511) (xy 53.523617 -449.83637) (xy 53.551224 -449.765765)
			(xy 53.58618 -449.698494) (xy 53.628088 -449.635319) (xy 53.676474 -449.576957) (xy 53.73079 -449.524069)
			(xy 53.790419 -449.477254) (xy 53.854687 -449.437042) (xy 53.922864 -449.40389) (xy 53.99418 -449.378172)
			(xy 54.067825 -449.36018) (xy 54.142965 -449.350118) (xy 54.218749 -449.348099) (xy 54.294319 -449.354148)
			(xy 54.368817 -449.368195) (xy 54.4414 -449.390081) (xy 54.511246 -449.419558) (xy 54.577563 -449.456293)
			(xy 54.639599 -449.499868) (xy 54.696652 -449.54979) (xy 54.748076 -449.605494) (xy 54.793287 -449.666349)
			(xy 54.831774 -449.731664) (xy 54.8631 -449.8007) (xy 54.88691 -449.872675) (xy 54.902935 -449.946773)
			(xy 54.910994 -450.022154) (xy 54.911498 -450.06006) (xy 56.027577 -450.06006) (xy 56.031612 -449.984356)
			(xy 56.043671 -449.909511) (xy 56.063617 -449.83637) (xy 56.091224 -449.765765) (xy 56.12618 -449.698494)
			(xy 56.168088 -449.635319) (xy 56.216474 -449.576957) (xy 56.27079 -449.524069) (xy 56.330419 -449.477254)
			(xy 56.394687 -449.437042) (xy 56.462864 -449.40389) (xy 56.53418 -449.378172) (xy 56.607825 -449.36018)
			(xy 56.682965 -449.350118) (xy 56.758749 -449.348099) (xy 56.834319 -449.354148) (xy 56.908817 -449.368195)
			(xy 56.9814 -449.390081) (xy 57.051246 -449.419558) (xy 57.117563 -449.456293) (xy 57.179599 -449.499868)
			(xy 57.236652 -449.54979) (xy 57.288076 -449.605494) (xy 57.333287 -449.666349) (xy 57.371774 -449.731664)
			(xy 57.4031 -449.8007) (xy 57.42691 -449.872675) (xy 57.442935 -449.946773) (xy 57.450994 -450.022154)
			(xy 57.451498 -450.06006) (xy 58.567577 -450.06006) (xy 58.571612 -449.984356) (xy 58.583671 -449.909511)
			(xy 58.603617 -449.83637) (xy 58.631224 -449.765765) (xy 58.66618 -449.698494) (xy 58.708088 -449.635319)
			(xy 58.756474 -449.576957) (xy 58.81079 -449.524069) (xy 58.870419 -449.477254) (xy 58.934687 -449.437042)
			(xy 59.002864 -449.40389) (xy 59.07418 -449.378172) (xy 59.147825 -449.36018) (xy 59.222965 -449.350118)
			(xy 59.298749 -449.348099) (xy 59.374319 -449.354148) (xy 59.448817 -449.368195) (xy 59.5214 -449.390081)
			(xy 59.591246 -449.419558) (xy 59.657563 -449.456293) (xy 59.719599 -449.499868) (xy 59.776652 -449.54979)
			(xy 59.828076 -449.605494) (xy 59.873287 -449.666349) (xy 59.911774 -449.731664) (xy 59.9431 -449.8007)
			(xy 59.96691 -449.872675) (xy 59.982935 -449.946773) (xy 59.990994 -450.022154) (xy 59.991498 -450.06006)
			(xy 61.107577 -450.06006) (xy 61.111612 -449.984356) (xy 61.123671 -449.909511) (xy 61.143617 -449.83637)
			(xy 61.171224 -449.765765) (xy 61.20618 -449.698494) (xy 61.248088 -449.635319) (xy 61.296474 -449.576957)
			(xy 61.35079 -449.524069) (xy 61.410419 -449.477254) (xy 61.474687 -449.437042) (xy 61.542864 -449.40389)
			(xy 61.61418 -449.378172) (xy 61.687825 -449.36018) (xy 61.762965 -449.350118) (xy 61.838749 -449.348099)
			(xy 61.914319 -449.354148) (xy 61.988817 -449.368195) (xy 62.0614 -449.390081) (xy 62.131246 -449.419558)
			(xy 62.197563 -449.456293) (xy 62.259599 -449.499868) (xy 62.265544 -449.50507) (xy 86.197697 -449.50507)
			(xy 86.201732 -449.429366) (xy 86.213791 -449.354521) (xy 86.233737 -449.28138) (xy 86.261344 -449.210775)
			(xy 86.2963 -449.143504) (xy 86.338208 -449.080329) (xy 86.386594 -449.021967) (xy 86.44091 -448.969079)
			(xy 86.500539 -448.922264) (xy 86.564807 -448.882052) (xy 86.632984 -448.8489) (xy 86.7043 -448.823182)
			(xy 86.777945 -448.80519) (xy 86.853085 -448.795128) (xy 86.928869 -448.793109) (xy 87.004439 -448.799158)
			(xy 87.078937 -448.813205) (xy 87.15152 -448.835091) (xy 87.221366 -448.864568) (xy 87.287683 -448.901303)
			(xy 87.349719 -448.944878) (xy 87.406772 -448.9948) (xy 87.458196 -449.050504) (xy 87.503407 -449.111359)
			(xy 87.541894 -449.176674) (xy 87.57322 -449.24571) (xy 87.59703 -449.317685) (xy 87.613055 -449.391783)
			(xy 87.621114 -449.467164) (xy 87.621618 -449.50507) (xy 88.737697 -449.50507) (xy 88.741732 -449.429366)
			(xy 88.753791 -449.354521) (xy 88.773737 -449.28138) (xy 88.801344 -449.210775) (xy 88.8363 -449.143504)
			(xy 88.878208 -449.080329) (xy 88.926594 -449.021967) (xy 88.98091 -448.969079) (xy 89.040539 -448.922264)
			(xy 89.104807 -448.882052) (xy 89.172984 -448.8489) (xy 89.2443 -448.823182) (xy 89.317945 -448.80519)
			(xy 89.393085 -448.795128) (xy 89.468869 -448.793109) (xy 89.544439 -448.799158) (xy 89.618937 -448.813205)
			(xy 89.69152 -448.835091) (xy 89.761366 -448.864568) (xy 89.827683 -448.901303) (xy 89.889719 -448.944878)
			(xy 89.946772 -448.9948) (xy 89.998196 -449.050504) (xy 90.043407 -449.111359) (xy 90.081894 -449.176674)
			(xy 90.11322 -449.24571) (xy 90.13703 -449.317685) (xy 90.153055 -449.391783) (xy 90.161114 -449.467164)
			(xy 90.161618 -449.50507) (xy 91.277697 -449.50507) (xy 91.281732 -449.429366) (xy 91.293791 -449.354521)
			(xy 91.313737 -449.28138) (xy 91.341344 -449.210775) (xy 91.3763 -449.143504) (xy 91.418208 -449.080329)
			(xy 91.466594 -449.021967) (xy 91.52091 -448.969079) (xy 91.580539 -448.922264) (xy 91.644807 -448.882052)
			(xy 91.712984 -448.8489) (xy 91.7843 -448.823182) (xy 91.857945 -448.80519) (xy 91.933085 -448.795128)
			(xy 92.008869 -448.793109) (xy 92.084439 -448.799158) (xy 92.158937 -448.813205) (xy 92.23152 -448.835091)
			(xy 92.301366 -448.864568) (xy 92.367683 -448.901303) (xy 92.429719 -448.944878) (xy 92.486772 -448.9948)
			(xy 92.538196 -449.050504) (xy 92.583407 -449.111359) (xy 92.621894 -449.176674) (xy 92.65322 -449.24571)
			(xy 92.67703 -449.317685) (xy 92.693055 -449.391783) (xy 92.701114 -449.467164) (xy 92.701618 -449.50507)
			(xy 92.701114 -449.542976) (xy 92.693055 -449.618357) (xy 92.67703 -449.692455) (xy 92.65322 -449.76443)
			(xy 92.621894 -449.833466) (xy 92.583407 -449.898781) (xy 92.538196 -449.959636) (xy 92.486772 -450.01534)
			(xy 92.429719 -450.065262) (xy 92.367683 -450.108837) (xy 92.301366 -450.145572) (xy 92.23152 -450.175049)
			(xy 92.158937 -450.196935) (xy 92.084439 -450.210982) (xy 92.008869 -450.217031) (xy 91.933085 -450.215012)
			(xy 91.857945 -450.20495) (xy 91.7843 -450.186958) (xy 91.712984 -450.16124) (xy 91.644807 -450.128088)
			(xy 91.580539 -450.087876) (xy 91.52091 -450.041061) (xy 91.466594 -449.988173) (xy 91.418208 -449.929811)
			(xy 91.3763 -449.866636) (xy 91.341344 -449.799365) (xy 91.313737 -449.72876) (xy 91.293791 -449.655619)
			(xy 91.281732 -449.580774) (xy 91.277697 -449.50507) (xy 90.161618 -449.50507) (xy 90.161114 -449.542976)
			(xy 90.153055 -449.618357) (xy 90.13703 -449.692455) (xy 90.11322 -449.76443) (xy 90.081894 -449.833466)
			(xy 90.043407 -449.898781) (xy 89.998196 -449.959636) (xy 89.946772 -450.01534) (xy 89.889719 -450.065262)
			(xy 89.827683 -450.108837) (xy 89.761366 -450.145572) (xy 89.69152 -450.175049) (xy 89.618937 -450.196935)
			(xy 89.544439 -450.210982) (xy 89.468869 -450.217031) (xy 89.393085 -450.215012) (xy 89.317945 -450.20495)
			(xy 89.2443 -450.186958) (xy 89.172984 -450.16124) (xy 89.104807 -450.128088) (xy 89.040539 -450.087876)
			(xy 88.98091 -450.041061) (xy 88.926594 -449.988173) (xy 88.878208 -449.929811) (xy 88.8363 -449.866636)
			(xy 88.801344 -449.799365) (xy 88.773737 -449.72876) (xy 88.753791 -449.655619) (xy 88.741732 -449.580774)
			(xy 88.737697 -449.50507) (xy 87.621618 -449.50507) (xy 87.621114 -449.542976) (xy 87.613055 -449.618357)
			(xy 87.59703 -449.692455) (xy 87.57322 -449.76443) (xy 87.541894 -449.833466) (xy 87.503407 -449.898781)
			(xy 87.458196 -449.959636) (xy 87.406772 -450.01534) (xy 87.349719 -450.065262) (xy 87.287683 -450.108837)
			(xy 87.221366 -450.145572) (xy 87.15152 -450.175049) (xy 87.078937 -450.196935) (xy 87.004439 -450.210982)
			(xy 86.928869 -450.217031) (xy 86.853085 -450.215012) (xy 86.777945 -450.20495) (xy 86.7043 -450.186958)
			(xy 86.632984 -450.16124) (xy 86.564807 -450.128088) (xy 86.500539 -450.087876) (xy 86.44091 -450.041061)
			(xy 86.386594 -449.988173) (xy 86.338208 -449.929811) (xy 86.2963 -449.866636) (xy 86.261344 -449.799365)
			(xy 86.233737 -449.72876) (xy 86.213791 -449.655619) (xy 86.201732 -449.580774) (xy 86.197697 -449.50507)
			(xy 62.265544 -449.50507) (xy 62.316652 -449.54979) (xy 62.368076 -449.605494) (xy 62.413287 -449.666349)
			(xy 62.451774 -449.731664) (xy 62.4831 -449.8007) (xy 62.50691 -449.872675) (xy 62.522935 -449.946773)
			(xy 62.530994 -450.022154) (xy 62.531498 -450.06006) (xy 62.530994 -450.097966) (xy 62.522935 -450.173347)
			(xy 62.50691 -450.247445) (xy 62.4831 -450.31942) (xy 62.451774 -450.388456) (xy 62.413287 -450.453771)
			(xy 62.368076 -450.514626) (xy 62.316652 -450.57033) (xy 62.259599 -450.620252) (xy 62.197563 -450.663827)
			(xy 62.131246 -450.700562) (xy 62.0614 -450.730039) (xy 61.988817 -450.751925) (xy 61.914319 -450.765972)
			(xy 61.838749 -450.772021) (xy 61.762965 -450.770002) (xy 61.687825 -450.75994) (xy 61.61418 -450.741948)
			(xy 61.542864 -450.71623) (xy 61.474687 -450.683078) (xy 61.410419 -450.642866) (xy 61.35079 -450.596051)
			(xy 61.296474 -450.543163) (xy 61.248088 -450.484801) (xy 61.20618 -450.421626) (xy 61.171224 -450.354355)
			(xy 61.143617 -450.28375) (xy 61.123671 -450.210609) (xy 61.111612 -450.135764) (xy 61.107577 -450.06006)
			(xy 59.991498 -450.06006) (xy 59.990994 -450.097966) (xy 59.982935 -450.173347) (xy 59.96691 -450.247445)
			(xy 59.9431 -450.31942) (xy 59.911774 -450.388456) (xy 59.873287 -450.453771) (xy 59.828076 -450.514626)
			(xy 59.776652 -450.57033) (xy 59.719599 -450.620252) (xy 59.657563 -450.663827) (xy 59.591246 -450.700562)
			(xy 59.5214 -450.730039) (xy 59.448817 -450.751925) (xy 59.374319 -450.765972) (xy 59.298749 -450.772021)
			(xy 59.222965 -450.770002) (xy 59.147825 -450.75994) (xy 59.07418 -450.741948) (xy 59.002864 -450.71623)
			(xy 58.934687 -450.683078) (xy 58.870419 -450.642866) (xy 58.81079 -450.596051) (xy 58.756474 -450.543163)
			(xy 58.708088 -450.484801) (xy 58.66618 -450.421626) (xy 58.631224 -450.354355) (xy 58.603617 -450.28375)
			(xy 58.583671 -450.210609) (xy 58.571612 -450.135764) (xy 58.567577 -450.06006) (xy 57.451498 -450.06006)
			(xy 57.450994 -450.097966) (xy 57.442935 -450.173347) (xy 57.42691 -450.247445) (xy 57.4031 -450.31942)
			(xy 57.371774 -450.388456) (xy 57.333287 -450.453771) (xy 57.288076 -450.514626) (xy 57.236652 -450.57033)
			(xy 57.179599 -450.620252) (xy 57.117563 -450.663827) (xy 57.051246 -450.700562) (xy 56.9814 -450.730039)
			(xy 56.908817 -450.751925) (xy 56.834319 -450.765972) (xy 56.758749 -450.772021) (xy 56.682965 -450.770002)
			(xy 56.607825 -450.75994) (xy 56.53418 -450.741948) (xy 56.462864 -450.71623) (xy 56.394687 -450.683078)
			(xy 56.330419 -450.642866) (xy 56.27079 -450.596051) (xy 56.216474 -450.543163) (xy 56.168088 -450.484801)
			(xy 56.12618 -450.421626) (xy 56.091224 -450.354355) (xy 56.063617 -450.28375) (xy 56.043671 -450.210609)
			(xy 56.031612 -450.135764) (xy 56.027577 -450.06006) (xy 54.911498 -450.06006) (xy 54.910994 -450.097966)
			(xy 54.902935 -450.173347) (xy 54.88691 -450.247445) (xy 54.8631 -450.31942) (xy 54.831774 -450.388456)
			(xy 54.793287 -450.453771) (xy 54.748076 -450.514626) (xy 54.696652 -450.57033) (xy 54.639599 -450.620252)
			(xy 54.577563 -450.663827) (xy 54.511246 -450.700562) (xy 54.4414 -450.730039) (xy 54.368817 -450.751925)
			(xy 54.294319 -450.765972) (xy 54.218749 -450.772021) (xy 54.142965 -450.770002) (xy 54.067825 -450.75994)
			(xy 53.99418 -450.741948) (xy 53.922864 -450.71623) (xy 53.854687 -450.683078) (xy 53.790419 -450.642866)
			(xy 53.73079 -450.596051) (xy 53.676474 -450.543163) (xy 53.628088 -450.484801) (xy 53.58618 -450.421626)
			(xy 53.551224 -450.354355) (xy 53.523617 -450.28375) (xy 53.503671 -450.210609) (xy 53.491612 -450.135764)
			(xy 53.487577 -450.06006) (xy 52.371498 -450.06006) (xy 52.370994 -450.097966) (xy 52.362935 -450.173347)
			(xy 52.34691 -450.247445) (xy 52.3231 -450.31942) (xy 52.291774 -450.388456) (xy 52.253287 -450.453771)
			(xy 52.208076 -450.514626) (xy 52.156652 -450.57033) (xy 52.099599 -450.620252) (xy 52.037563 -450.663827)
			(xy 51.971246 -450.700562) (xy 51.9014 -450.730039) (xy 51.828817 -450.751925) (xy 51.754319 -450.765972)
			(xy 51.678749 -450.772021) (xy 51.602965 -450.770002) (xy 51.527825 -450.75994) (xy 51.45418 -450.741948)
			(xy 51.382864 -450.71623) (xy 51.314687 -450.683078) (xy 51.250419 -450.642866) (xy 51.19079 -450.596051)
			(xy 51.136474 -450.543163) (xy 51.088088 -450.484801) (xy 51.04618 -450.421626) (xy 51.011224 -450.354355)
			(xy 50.983617 -450.28375) (xy 50.963671 -450.210609) (xy 50.951612 -450.135764) (xy 50.947577 -450.06006)
			(xy 49.831498 -450.06006) (xy 49.830994 -450.097966) (xy 49.822935 -450.173347) (xy 49.80691 -450.247445)
			(xy 49.7831 -450.31942) (xy 49.751774 -450.388456) (xy 49.713287 -450.453771) (xy 49.668076 -450.514626)
			(xy 49.616652 -450.57033) (xy 49.559599 -450.620252) (xy 49.497563 -450.663827) (xy 49.431246 -450.700562)
			(xy 49.3614 -450.730039) (xy 49.288817 -450.751925) (xy 49.214319 -450.765972) (xy 49.138749 -450.772021)
			(xy 49.062965 -450.770002) (xy 48.987825 -450.75994) (xy 48.91418 -450.741948) (xy 48.842864 -450.71623)
			(xy 48.774687 -450.683078) (xy 48.710419 -450.642866) (xy 48.65079 -450.596051) (xy 48.596474 -450.543163)
			(xy 48.548088 -450.484801) (xy 48.50618 -450.421626) (xy 48.471224 -450.354355) (xy 48.443617 -450.28375)
			(xy 48.423671 -450.210609) (xy 48.411612 -450.135764) (xy 48.407577 -450.06006) (xy 47.291498 -450.06006)
			(xy 47.290994 -450.097966) (xy 47.282935 -450.173347) (xy 47.26691 -450.247445) (xy 47.2431 -450.31942)
			(xy 47.211774 -450.388456) (xy 47.173287 -450.453771) (xy 47.128076 -450.514626) (xy 47.076652 -450.57033)
			(xy 47.019599 -450.620252) (xy 46.957563 -450.663827) (xy 46.891246 -450.700562) (xy 46.8214 -450.730039)
			(xy 46.748817 -450.751925) (xy 46.674319 -450.765972) (xy 46.598749 -450.772021) (xy 46.522965 -450.770002)
			(xy 46.447825 -450.75994) (xy 46.37418 -450.741948) (xy 46.302864 -450.71623) (xy 46.234687 -450.683078)
			(xy 46.170419 -450.642866) (xy 46.11079 -450.596051) (xy 46.056474 -450.543163) (xy 46.008088 -450.484801)
			(xy 45.96618 -450.421626) (xy 45.931224 -450.354355) (xy 45.903617 -450.28375) (xy 45.883671 -450.210609)
			(xy 45.871612 -450.135764) (xy 45.867577 -450.06006) (xy 44.751498 -450.06006) (xy 44.750994 -450.097966)
			(xy 44.742935 -450.173347) (xy 44.72691 -450.247445) (xy 44.7031 -450.31942) (xy 44.671774 -450.388456)
			(xy 44.633287 -450.453771) (xy 44.588076 -450.514626) (xy 44.536652 -450.57033) (xy 44.479599 -450.620252)
			(xy 44.417563 -450.663827) (xy 44.351246 -450.700562) (xy 44.2814 -450.730039) (xy 44.208817 -450.751925)
			(xy 44.134319 -450.765972) (xy 44.058749 -450.772021) (xy 43.982965 -450.770002) (xy 43.907825 -450.75994)
			(xy 43.83418 -450.741948) (xy 43.762864 -450.71623) (xy 43.694687 -450.683078) (xy 43.630419 -450.642866)
			(xy 43.57079 -450.596051) (xy 43.516474 -450.543163) (xy 43.468088 -450.484801) (xy 43.42618 -450.421626)
			(xy 43.391224 -450.354355) (xy 43.363617 -450.28375) (xy 43.343671 -450.210609) (xy 43.331612 -450.135764)
			(xy 43.327577 -450.06006) (xy 42.501239 -450.06006) (xy 42.515699 -450.070266) (xy 42.604766 -450.142723)
			(xy 42.688681 -450.221089) (xy 42.767054 -450.304998) (xy 42.839517 -450.39406) (xy 42.905734 -450.487859)
			(xy 42.965396 -450.585958) (xy 43.018225 -450.6879) (xy 43.056094 -450.77507) (xy 84.927697 -450.77507)
			(xy 84.931732 -450.699366) (xy 84.943791 -450.624521) (xy 84.963737 -450.55138) (xy 84.991344 -450.480775)
			(xy 85.0263 -450.413504) (xy 85.068208 -450.350329) (xy 85.116594 -450.291967) (xy 85.17091 -450.239079)
			(xy 85.230539 -450.192264) (xy 85.294807 -450.152052) (xy 85.362984 -450.1189) (xy 85.4343 -450.093182)
			(xy 85.507945 -450.07519) (xy 85.583085 -450.065128) (xy 85.658869 -450.063109) (xy 85.734439 -450.069158)
			(xy 85.808937 -450.083205) (xy 85.88152 -450.105091) (xy 85.951366 -450.134568) (xy 86.017683 -450.171303)
			(xy 86.079719 -450.214878) (xy 86.136772 -450.2648) (xy 86.188196 -450.320504) (xy 86.233407 -450.381359)
			(xy 86.271894 -450.446674) (xy 86.30322 -450.51571) (xy 86.32703 -450.587685) (xy 86.343055 -450.661783)
			(xy 86.351114 -450.737164) (xy 86.351618 -450.77507) (xy 87.467697 -450.77507) (xy 87.471732 -450.699366)
			(xy 87.483791 -450.624521) (xy 87.503737 -450.55138) (xy 87.531344 -450.480775) (xy 87.5663 -450.413504)
			(xy 87.608208 -450.350329) (xy 87.656594 -450.291967) (xy 87.71091 -450.239079) (xy 87.770539 -450.192264)
			(xy 87.834807 -450.152052) (xy 87.902984 -450.1189) (xy 87.9743 -450.093182) (xy 88.047945 -450.07519)
			(xy 88.123085 -450.065128) (xy 88.198869 -450.063109) (xy 88.274439 -450.069158) (xy 88.348937 -450.083205)
			(xy 88.42152 -450.105091) (xy 88.491366 -450.134568) (xy 88.557683 -450.171303) (xy 88.619719 -450.214878)
			(xy 88.676772 -450.2648) (xy 88.728196 -450.320504) (xy 88.773407 -450.381359) (xy 88.811894 -450.446674)
			(xy 88.84322 -450.51571) (xy 88.86703 -450.587685) (xy 88.883055 -450.661783) (xy 88.891114 -450.737164)
			(xy 88.891618 -450.77507) (xy 90.007697 -450.77507) (xy 90.011732 -450.699366) (xy 90.023791 -450.624521)
			(xy 90.043737 -450.55138) (xy 90.071344 -450.480775) (xy 90.1063 -450.413504) (xy 90.148208 -450.350329)
			(xy 90.196594 -450.291967) (xy 90.25091 -450.239079) (xy 90.310539 -450.192264) (xy 90.374807 -450.152052)
			(xy 90.442984 -450.1189) (xy 90.5143 -450.093182) (xy 90.587945 -450.07519) (xy 90.663085 -450.065128)
			(xy 90.738869 -450.063109) (xy 90.814439 -450.069158) (xy 90.888937 -450.083205) (xy 90.96152 -450.105091)
			(xy 91.031366 -450.134568) (xy 91.097683 -450.171303) (xy 91.159719 -450.214878) (xy 91.216772 -450.2648)
			(xy 91.268196 -450.320504) (xy 91.313407 -450.381359) (xy 91.351894 -450.446674) (xy 91.38322 -450.51571)
			(xy 91.40703 -450.587685) (xy 91.423055 -450.661783) (xy 91.431114 -450.737164) (xy 91.431618 -450.77507)
			(xy 91.431114 -450.812976) (xy 91.423055 -450.888357) (xy 91.40703 -450.962455) (xy 91.38322 -451.03443)
			(xy 91.351894 -451.103466) (xy 91.313407 -451.168781) (xy 91.268196 -451.229636) (xy 91.216772 -451.28534)
			(xy 91.159719 -451.335262) (xy 91.097683 -451.378837) (xy 91.031366 -451.415572) (xy 90.96152 -451.445049)
			(xy 90.888937 -451.466935) (xy 90.814439 -451.480982) (xy 90.738869 -451.487031) (xy 90.663085 -451.485012)
			(xy 90.587945 -451.47495) (xy 90.5143 -451.456958) (xy 90.442984 -451.43124) (xy 90.374807 -451.398088)
			(xy 90.310539 -451.357876) (xy 90.25091 -451.311061) (xy 90.196594 -451.258173) (xy 90.148208 -451.199811)
			(xy 90.1063 -451.136636) (xy 90.071344 -451.069365) (xy 90.043737 -450.99876) (xy 90.023791 -450.925619)
			(xy 90.011732 -450.850774) (xy 90.007697 -450.77507) (xy 88.891618 -450.77507) (xy 88.891114 -450.812976)
			(xy 88.883055 -450.888357) (xy 88.86703 -450.962455) (xy 88.84322 -451.03443) (xy 88.811894 -451.103466)
			(xy 88.773407 -451.168781) (xy 88.728196 -451.229636) (xy 88.676772 -451.28534) (xy 88.619719 -451.335262)
			(xy 88.557683 -451.378837) (xy 88.491366 -451.415572) (xy 88.42152 -451.445049) (xy 88.348937 -451.466935)
			(xy 88.274439 -451.480982) (xy 88.198869 -451.487031) (xy 88.123085 -451.485012) (xy 88.047945 -451.47495)
			(xy 87.9743 -451.456958) (xy 87.902984 -451.43124) (xy 87.834807 -451.398088) (xy 87.770539 -451.357876)
			(xy 87.71091 -451.311061) (xy 87.656594 -451.258173) (xy 87.608208 -451.199811) (xy 87.5663 -451.136636)
			(xy 87.531344 -451.069365) (xy 87.503737 -450.99876) (xy 87.483791 -450.925619) (xy 87.471732 -450.850774)
			(xy 87.467697 -450.77507) (xy 86.351618 -450.77507) (xy 86.351114 -450.812976) (xy 86.343055 -450.888357)
			(xy 86.32703 -450.962455) (xy 86.30322 -451.03443) (xy 86.271894 -451.103466) (xy 86.233407 -451.168781)
			(xy 86.188196 -451.229636) (xy 86.136772 -451.28534) (xy 86.079719 -451.335262) (xy 86.017683 -451.378837)
			(xy 85.951366 -451.415572) (xy 85.88152 -451.445049) (xy 85.808937 -451.466935) (xy 85.734439 -451.480982)
			(xy 85.658869 -451.487031) (xy 85.583085 -451.485012) (xy 85.507945 -451.47495) (xy 85.4343 -451.456958)
			(xy 85.362984 -451.43124) (xy 85.294807 -451.398088) (xy 85.230539 -451.357876) (xy 85.17091 -451.311061)
			(xy 85.116594 -451.258173) (xy 85.068208 -451.199811) (xy 85.0263 -451.136636) (xy 84.991344 -451.069365)
			(xy 84.963737 -450.99876) (xy 84.943791 -450.925619) (xy 84.931732 -450.850774) (xy 84.927697 -450.77507)
			(xy 43.056094 -450.77507) (xy 43.063974 -450.793209) (xy 43.10243 -450.901394) (xy 43.133415 -451.011952)
			(xy 43.156782 -451.124366) (xy 43.172424 -451.238113) (xy 43.180268 -451.352661) (xy 43.180762 -451.41007)
			(xy 43.180576 -451.443253) (xy 43.177909 -451.509567) (xy 43.175428 -451.542658) (xy 43.170272 -451.600942)
			(xy 43.152948 -451.716671) (xy 43.127616 -451.830914) (xy 43.094401 -451.943119) (xy 43.056327 -452.04507)
			(xy 86.197697 -452.04507) (xy 86.201732 -451.969366) (xy 86.213791 -451.894521) (xy 86.233737 -451.82138)
			(xy 86.261344 -451.750775) (xy 86.2963 -451.683504) (xy 86.338208 -451.620329) (xy 86.386594 -451.561967)
			(xy 86.44091 -451.509079) (xy 86.500539 -451.462264) (xy 86.564807 -451.422052) (xy 86.632984 -451.3889)
			(xy 86.7043 -451.363182) (xy 86.777945 -451.34519) (xy 86.853085 -451.335128) (xy 86.928869 -451.333109)
			(xy 87.004439 -451.339158) (xy 87.078937 -451.353205) (xy 87.15152 -451.375091) (xy 87.221366 -451.404568)
			(xy 87.287683 -451.441303) (xy 87.349719 -451.484878) (xy 87.406772 -451.5348) (xy 87.458196 -451.590504)
			(xy 87.503407 -451.651359) (xy 87.541894 -451.716674) (xy 87.57322 -451.78571) (xy 87.59703 -451.857685)
			(xy 87.613055 -451.931783) (xy 87.621114 -452.007164) (xy 87.621618 -452.04507) (xy 88.737697 -452.04507)
			(xy 88.741732 -451.969366) (xy 88.753791 -451.894521) (xy 88.773737 -451.82138) (xy 88.801344 -451.750775)
			(xy 88.8363 -451.683504) (xy 88.878208 -451.620329) (xy 88.926594 -451.561967) (xy 88.98091 -451.509079)
			(xy 89.040539 -451.462264) (xy 89.104807 -451.422052) (xy 89.172984 -451.3889) (xy 89.2443 -451.363182)
			(xy 89.317945 -451.34519) (xy 89.393085 -451.335128) (xy 89.468869 -451.333109) (xy 89.544439 -451.339158)
			(xy 89.618937 -451.353205) (xy 89.69152 -451.375091) (xy 89.761366 -451.404568) (xy 89.827683 -451.441303)
			(xy 89.889719 -451.484878) (xy 89.946772 -451.5348) (xy 89.998196 -451.590504) (xy 90.043407 -451.651359)
			(xy 90.081894 -451.716674) (xy 90.11322 -451.78571) (xy 90.13703 -451.857685) (xy 90.153055 -451.931783)
			(xy 90.161114 -452.007164) (xy 90.161618 -452.04507) (xy 91.277697 -452.04507) (xy 91.281732 -451.969366)
			(xy 91.293791 -451.894521) (xy 91.313737 -451.82138) (xy 91.341344 -451.750775) (xy 91.3763 -451.683504)
			(xy 91.418208 -451.620329) (xy 91.466594 -451.561967) (xy 91.52091 -451.509079) (xy 91.580539 -451.462264)
			(xy 91.644807 -451.422052) (xy 91.712984 -451.3889) (xy 91.7843 -451.363182) (xy 91.857945 -451.34519)
			(xy 91.933085 -451.335128) (xy 92.008869 -451.333109) (xy 92.084439 -451.339158) (xy 92.158937 -451.353205)
			(xy 92.23152 -451.375091) (xy 92.301366 -451.404568) (xy 92.367683 -451.441303) (xy 92.429719 -451.484878)
			(xy 92.486772 -451.5348) (xy 92.538196 -451.590504) (xy 92.583407 -451.651359) (xy 92.621894 -451.716674)
			(xy 92.65322 -451.78571) (xy 92.67703 -451.857685) (xy 92.693055 -451.931783) (xy 92.701114 -452.007164)
			(xy 92.701618 -452.04507) (xy 92.701114 -452.082976) (xy 92.693055 -452.158357) (xy 92.67703 -452.232455)
			(xy 92.65322 -452.30443) (xy 92.621894 -452.373466) (xy 92.583407 -452.438781) (xy 92.538196 -452.499636)
			(xy 92.486772 -452.55534) (xy 92.429719 -452.605262) (xy 92.367683 -452.648837) (xy 92.301366 -452.685572)
			(xy 92.23152 -452.715049) (xy 92.158937 -452.736935) (xy 92.084439 -452.750982) (xy 92.008869 -452.757031)
			(xy 91.933085 -452.755012) (xy 91.857945 -452.74495) (xy 91.7843 -452.726958) (xy 91.712984 -452.70124)
			(xy 91.644807 -452.668088) (xy 91.580539 -452.627876) (xy 91.52091 -452.581061) (xy 91.466594 -452.528173)
			(xy 91.418208 -452.469811) (xy 91.3763 -452.406636) (xy 91.341344 -452.339365) (xy 91.313737 -452.26876)
			(xy 91.293791 -452.195619) (xy 91.281732 -452.120774) (xy 91.277697 -452.04507) (xy 90.161618 -452.04507)
			(xy 90.161114 -452.082976) (xy 90.153055 -452.158357) (xy 90.13703 -452.232455) (xy 90.11322 -452.30443)
			(xy 90.081894 -452.373466) (xy 90.043407 -452.438781) (xy 89.998196 -452.499636) (xy 89.946772 -452.55534)
			(xy 89.889719 -452.605262) (xy 89.827683 -452.648837) (xy 89.761366 -452.685572) (xy 89.69152 -452.715049)
			(xy 89.618937 -452.736935) (xy 89.544439 -452.750982) (xy 89.468869 -452.757031) (xy 89.393085 -452.755012)
			(xy 89.317945 -452.74495) (xy 89.2443 -452.726958) (xy 89.172984 -452.70124) (xy 89.104807 -452.668088)
			(xy 89.040539 -452.627876) (xy 88.98091 -452.581061) (xy 88.926594 -452.528173) (xy 88.878208 -452.469811)
			(xy 88.8363 -452.406636) (xy 88.801344 -452.339365) (xy 88.773737 -452.26876) (xy 88.753791 -452.195619)
			(xy 88.741732 -452.120774) (xy 88.737697 -452.04507) (xy 87.621618 -452.04507) (xy 87.621114 -452.082976)
			(xy 87.613055 -452.158357) (xy 87.59703 -452.232455) (xy 87.57322 -452.30443) (xy 87.541894 -452.373466)
			(xy 87.503407 -452.438781) (xy 87.458196 -452.499636) (xy 87.406772 -452.55534) (xy 87.349719 -452.605262)
			(xy 87.287683 -452.648837) (xy 87.221366 -452.685572) (xy 87.15152 -452.715049) (xy 87.078937 -452.736935)
			(xy 87.004439 -452.750982) (xy 86.928869 -452.757031) (xy 86.853085 -452.755012) (xy 86.777945 -452.74495)
			(xy 86.7043 -452.726958) (xy 86.632984 -452.70124) (xy 86.564807 -452.668088) (xy 86.500539 -452.627876)
			(xy 86.44091 -452.581061) (xy 86.386594 -452.528173) (xy 86.338208 -452.469811) (xy 86.2963 -452.406636)
			(xy 86.261344 -452.339365) (xy 86.233737 -452.26876) (xy 86.213791 -452.195619) (xy 86.201732 -452.120774)
			(xy 86.197697 -452.04507) (xy 43.056327 -452.04507) (xy 43.055094 -452.048372) (xy 43.328336 -452.048372)
			(xy 44.751244 -452.048372) (xy 44.751244 -452.76008) (xy 45.867577 -452.76008) (xy 45.871612 -452.684376)
			(xy 45.883671 -452.609531) (xy 45.903617 -452.53639) (xy 45.931224 -452.465785) (xy 45.96618 -452.398514)
			(xy 46.008088 -452.335339) (xy 46.056474 -452.276977) (xy 46.11079 -452.224089) (xy 46.170419 -452.177274)
			(xy 46.234687 -452.137062) (xy 46.302864 -452.10391) (xy 46.37418 -452.078192) (xy 46.447825 -452.0602)
			(xy 46.522965 -452.050138) (xy 46.598749 -452.048119) (xy 46.674319 -452.054168) (xy 46.748817 -452.068215)
			(xy 46.8214 -452.090101) (xy 46.891246 -452.119578) (xy 46.957563 -452.156313) (xy 47.019599 -452.199888)
			(xy 47.076652 -452.24981) (xy 47.128076 -452.305514) (xy 47.173287 -452.366369) (xy 47.211774 -452.431684)
			(xy 47.2431 -452.50072) (xy 47.26691 -452.572695) (xy 47.282935 -452.646793) (xy 47.290994 -452.722174)
			(xy 47.291498 -452.76008) (xy 48.407577 -452.76008) (xy 48.411612 -452.684376) (xy 48.423671 -452.609531)
			(xy 48.443617 -452.53639) (xy 48.471224 -452.465785) (xy 48.50618 -452.398514) (xy 48.548088 -452.335339)
			(xy 48.596474 -452.276977) (xy 48.65079 -452.224089) (xy 48.710419 -452.177274) (xy 48.774687 -452.137062)
			(xy 48.842864 -452.10391) (xy 48.91418 -452.078192) (xy 48.987825 -452.0602) (xy 49.062965 -452.050138)
			(xy 49.138749 -452.048119) (xy 49.214319 -452.054168) (xy 49.288817 -452.068215) (xy 49.3614 -452.090101)
			(xy 49.431246 -452.119578) (xy 49.497563 -452.156313) (xy 49.559599 -452.199888) (xy 49.616652 -452.24981)
			(xy 49.668076 -452.305514) (xy 49.713287 -452.366369) (xy 49.751774 -452.431684) (xy 49.7831 -452.50072)
			(xy 49.80691 -452.572695) (xy 49.822935 -452.646793) (xy 49.830994 -452.722174) (xy 49.831498 -452.76008)
			(xy 50.947577 -452.76008) (xy 50.951612 -452.684376) (xy 50.963671 -452.609531) (xy 50.983617 -452.53639)
			(xy 51.011224 -452.465785) (xy 51.04618 -452.398514) (xy 51.088088 -452.335339) (xy 51.136474 -452.276977)
			(xy 51.19079 -452.224089) (xy 51.250419 -452.177274) (xy 51.314687 -452.137062) (xy 51.382864 -452.10391)
			(xy 51.45418 -452.078192) (xy 51.527825 -452.0602) (xy 51.602965 -452.050138) (xy 51.678749 -452.048119)
			(xy 51.754319 -452.054168) (xy 51.828817 -452.068215) (xy 51.9014 -452.090101) (xy 51.971246 -452.119578)
			(xy 52.037563 -452.156313) (xy 52.099599 -452.199888) (xy 52.156652 -452.24981) (xy 52.208076 -452.305514)
			(xy 52.253287 -452.366369) (xy 52.291774 -452.431684) (xy 52.3231 -452.50072) (xy 52.34691 -452.572695)
			(xy 52.362935 -452.646793) (xy 52.370994 -452.722174) (xy 52.371498 -452.76008) (xy 53.487577 -452.76008)
			(xy 53.491612 -452.684376) (xy 53.503671 -452.609531) (xy 53.523617 -452.53639) (xy 53.551224 -452.465785)
			(xy 53.58618 -452.398514) (xy 53.628088 -452.335339) (xy 53.676474 -452.276977) (xy 53.73079 -452.224089)
			(xy 53.790419 -452.177274) (xy 53.854687 -452.137062) (xy 53.922864 -452.10391) (xy 53.99418 -452.078192)
			(xy 54.067825 -452.0602) (xy 54.142965 -452.050138) (xy 54.218749 -452.048119) (xy 54.294319 -452.054168)
			(xy 54.368817 -452.068215) (xy 54.4414 -452.090101) (xy 54.511246 -452.119578) (xy 54.577563 -452.156313)
			(xy 54.639599 -452.199888) (xy 54.696652 -452.24981) (xy 54.748076 -452.305514) (xy 54.793287 -452.366369)
			(xy 54.831774 -452.431684) (xy 54.8631 -452.50072) (xy 54.88691 -452.572695) (xy 54.902935 -452.646793)
			(xy 54.910994 -452.722174) (xy 54.911498 -452.76008) (xy 56.027577 -452.76008) (xy 56.031612 -452.684376)
			(xy 56.043671 -452.609531) (xy 56.063617 -452.53639) (xy 56.091224 -452.465785) (xy 56.12618 -452.398514)
			(xy 56.168088 -452.335339) (xy 56.216474 -452.276977) (xy 56.27079 -452.224089) (xy 56.330419 -452.177274)
			(xy 56.394687 -452.137062) (xy 56.462864 -452.10391) (xy 56.53418 -452.078192) (xy 56.607825 -452.0602)
			(xy 56.682965 -452.050138) (xy 56.758749 -452.048119) (xy 56.834319 -452.054168) (xy 56.908817 -452.068215)
			(xy 56.9814 -452.090101) (xy 57.051246 -452.119578) (xy 57.117563 -452.156313) (xy 57.179599 -452.199888)
			(xy 57.236652 -452.24981) (xy 57.288076 -452.305514) (xy 57.333287 -452.366369) (xy 57.371774 -452.431684)
			(xy 57.4031 -452.50072) (xy 57.42691 -452.572695) (xy 57.442935 -452.646793) (xy 57.450994 -452.722174)
			(xy 57.451498 -452.76008) (xy 58.567577 -452.76008) (xy 58.571612 -452.684376) (xy 58.583671 -452.609531)
			(xy 58.603617 -452.53639) (xy 58.631224 -452.465785) (xy 58.66618 -452.398514) (xy 58.708088 -452.335339)
			(xy 58.756474 -452.276977) (xy 58.81079 -452.224089) (xy 58.870419 -452.177274) (xy 58.934687 -452.137062)
			(xy 59.002864 -452.10391) (xy 59.07418 -452.078192) (xy 59.147825 -452.0602) (xy 59.222965 -452.050138)
			(xy 59.298749 -452.048119) (xy 59.374319 -452.054168) (xy 59.448817 -452.068215) (xy 59.5214 -452.090101)
			(xy 59.591246 -452.119578) (xy 59.657563 -452.156313) (xy 59.719599 -452.199888) (xy 59.776652 -452.24981)
			(xy 59.828076 -452.305514) (xy 59.873287 -452.366369) (xy 59.911774 -452.431684) (xy 59.9431 -452.50072)
			(xy 59.96691 -452.572695) (xy 59.982935 -452.646793) (xy 59.990994 -452.722174) (xy 59.991498 -452.76008)
			(xy 61.107577 -452.76008) (xy 61.111612 -452.684376) (xy 61.123671 -452.609531) (xy 61.143617 -452.53639)
			(xy 61.171224 -452.465785) (xy 61.20618 -452.398514) (xy 61.248088 -452.335339) (xy 61.296474 -452.276977)
			(xy 61.35079 -452.224089) (xy 61.410419 -452.177274) (xy 61.474687 -452.137062) (xy 61.542864 -452.10391)
			(xy 61.61418 -452.078192) (xy 61.687825 -452.0602) (xy 61.762965 -452.050138) (xy 61.838749 -452.048119)
			(xy 61.914319 -452.054168) (xy 61.988817 -452.068215) (xy 62.0614 -452.090101) (xy 62.131246 -452.119578)
			(xy 62.197563 -452.156313) (xy 62.259599 -452.199888) (xy 62.316652 -452.24981) (xy 62.368076 -452.305514)
			(xy 62.413287 -452.366369) (xy 62.451774 -452.431684) (xy 62.4831 -452.50072) (xy 62.50691 -452.572695)
			(xy 62.522935 -452.646793) (xy 62.530994 -452.722174) (xy 62.531498 -452.76008) (xy 62.530994 -452.797986)
			(xy 62.522935 -452.873367) (xy 62.50691 -452.947465) (xy 62.4831 -453.01944) (xy 62.451774 -453.088476)
			(xy 62.413287 -453.153791) (xy 62.368076 -453.214646) (xy 62.316652 -453.27035) (xy 62.265544 -453.31507)
			(xy 84.927697 -453.31507) (xy 84.931732 -453.239366) (xy 84.943791 -453.164521) (xy 84.963737 -453.09138)
			(xy 84.991344 -453.020775) (xy 85.0263 -452.953504) (xy 85.068208 -452.890329) (xy 85.116594 -452.831967)
			(xy 85.17091 -452.779079) (xy 85.230539 -452.732264) (xy 85.294807 -452.692052) (xy 85.362984 -452.6589)
			(xy 85.4343 -452.633182) (xy 85.507945 -452.61519) (xy 85.583085 -452.605128) (xy 85.658869 -452.603109)
			(xy 85.734439 -452.609158) (xy 85.808937 -452.623205) (xy 85.88152 -452.645091) (xy 85.951366 -452.674568)
			(xy 86.017683 -452.711303) (xy 86.079719 -452.754878) (xy 86.136772 -452.8048) (xy 86.188196 -452.860504)
			(xy 86.233407 -452.921359) (xy 86.271894 -452.986674) (xy 86.30322 -453.05571) (xy 86.32703 -453.127685)
			(xy 86.343055 -453.201783) (xy 86.351114 -453.277164) (xy 86.351618 -453.31507) (xy 87.467697 -453.31507)
			(xy 87.471732 -453.239366) (xy 87.483791 -453.164521) (xy 87.503737 -453.09138) (xy 87.531344 -453.020775)
			(xy 87.5663 -452.953504) (xy 87.608208 -452.890329) (xy 87.656594 -452.831967) (xy 87.71091 -452.779079)
			(xy 87.770539 -452.732264) (xy 87.834807 -452.692052) (xy 87.902984 -452.6589) (xy 87.9743 -452.633182)
			(xy 88.047945 -452.61519) (xy 88.123085 -452.605128) (xy 88.198869 -452.603109) (xy 88.274439 -452.609158)
			(xy 88.348937 -452.623205) (xy 88.42152 -452.645091) (xy 88.491366 -452.674568) (xy 88.557683 -452.711303)
			(xy 88.619719 -452.754878) (xy 88.676772 -452.8048) (xy 88.728196 -452.860504) (xy 88.773407 -452.921359)
			(xy 88.811894 -452.986674) (xy 88.84322 -453.05571) (xy 88.86703 -453.127685) (xy 88.883055 -453.201783)
			(xy 88.891114 -453.277164) (xy 88.891618 -453.31507) (xy 90.007697 -453.31507) (xy 90.011732 -453.239366)
			(xy 90.023791 -453.164521) (xy 90.043737 -453.09138) (xy 90.071344 -453.020775) (xy 90.1063 -452.953504)
			(xy 90.148208 -452.890329) (xy 90.196594 -452.831967) (xy 90.25091 -452.779079) (xy 90.310539 -452.732264)
			(xy 90.374807 -452.692052) (xy 90.442984 -452.6589) (xy 90.5143 -452.633182) (xy 90.587945 -452.61519)
			(xy 90.663085 -452.605128) (xy 90.738869 -452.603109) (xy 90.814439 -452.609158) (xy 90.888937 -452.623205)
			(xy 90.96152 -452.645091) (xy 91.031366 -452.674568) (xy 91.097683 -452.711303) (xy 91.159719 -452.754878)
			(xy 91.165664 -452.76008) (xy 93.154506 -452.76008) (xy 93.158522 -452.64381) (xy 93.170549 -452.528095)
			(xy 93.190531 -452.413485) (xy 93.218373 -452.300526) (xy 93.253942 -452.189758) (xy 93.297068 -452.081707)
			(xy 93.347545 -451.976889) (xy 93.405134 -451.875804) (xy 93.46956 -451.778932) (xy 93.540515 -451.686736)
			(xy 93.617662 -451.599655) (xy 93.700633 -451.518104) (xy 93.789033 -451.442472) (xy 93.88244 -451.373118)
			(xy 93.980409 -451.310375) (xy 94.082473 -451.254539) (xy 94.188147 -451.205878) (xy 94.296926 -451.164624)
			(xy 94.408291 -451.130973) (xy 94.521714 -451.105085) (xy 94.636651 -451.087084) (xy 94.752557 -451.077055)
			(xy 94.868879 -451.075047) (xy 94.985062 -451.081069) (xy 95.100553 -451.095092) (xy 95.214801 -451.11705)
			(xy 95.327262 -451.146837) (xy 95.4374 -451.184312) (xy 95.54469 -451.229297) (xy 95.648621 -451.281576)
			(xy 95.748697 -451.340901) (xy 95.844443 -451.406989) (xy 95.9354 -451.479525) (xy 96.021136 -451.558164)
			(xy 96.101243 -451.64253) (xy 96.175339 -451.732222) (xy 96.243069 -451.826812) (xy 96.304113 -451.92585)
			(xy 96.358178 -452.028863) (xy 96.405008 -452.13536) (xy 96.444379 -452.244835) (xy 96.476103 -452.356765)
			(xy 96.500029 -452.470617) (xy 96.516043 -452.585849) (xy 96.52407 -452.701911) (xy 96.524572 -452.76008)
			(xy 96.52407 -452.818249) (xy 96.516043 -452.934311) (xy 96.500029 -453.049543) (xy 96.476103 -453.163395)
			(xy 96.444379 -453.275325) (xy 96.405008 -453.3848) (xy 96.358178 -453.491297) (xy 96.304113 -453.59431)
			(xy 96.243069 -453.693348) (xy 96.175339 -453.787938) (xy 96.101243 -453.87763) (xy 96.021136 -453.961996)
			(xy 95.9354 -454.040635) (xy 95.844443 -454.113171) (xy 95.748697 -454.179259) (xy 95.648621 -454.238584)
			(xy 95.54469 -454.290863) (xy 95.4374 -454.335848) (xy 95.327262 -454.373323) (xy 95.214801 -454.40311)
			(xy 95.100553 -454.425068) (xy 94.985062 -454.439091) (xy 94.868879 -454.445113) (xy 94.752557 -454.443105)
			(xy 94.636651 -454.433076) (xy 94.521714 -454.415075) (xy 94.408291 -454.389187) (xy 94.296926 -454.355536)
			(xy 94.188147 -454.314282) (xy 94.082473 -454.265621) (xy 93.980409 -454.209785) (xy 93.88244 -454.147042)
			(xy 93.789033 -454.077688) (xy 93.700633 -454.002056) (xy 93.617662 -453.920505) (xy 93.540515 -453.833424)
			(xy 93.46956 -453.741228) (xy 93.405134 -453.644356) (xy 93.347545 -453.543271) (xy 93.297068 -453.438453)
			(xy 93.253942 -453.330402) (xy 93.218373 -453.219634) (xy 93.190531 -453.106675) (xy 93.170549 -452.992065)
			(xy 93.158522 -452.87635) (xy 93.154506 -452.76008) (xy 91.165664 -452.76008) (xy 91.216772 -452.8048)
			(xy 91.268196 -452.860504) (xy 91.313407 -452.921359) (xy 91.351894 -452.986674) (xy 91.38322 -453.05571)
			(xy 91.40703 -453.127685) (xy 91.423055 -453.201783) (xy 91.431114 -453.277164) (xy 91.431618 -453.31507)
			(xy 91.431114 -453.352976) (xy 91.423055 -453.428357) (xy 91.40703 -453.502455) (xy 91.38322 -453.57443)
			(xy 91.351894 -453.643466) (xy 91.313407 -453.708781) (xy 91.268196 -453.769636) (xy 91.216772 -453.82534)
			(xy 91.159719 -453.875262) (xy 91.097683 -453.918837) (xy 91.031366 -453.955572) (xy 90.96152 -453.985049)
			(xy 90.888937 -454.006935) (xy 90.814439 -454.020982) (xy 90.738869 -454.027031) (xy 90.663085 -454.025012)
			(xy 90.587945 -454.01495) (xy 90.5143 -453.996958) (xy 90.442984 -453.97124) (xy 90.374807 -453.938088)
			(xy 90.310539 -453.897876) (xy 90.25091 -453.851061) (xy 90.196594 -453.798173) (xy 90.148208 -453.739811)
			(xy 90.1063 -453.676636) (xy 90.071344 -453.609365) (xy 90.043737 -453.53876) (xy 90.023791 -453.465619)
			(xy 90.011732 -453.390774) (xy 90.007697 -453.31507) (xy 88.891618 -453.31507) (xy 88.891114 -453.352976)
			(xy 88.883055 -453.428357) (xy 88.86703 -453.502455) (xy 88.84322 -453.57443) (xy 88.811894 -453.643466)
			(xy 88.773407 -453.708781) (xy 88.728196 -453.769636) (xy 88.676772 -453.82534) (xy 88.619719 -453.875262)
			(xy 88.557683 -453.918837) (xy 88.491366 -453.955572) (xy 88.42152 -453.985049) (xy 88.348937 -454.006935)
			(xy 88.274439 -454.020982) (xy 88.198869 -454.027031) (xy 88.123085 -454.025012) (xy 88.047945 -454.01495)
			(xy 87.9743 -453.996958) (xy 87.902984 -453.97124) (xy 87.834807 -453.938088) (xy 87.770539 -453.897876)
			(xy 87.71091 -453.851061) (xy 87.656594 -453.798173) (xy 87.608208 -453.739811) (xy 87.5663 -453.676636)
			(xy 87.531344 -453.609365) (xy 87.503737 -453.53876) (xy 87.483791 -453.465619) (xy 87.471732 -453.390774)
			(xy 87.467697 -453.31507) (xy 86.351618 -453.31507) (xy 86.351114 -453.352976) (xy 86.343055 -453.428357)
			(xy 86.32703 -453.502455) (xy 86.30322 -453.57443) (xy 86.271894 -453.643466) (xy 86.233407 -453.708781)
			(xy 86.188196 -453.769636) (xy 86.136772 -453.82534) (xy 86.079719 -453.875262) (xy 86.017683 -453.918837)
			(xy 85.951366 -453.955572) (xy 85.88152 -453.985049) (xy 85.808937 -454.006935) (xy 85.734439 -454.020982)
			(xy 85.658869 -454.027031) (xy 85.583085 -454.025012) (xy 85.507945 -454.01495) (xy 85.4343 -453.996958)
			(xy 85.362984 -453.97124) (xy 85.294807 -453.938088) (xy 85.230539 -453.897876) (xy 85.17091 -453.851061)
			(xy 85.116594 -453.798173) (xy 85.068208 -453.739811) (xy 85.0263 -453.676636) (xy 84.991344 -453.609365)
			(xy 84.963737 -453.53876) (xy 84.943791 -453.465619) (xy 84.931732 -453.390774) (xy 84.927697 -453.31507)
			(xy 62.265544 -453.31507) (xy 62.259599 -453.320272) (xy 62.197563 -453.363847) (xy 62.131246 -453.400582)
			(xy 62.0614 -453.430059) (xy 61.988817 -453.451945) (xy 61.914319 -453.465992) (xy 61.838749 -453.472041)
			(xy 61.762965 -453.470022) (xy 61.687825 -453.45996) (xy 61.61418 -453.441968) (xy 61.542864 -453.41625)
			(xy 61.474687 -453.383098) (xy 61.410419 -453.342886) (xy 61.35079 -453.296071) (xy 61.296474 -453.243183)
			(xy 61.248088 -453.184821) (xy 61.20618 -453.121646) (xy 61.171224 -453.054375) (xy 61.143617 -452.98377)
			(xy 61.123671 -452.910629) (xy 61.111612 -452.835784) (xy 61.107577 -452.76008) (xy 59.991498 -452.76008)
			(xy 59.990994 -452.797986) (xy 59.982935 -452.873367) (xy 59.96691 -452.947465) (xy 59.9431 -453.01944)
			(xy 59.911774 -453.088476) (xy 59.873287 -453.153791) (xy 59.828076 -453.214646) (xy 59.776652 -453.27035)
			(xy 59.719599 -453.320272) (xy 59.657563 -453.363847) (xy 59.591246 -453.400582) (xy 59.5214 -453.430059)
			(xy 59.448817 -453.451945) (xy 59.374319 -453.465992) (xy 59.298749 -453.472041) (xy 59.222965 -453.470022)
			(xy 59.147825 -453.45996) (xy 59.07418 -453.441968) (xy 59.002864 -453.41625) (xy 58.934687 -453.383098)
			(xy 58.870419 -453.342886) (xy 58.81079 -453.296071) (xy 58.756474 -453.243183) (xy 58.708088 -453.184821)
			(xy 58.66618 -453.121646) (xy 58.631224 -453.054375) (xy 58.603617 -452.98377) (xy 58.583671 -452.910629)
			(xy 58.571612 -452.835784) (xy 58.567577 -452.76008) (xy 57.451498 -452.76008) (xy 57.450994 -452.797986)
			(xy 57.442935 -452.873367) (xy 57.42691 -452.947465) (xy 57.4031 -453.01944) (xy 57.371774 -453.088476)
			(xy 57.333287 -453.153791) (xy 57.288076 -453.214646) (xy 57.236652 -453.27035) (xy 57.179599 -453.320272)
			(xy 57.117563 -453.363847) (xy 57.051246 -453.400582) (xy 56.9814 -453.430059) (xy 56.908817 -453.451945)
			(xy 56.834319 -453.465992) (xy 56.758749 -453.472041) (xy 56.682965 -453.470022) (xy 56.607825 -453.45996)
			(xy 56.53418 -453.441968) (xy 56.462864 -453.41625) (xy 56.394687 -453.383098) (xy 56.330419 -453.342886)
			(xy 56.27079 -453.296071) (xy 56.216474 -453.243183) (xy 56.168088 -453.184821) (xy 56.12618 -453.121646)
			(xy 56.091224 -453.054375) (xy 56.063617 -452.98377) (xy 56.043671 -452.910629) (xy 56.031612 -452.835784)
			(xy 56.027577 -452.76008) (xy 54.911498 -452.76008) (xy 54.910994 -452.797986) (xy 54.902935 -452.873367)
			(xy 54.88691 -452.947465) (xy 54.8631 -453.01944) (xy 54.831774 -453.088476) (xy 54.793287 -453.153791)
			(xy 54.748076 -453.214646) (xy 54.696652 -453.27035) (xy 54.639599 -453.320272) (xy 54.577563 -453.363847)
			(xy 54.511246 -453.400582) (xy 54.4414 -453.430059) (xy 54.368817 -453.451945) (xy 54.294319 -453.465992)
			(xy 54.218749 -453.472041) (xy 54.142965 -453.470022) (xy 54.067825 -453.45996) (xy 53.99418 -453.441968)
			(xy 53.922864 -453.41625) (xy 53.854687 -453.383098) (xy 53.790419 -453.342886) (xy 53.73079 -453.296071)
			(xy 53.676474 -453.243183) (xy 53.628088 -453.184821) (xy 53.58618 -453.121646) (xy 53.551224 -453.054375)
			(xy 53.523617 -452.98377) (xy 53.503671 -452.910629) (xy 53.491612 -452.835784) (xy 53.487577 -452.76008)
			(xy 52.371498 -452.76008) (xy 52.370994 -452.797986) (xy 52.362935 -452.873367) (xy 52.34691 -452.947465)
			(xy 52.3231 -453.01944) (xy 52.291774 -453.088476) (xy 52.253287 -453.153791) (xy 52.208076 -453.214646)
			(xy 52.156652 -453.27035) (xy 52.099599 -453.320272) (xy 52.037563 -453.363847) (xy 51.971246 -453.400582)
			(xy 51.9014 -453.430059) (xy 51.828817 -453.451945) (xy 51.754319 -453.465992) (xy 51.678749 -453.472041)
			(xy 51.602965 -453.470022) (xy 51.527825 -453.45996) (xy 51.45418 -453.441968) (xy 51.382864 -453.41625)
			(xy 51.314687 -453.383098) (xy 51.250419 -453.342886) (xy 51.19079 -453.296071) (xy 51.136474 -453.243183)
			(xy 51.088088 -453.184821) (xy 51.04618 -453.121646) (xy 51.011224 -453.054375) (xy 50.983617 -452.98377)
			(xy 50.963671 -452.910629) (xy 50.951612 -452.835784) (xy 50.947577 -452.76008) (xy 49.831498 -452.76008)
			(xy 49.830994 -452.797986) (xy 49.822935 -452.873367) (xy 49.80691 -452.947465) (xy 49.7831 -453.01944)
			(xy 49.751774 -453.088476) (xy 49.713287 -453.153791) (xy 49.668076 -453.214646) (xy 49.616652 -453.27035)
			(xy 49.559599 -453.320272) (xy 49.497563 -453.363847) (xy 49.431246 -453.400582) (xy 49.3614 -453.430059)
			(xy 49.288817 -453.451945) (xy 49.214319 -453.465992) (xy 49.138749 -453.472041) (xy 49.062965 -453.470022)
			(xy 48.987825 -453.45996) (xy 48.91418 -453.441968) (xy 48.842864 -453.41625) (xy 48.774687 -453.383098)
			(xy 48.710419 -453.342886) (xy 48.65079 -453.296071) (xy 48.596474 -453.243183) (xy 48.548088 -453.184821)
			(xy 48.50618 -453.121646) (xy 48.471224 -453.054375) (xy 48.443617 -452.98377) (xy 48.423671 -452.910629)
			(xy 48.411612 -452.835784) (xy 48.407577 -452.76008) (xy 47.291498 -452.76008) (xy 47.290994 -452.797986)
			(xy 47.282935 -452.873367) (xy 47.26691 -452.947465) (xy 47.2431 -453.01944) (xy 47.211774 -453.088476)
			(xy 47.173287 -453.153791) (xy 47.128076 -453.214646) (xy 47.076652 -453.27035) (xy 47.019599 -453.320272)
			(xy 46.957563 -453.363847) (xy 46.891246 -453.400582) (xy 46.8214 -453.430059) (xy 46.748817 -453.451945)
			(xy 46.674319 -453.465992) (xy 46.598749 -453.472041) (xy 46.522965 -453.470022) (xy 46.447825 -453.45996)
			(xy 46.37418 -453.441968) (xy 46.302864 -453.41625) (xy 46.234687 -453.383098) (xy 46.170419 -453.342886)
			(xy 46.11079 -453.296071) (xy 46.056474 -453.243183) (xy 46.008088 -453.184821) (xy 45.96618 -453.121646)
			(xy 45.931224 -453.054375) (xy 45.903617 -452.98377) (xy 45.883671 -452.910629) (xy 45.871612 -452.835784)
			(xy 45.867577 -452.76008) (xy 44.751244 -452.76008) (xy 44.751244 -453.471788) (xy 43.328336 -453.471788)
			(xy 43.328336 -452.048372) (xy 43.055094 -452.048372) (xy 43.053462 -452.052742) (xy 43.004999 -452.159253)
			(xy 42.949245 -452.262135) (xy 42.886471 -452.360891) (xy 42.816981 -452.455042) (xy 42.741111 -452.544132)
			(xy 42.659229 -452.627729) (xy 42.571732 -452.70543) (xy 42.479042 -452.776857) (xy 42.381609 -452.841665)
			(xy 42.279905 -452.89954) (xy 42.174422 -452.950202) (xy 42.065671 -452.993404) (xy 41.954179 -453.028939)
			(xy 41.840485 -453.056634) (xy 41.725141 -453.076354) (xy 41.608704 -453.088005) (xy 41.491739 -453.09153)
			(xy 41.374812 -453.086912) (xy 41.258489 -453.074173) (xy 41.143334 -453.053375) (xy 41.029905 -453.024618)
			(xy 40.91875 -452.988042) (xy 40.810407 -452.943825) (xy 40.705403 -452.892179) (xy 40.604244 -452.833356)
			(xy 40.507421 -452.76764) (xy 40.415403 -452.695349) (xy 40.328636 -452.616834) (xy 40.247539 -452.532474)
			(xy 40.172506 -452.442679) (xy 40.103899 -452.347883) (xy 40.042051 -452.248544) (xy 39.987262 -452.145145)
			(xy 39.939796 -452.038186) (xy 39.899884 -451.928185) (xy 39.86772 -451.815674) (xy 39.843457 -451.701199)
			(xy 39.827215 -451.585313) (xy 39.819072 -451.468579) (xy 39.818564 -451.41007) (xy 36.442855 -451.41007)
			(xy 36.4555 -451.454513) (xy 36.471468 -451.539933) (xy 36.479486 -451.626462) (xy 36.479988 -451.669912)
			(xy 36.479486 -451.713362) (xy 36.471468 -451.799891) (xy 36.4555 -451.885311) (xy 36.431719 -451.968893)
			(xy 36.400327 -452.049925) (xy 36.361593 -452.127714) (xy 36.315846 -452.201598) (xy 36.263477 -452.270945)
			(xy 36.204933 -452.335165) (xy 36.140713 -452.393709) (xy 36.071366 -452.446078) (xy 35.997482 -452.491825)
			(xy 35.919693 -452.530559) (xy 35.838661 -452.561951) (xy 35.755079 -452.585732) (xy 35.669659 -452.6017)
			(xy 35.58313 -452.609718) (xy 35.49623 -452.609718) (xy 35.409701 -452.6017) (xy 35.324281 -452.585732)
			(xy 35.240699 -452.561951) (xy 35.159667 -452.530559) (xy 35.081878 -452.491825) (xy 35.007994 -452.446078)
			(xy 34.938647 -452.393709) (xy 34.874427 -452.335165) (xy 34.815883 -452.270945) (xy 34.763514 -452.201598)
			(xy 34.717767 -452.127714) (xy 34.679033 -452.049925) (xy 34.647641 -451.968893) (xy 34.62386 -451.885311)
			(xy 34.607892 -451.799891) (xy 34.599874 -451.713362) (xy 31.79826 -451.713362) (xy 31.79826 -454.209889)
			(xy 34.598818 -454.209889) (xy 34.602752 -454.123939) (xy 34.614523 -454.038708) (xy 34.634029 -453.954909)
			(xy 34.661109 -453.873242) (xy 34.695537 -453.79439) (xy 34.737023 -453.719013) (xy 34.785222 -453.647741)
			(xy 34.83973 -453.58117) (xy 34.900091 -453.519856) (xy 34.965801 -453.464313) (xy 35.03631 -453.415005)
			(xy 35.111029 -453.372343) (xy 35.189332 -453.336686) (xy 35.270565 -453.308331) (xy 35.354049 -453.287515)
			(xy 35.439085 -453.274413) (xy 35.524963 -453.269133) (xy 35.610964 -453.27172) (xy 35.696369 -453.282153)
			(xy 35.780464 -453.300344) (xy 35.862545 -453.32614) (xy 35.941927 -453.359328) (xy 36.017945 -453.399627)
			(xy 36.089964 -453.446703) (xy 36.157381 -453.500161) (xy 36.219634 -453.559554) (xy 36.2762 -453.624385)
			(xy 36.326607 -453.694113) (xy 36.370434 -453.768153) (xy 36.38931 -453.806814) (xy 36.405058 -453.839834)
			(xy 36.467034 -453.879204) (xy 37.323776 -453.879204) (xy 40.069516 -456.624944) (xy 40.069516 -457.216002)
			(xy 40.082216 -457.242164) (xy 40.09429 -457.268214) (xy 40.111295 -457.323054) (xy 40.119892 -457.379823)
			(xy 40.119888 -457.437239) (xy 40.111281 -457.494006) (xy 40.094268 -457.548843) (xy 40.082216 -457.574904)
			(xy 40.069516 -457.601066) (xy 40.069516 -458.40396) (xy 40.070009 -458.426526) (xy 40.078023 -458.470942)
			(xy 40.093753 -458.513245) (xy 40.116706 -458.552107) (xy 40.146159 -458.586305) (xy 40.181188 -458.614765)
			(xy 40.220692 -458.636594) (xy 40.263429 -458.651105) (xy 40.308056 -458.657842) (xy 40.330628 -458.657706)
			(xy 40.34536 -458.657452) (xy 41.18356 -458.657452) (xy 41.215521 -458.65801) (xy 41.278941 -458.666018)
			(xy 41.340857 -458.68191) (xy 41.400292 -458.705438) (xy 41.45631 -458.736231) (xy 41.508026 -458.773801)
			(xy 41.554626 -458.817557) (xy 41.595373 -458.866809) (xy 41.629626 -458.92078) (xy 41.656845 -458.978619)
			(xy 41.676599 -459.039413) (xy 41.688578 -459.102203) (xy 41.692592 -459.166) (xy 41.688578 -459.229797)
			(xy 41.676599 -459.292587) (xy 41.656845 -459.353381) (xy 41.629626 -459.41122) (xy 41.595373 -459.465191)
			(xy 41.554626 -459.514443) (xy 41.508026 -459.558199) (xy 41.45631 -459.595769) (xy 41.400292 -459.626562)
			(xy 41.340857 -459.65009) (xy 41.278941 -459.665982) (xy 41.215521 -459.67399) (xy 41.18356 -459.674468)
			(xy 40.34536 -459.674468) (xy 40.312658 -459.673968) (xy 40.247794 -459.66557) (xy 40.184544 -459.648918)
			(xy 40.123955 -459.624286) (xy 40.067027 -459.592083) (xy 40.04056 -459.572868) (xy 40.006778 -459.547468)
			(xy 39.189152 -459.547468) (xy 39.189152 -458.784452) (xy 39.214552 -458.784452) (xy 39.214552 -458.571854)
			(xy 39.4081 -458.378306) (xy 39.4081 -457.601066) (xy 39.3954 -457.574904) (xy 39.383375 -457.548832)
			(xy 39.366362 -457.493999) (xy 39.357756 -457.437236) (xy 39.357752 -457.379825) (xy 39.366349 -457.32306)
			(xy 39.383353 -457.268225) (xy 39.3954 -457.242164) (xy 39.4081 -457.216002) (xy 39.4081 -456.898756)
			(xy 37.049964 -454.54062) (xy 36.467034 -454.54062) (xy 36.405058 -454.57999) (xy 36.38931 -454.61301)
			(xy 36.370424 -454.651666) (xy 36.326595 -454.725706) (xy 36.276186 -454.795432) (xy 36.219619 -454.860262)
			(xy 36.157365 -454.919653) (xy 36.089946 -454.97311) (xy 36.017926 -455.020184) (xy 35.941907 -455.060482)
			(xy 35.862525 -455.093667) (xy 35.780443 -455.119462) (xy 35.696347 -455.137651) (xy 35.610942 -455.148081)
			(xy 35.524941 -455.150667) (xy 35.439064 -455.145385) (xy 35.354028 -455.13228) (xy 35.270545 -455.111463)
			(xy 35.189312 -455.083106) (xy 35.11101 -455.047447) (xy 35.036292 -455.004784) (xy 34.965784 -454.955474)
			(xy 34.900075 -454.899929) (xy 34.839715 -454.838614) (xy 34.785209 -454.772042) (xy 34.737012 -454.700768)
			(xy 34.695527 -454.62539) (xy 34.661102 -454.546538) (xy 34.634023 -454.46487) (xy 34.614519 -454.38107)
			(xy 34.602751 -454.295839) (xy 34.598818 -454.209889) (xy 31.79826 -454.209889) (xy 31.79826 -456.793362)
			(xy 34.599874 -456.793362) (xy 34.599874 -456.706462) (xy 34.607892 -456.619933) (xy 34.62386 -456.534513)
			(xy 34.647641 -456.450931) (xy 34.679033 -456.369899) (xy 34.717767 -456.29211) (xy 34.763514 -456.218226)
			(xy 34.815883 -456.148879) (xy 34.874427 -456.084659) (xy 34.938647 -456.026115) (xy 35.007994 -455.973746)
			(xy 35.081878 -455.927999) (xy 35.159667 -455.889265) (xy 35.240699 -455.857873) (xy 35.324281 -455.834092)
			(xy 35.409701 -455.818124) (xy 35.49623 -455.810106) (xy 35.58313 -455.810106) (xy 35.669659 -455.818124)
			(xy 35.755079 -455.834092) (xy 35.838661 -455.857873) (xy 35.919693 -455.889265) (xy 35.997482 -455.927999)
			(xy 36.071366 -455.973746) (xy 36.140713 -456.026115) (xy 36.204933 -456.084659) (xy 36.263477 -456.148879)
			(xy 36.315846 -456.218226) (xy 36.361593 -456.29211) (xy 36.400327 -456.369899) (xy 36.431719 -456.450931)
			(xy 36.4555 -456.534513) (xy 36.471468 -456.619933) (xy 36.479486 -456.706462) (xy 36.479988 -456.749912)
			(xy 36.479486 -456.793362) (xy 36.471468 -456.879891) (xy 36.4555 -456.965311) (xy 36.431719 -457.048893)
			(xy 36.400327 -457.129925) (xy 36.361593 -457.207714) (xy 36.315846 -457.281598) (xy 36.263477 -457.350945)
			(xy 36.204933 -457.415165) (xy 36.140713 -457.473709) (xy 36.071366 -457.526078) (xy 35.997482 -457.571825)
			(xy 35.919693 -457.610559) (xy 35.838661 -457.641951) (xy 35.755079 -457.665732) (xy 35.669659 -457.6817)
			(xy 35.58313 -457.689718) (xy 35.49623 -457.689718) (xy 35.409701 -457.6817) (xy 35.324281 -457.665732)
			(xy 35.240699 -457.641951) (xy 35.159667 -457.610559) (xy 35.081878 -457.571825) (xy 35.007994 -457.526078)
			(xy 34.938647 -457.473709) (xy 34.874427 -457.415165) (xy 34.815883 -457.350945) (xy 34.763514 -457.281598)
			(xy 34.717767 -457.207714) (xy 34.679033 -457.129925) (xy 34.647641 -457.048893) (xy 34.62386 -456.965311)
			(xy 34.607892 -456.879891) (xy 34.599874 -456.793362) (xy 31.79826 -456.793362) (xy 31.79826 -456.91679)
			(xy 32.313626 -457.432156) (xy 34.182304 -459.30058) (xy 34.199181 -459.316089) (xy 34.237409 -459.341367)
			(xy 34.279552 -459.35938) (xy 34.324242 -459.369542) (xy 34.370029 -459.371524) (xy 34.41543 -459.365263)
			(xy 34.458972 -459.350961) (xy 34.499243 -459.329081) (xy 34.534936 -459.300334) (xy 34.564895 -459.265651)
			(xy 34.588149 -459.226158) (xy 34.603942 -459.183134) (xy 34.608262 -459.160626) (xy 34.613917 -459.122649)
			(xy 34.630646 -459.047707) (xy 34.653444 -458.974382) (xy 34.667444 -458.93863) (xy 34.685175 -458.896082)
			(xy 34.727797 -458.814347) (xy 34.778215 -458.737175) (xy 34.806636 -458.700886) (xy 34.833586 -458.668066)
			(xy 34.892507 -458.606901) (xy 34.956704 -458.551298) (xy 35.025653 -458.501712) (xy 35.098794 -458.458546)
			(xy 35.175529 -458.422151) (xy 35.255234 -458.392826) (xy 35.337259 -458.370807) (xy 35.420935 -458.356276)
			(xy 35.505581 -458.34935) (xy 35.590506 -458.350086) (xy 35.675019 -458.358478) (xy 35.758431 -458.374457)
			(xy 35.840062 -458.397893) (xy 35.919247 -458.428596) (xy 35.99534 -458.466315) (xy 36.067722 -458.510742)
			(xy 36.135802 -458.561516) (xy 36.199025 -458.618223) (xy 36.256877 -458.6804) (xy 36.308886 -458.747541)
			(xy 36.354628 -458.819099) (xy 36.374578 -458.856588) (xy 36.390326 -458.887068) (xy 36.503864 -458.959204)
			(xy 38.188392 -458.959204) (xy 39.805356 -460.576168) (xy 39.805356 -460.635096) (xy 39.805899 -460.651747)
			(xy 39.814515 -460.683914) (xy 39.831162 -460.712757) (xy 39.854705 -460.736309) (xy 39.883541 -460.752967)
			(xy 39.915705 -460.761595) (xy 39.932356 -460.762096) (xy 39.969694 -460.762096) (xy 40.000936 -460.74203)
			(xy 40.010672 -460.735858) (xy 40.030619 -460.724297) (xy 40.040814 -460.718916) (xy 40.067351 -460.705619)
			(xy 40.122867 -460.684612) (xy 40.151558 -460.677006) (xy 40.165264 -460.673669) (xy 40.192965 -460.668331)
			(xy 40.20693 -460.666338) (xy 40.243252 -460.662782) (xy 40.250364 -460.662528) (xy 40.277034 -460.66202)
			(xy 40.89527 -460.664306) (xy 41.395396 -460.666338) (xy 41.40327 -460.665322) (xy 41.433218 -460.66212)
			(xy 41.49345 -460.661993) (xy 41.523412 -460.665068) (xy 41.551593 -460.668692) (xy 41.606969 -460.68142)
			(xy 41.660577 -460.700256) (xy 41.711745 -460.724962) (xy 41.73601 -460.739744) (xy 41.761664 -460.757016)
			(xy 41.78353 -460.773119) (xy 41.824048 -460.809281) (xy 41.860476 -460.849558) (xy 41.876726 -460.871316)
			(xy 41.895154 -460.897452) (xy 41.926004 -460.95347) (xy 41.94958 -461.012917) (xy 41.965509 -461.074853)
			(xy 41.973538 -461.138298) (xy 41.974008 -461.170274) (xy 41.974008 -461.1751) (xy 41.973463 -461.208758)
			(xy 41.96458 -461.275484) (xy 41.946968 -461.340455) (xy 41.920937 -461.402534) (xy 41.886941 -461.460634)
			(xy 41.845575 -461.51374) (xy 41.797562 -461.560922) (xy 41.743743 -461.601356) (xy 41.714674 -461.61833)
			(xy 41.704536 -461.623949) (xy 41.683827 -461.634368) (xy 41.673272 -461.639158) (xy 41.640126 -461.653272)
			(xy 41.570858 -461.673067) (xy 41.499491 -461.68289) (xy 41.463468 -461.683354) (xy 40.93591 -461.681322)
			(xy 40.732202 -461.68056) (xy 40.715476 -461.680958) (xy 40.683123 -461.689443) (xy 40.654085 -461.706041)
			(xy 40.630356 -461.729613) (xy 40.613565 -461.758541) (xy 40.604866 -461.790837) (xy 40.60444 -461.80756)
			(xy 40.60444 -461.91043) (xy 40.630094 -461.936084) (xy 40.630094 -462.273904) (xy 51.322732 -462.273904)
			(xy 52.974748 -462.273904) (xy 52.974748 -463.925412) (xy 51.322732 -463.925412) (xy 51.322732 -462.273904)
			(xy 40.630094 -462.273904) (xy 40.630094 -462.752948) (xy 40.08374 -462.752948) (xy 40.067084 -462.753438)
			(xy 40.034906 -462.762053) (xy 40.006056 -462.778707) (xy 39.982502 -462.802262) (xy 39.96585 -462.831113)
			(xy 39.957237 -462.863292) (xy 39.95674 -462.879948) (xy 39.95674 -462.903824) (xy 39.943532 -462.96961)
			(xy 39.960804 -463.011012) (xy 39.966964 -463.024644) (xy 39.984629 -463.048776) (xy 40.007427 -463.068131)
			(xy 40.034106 -463.081645) (xy 40.063198 -463.088575) (xy 40.078152 -463.08899) (xy 40.40505 -463.08899)
			(xy 40.43668 -463.089482) (xy 40.499399 -463.097735) (xy 40.560504 -463.114108) (xy 40.618948 -463.138318)
			(xy 40.62223 -463.140213) (xy 47.82311 -463.140213) (xy 47.82311 -463.059103) (xy 47.83106 -462.978384)
			(xy 47.846883 -462.898833) (xy 47.870428 -462.821217) (xy 47.901467 -462.746281) (xy 47.939702 -462.674749)
			(xy 47.984764 -462.607309) (xy 48.036219 -462.54461) (xy 48.093572 -462.487257) (xy 48.156271 -462.435802)
			(xy 48.223711 -462.39074) (xy 48.295243 -462.352505) (xy 48.370179 -462.321466) (xy 48.447795 -462.297921)
			(xy 48.527346 -462.282098) (xy 48.608065 -462.274148) (xy 48.689175 -462.274148) (xy 48.769894 -462.282098)
			(xy 48.849445 -462.297921) (xy 48.927061 -462.321466) (xy 49.001997 -462.352505) (xy 49.073529 -462.39074)
			(xy 49.140969 -462.435802) (xy 49.203668 -462.487257) (xy 49.261021 -462.54461) (xy 49.312476 -462.607309)
			(xy 49.357538 -462.674749) (xy 49.395773 -462.746281) (xy 49.426812 -462.821217) (xy 49.450357 -462.898833)
			(xy 49.46618 -462.978384) (xy 49.47413 -463.059103) (xy 49.474628 -463.099658) (xy 49.47413 -463.140213)
			(xy 49.46618 -463.220932) (xy 49.450357 -463.300483) (xy 49.426812 -463.378099) (xy 49.395773 -463.453035)
			(xy 49.357538 -463.524567) (xy 49.312476 -463.592007) (xy 49.261021 -463.654706) (xy 49.203668 -463.712059)
			(xy 49.140969 -463.763514) (xy 49.073529 -463.808576) (xy 49.001997 -463.846811) (xy 48.927061 -463.87785)
			(xy 48.849445 -463.901395) (xy 48.769894 -463.917218) (xy 48.689175 -463.925168) (xy 48.608065 -463.925168)
			(xy 48.527346 -463.917218) (xy 48.447795 -463.901395) (xy 48.370179 -463.87785) (xy 48.295243 -463.846811)
			(xy 48.223711 -463.808576) (xy 48.156271 -463.763514) (xy 48.093572 -463.712059) (xy 48.036219 -463.654706)
			(xy 47.984764 -463.592007) (xy 47.939702 -463.524567) (xy 47.901467 -463.453035) (xy 47.870428 -463.378099)
			(xy 47.846883 -463.300483) (xy 47.83106 -463.220932) (xy 47.82311 -463.140213) (xy 40.62223 -463.140213)
			(xy 40.67373 -463.169952) (xy 40.723913 -463.208468) (xy 40.768637 -463.253207) (xy 40.807137 -463.303403)
			(xy 40.823388 -463.330544) (xy 40.838316 -463.357348) (xy 40.862022 -463.413937) (xy 40.878367 -463.473074)
			(xy 40.887088 -463.533805) (xy 40.888045 -463.595152) (xy 40.88511 -463.625692) (xy 40.88224 -463.648923)
			(xy 40.872574 -463.694725) (xy 40.865806 -463.717132) (xy 40.853868 -463.750152) (xy 40.841578 -463.779723)
			(xy 40.810305 -463.835606) (xy 40.77192 -463.886865) (xy 40.727097 -463.932601) (xy 40.676622 -463.972011)
			(xy 40.621381 -464.004404) (xy 40.562343 -464.029211) (xy 40.500544 -464.045997) (xy 40.437069 -464.054468)
			(xy 40.40505 -464.054952) (xy 40.275764 -464.054952) (xy 40.253948 -464.057218) (xy 40.211508 -464.068279)
			(xy 40.171596 -464.08646) (xy 40.135396 -464.11122) (xy 40.103984 -464.141826) (xy 40.078289 -464.177369)
			(xy 40.059077 -464.216795) (xy 40.046915 -464.258932) (xy 40.042166 -464.302532) (xy 40.0431 -464.324446)
			(xy 40.044878 -464.357466) (xy 40.044878 -464.36661) (xy 40.044898 -464.380475) (xy 40.043625 -464.408176)
			(xy 40.042338 -464.421982) (xy 40.041793 -464.444814) (xy 40.047925 -464.490067) (xy 40.062042 -464.533496)
			(xy 40.083693 -464.573704) (xy 40.112178 -464.609397) (xy 40.146583 -464.639426) (xy 40.185799 -464.662825)
			(xy 40.228565 -464.678841) (xy 40.273504 -464.686958) (xy 40.296338 -464.687412) (xy 40.594788 -464.687412)
			(xy 40.626419 -464.687906) (xy 40.689141 -464.696162) (xy 40.750248 -464.712535) (xy 40.808696 -464.736743)
			(xy 40.863483 -464.768373) (xy 40.913674 -464.806885) (xy 40.958408 -464.851617) (xy 40.99692 -464.901807)
			(xy 41.028552 -464.956593) (xy 41.052762 -465.01504) (xy 41.069135 -465.076147) (xy 41.077393 -465.138869)
			(xy 41.077393 -465.202131) (xy 41.069135 -465.264853) (xy 41.052762 -465.32596) (xy 41.028552 -465.384407)
			(xy 40.99692 -465.439193) (xy 40.958408 -465.489383) (xy 40.913674 -465.534115) (xy 40.863483 -465.572627)
			(xy 40.808696 -465.604257) (xy 40.750248 -465.628465) (xy 40.689141 -465.644838) (xy 40.626419 -465.653094)
			(xy 40.594788 -465.653628) (xy 39.51478 -465.653628) (xy 39.484902 -465.653185) (xy 39.425603 -465.64582)
			(xy 39.367666 -465.631191) (xy 39.311978 -465.609524) (xy 39.25939 -465.581148) (xy 39.210706 -465.546499)
			(xy 39.18839 -465.526628) (xy 39.133272 -465.526628) (xy 39.133272 -465.469224) (xy 39.11219 -465.43722)
			(xy 39.101522 -465.420456) (xy 39.088822 -465.398358) (xy 39.07155 -465.362544) (xy 39.058817 -465.331797)
			(xy 39.040976 -465.267685) (xy 39.03599 -465.234782) (xy 39.033547 -465.215068) (xy 39.031513 -465.175394)
			(xy 39.031926 -465.155534) (xy 39.032434 -465.145374) (xy 39.033107 -465.122474) (xy 39.027192 -465.077047)
			(xy 39.013233 -465.033415) (xy 38.991681 -464.992991) (xy 38.963233 -464.957084) (xy 38.928812 -464.926855)
			(xy 38.889531 -464.903284) (xy 38.846662 -464.887134) (xy 38.801593 -464.878927) (xy 38.778688 -464.87842)
			(xy 36.397184 -464.87842) (xy 36.2966 -464.928966) (xy 36.279074 -464.951318) (xy 36.251834 -464.98517)
			(xy 36.19207 -465.048248) (xy 36.12674 -465.105544) (xy 36.056403 -465.156568) (xy 35.981659 -465.200886)
			(xy 35.903145 -465.238118) (xy 35.82153 -465.267948) (xy 35.737512 -465.290121) (xy 35.651806 -465.304448)
			(xy 35.565144 -465.310807) (xy 35.478265 -465.309143) (xy 35.39191 -465.299471) (xy 35.306816 -465.281873)
			(xy 35.223708 -465.256499) (xy 35.143295 -465.223566) (xy 35.066264 -465.183355) (xy 34.993272 -465.136209)
			(xy 34.92494 -465.082529) (xy 34.861852 -465.022774) (xy 34.804546 -464.957453) (xy 34.753511 -464.887124)
			(xy 34.709182 -464.812387) (xy 34.671938 -464.733878) (xy 34.642095 -464.652268) (xy 34.619909 -464.568253)
			(xy 34.605569 -464.48255) (xy 34.601912 -464.439254) (xy 34.600558 -464.419599) (xy 34.599288 -464.380216)
			(xy 34.599372 -464.360514) (xy 34.6004 -464.313966) (xy 34.610522 -464.221406) (xy 34.629748 -464.130301)
			(xy 34.657888 -464.041543) (xy 34.694667 -463.956003) (xy 34.71672 -463.914998) (xy 34.726683 -463.893731)
			(xy 34.739495 -463.848555) (xy 34.74379 -463.801794) (xy 34.739419 -463.75504) (xy 34.726534 -463.709885)
			(xy 34.705571 -463.667866) (xy 34.677244 -463.630414) (xy 34.642519 -463.598803) (xy 34.602578 -463.574112)
			(xy 34.558779 -463.557178) (xy 34.512615 -463.548581) (xy 34.489136 -463.547968) (xy 34.284158 -463.547968)
			(xy 31.73857 -461.002126) (xy 31.726435 -460.990668) (xy 31.697556 -460.973962) (xy 31.665335 -460.965306)
			(xy 31.648654 -460.964788) (xy 31.477966 -460.964788) (xy 31.455983 -460.965935) (xy 31.41288 -460.974852)
			(xy 31.371958 -460.991061) (xy 31.334441 -461.014079) (xy 31.30145 -461.043216) (xy 31.273973 -461.077602)
			(xy 31.252831 -461.116207) (xy 31.238656 -461.157878) (xy 31.231873 -461.201367) (xy 31.232684 -461.245375)
			(xy 31.241065 -461.288586) (xy 31.256765 -461.329706) (xy 31.267654 -461.348836) (xy 31.291276 -461.391)
			(xy 31.315152 -461.439514) (xy 31.332589 -461.478886) (xy 31.361029 -461.56017) (xy 31.381918 -461.643714)
			(xy 31.395081 -461.728817) (xy 31.400407 -461.814768) (xy 31.397852 -461.900846) (xy 31.387437 -461.986329)
			(xy 31.369249 -462.070502) (xy 31.343441 -462.15266) (xy 31.310229 -462.232113) (xy 31.269892 -462.308197)
			(xy 31.222766 -462.380274) (xy 31.169248 -462.44774) (xy 31.109784 -462.51003) (xy 31.044875 -462.566622)
			(xy 30.975063 -462.617042) (xy 30.900933 -462.660867) (xy 30.823106 -462.697731) (xy 30.742235 -462.727324)
			(xy 30.658997 -462.749398) (xy 30.574089 -462.763769) (xy 30.488223 -462.770317) (xy 30.402117 -462.768985)
			(xy 30.316494 -462.759786) (xy 30.232071 -462.742797) (xy 30.149555 -462.71816) (xy 30.069638 -462.68608)
			(xy 29.992988 -462.646828) (xy 29.920249 -462.600732) (xy 29.852029 -462.548178) (xy 29.7889 -462.489607)
			(xy 29.731391 -462.425508) (xy 29.7053 -462.391252) (xy 29.704538 -462.390236) (xy 29.687012 -462.366868)
			(xy 29.583888 -462.31302) (xy 28.37434 -462.31302) (xy 28.350958 -462.313549) (xy 28.304982 -462.322101)
			(xy 28.261349 -462.338923) (xy 28.221531 -462.363447) (xy 28.186874 -462.394844) (xy 28.158549 -462.432055)
			(xy 28.137514 -462.47382) (xy 28.124477 -462.518731) (xy 28.119881 -462.565269) (xy 28.121356 -462.58861)
			(xy 28.122626 -462.609184) (xy 28.12288 -462.61655) (xy 28.12288 -463.41538) (xy 28.122363 -463.446994)
			(xy 28.11411 -463.509681) (xy 28.097746 -463.570755) (xy 28.073549 -463.62917) (xy 28.041935 -463.683927)
			(xy 28.003444 -463.734089) (xy 27.958735 -463.778798) (xy 27.908573 -463.817289) (xy 27.853816 -463.848903)
			(xy 27.795401 -463.8731) (xy 27.734327 -463.889464) (xy 27.67164 -463.897717) (xy 27.608412 -463.897717)
			(xy 27.545725 -463.889464) (xy 27.484651 -463.8731) (xy 27.426236 -463.848903) (xy 27.371479 -463.817289)
			(xy 27.321317 -463.778798) (xy 27.276608 -463.734089) (xy 27.238117 -463.683927) (xy 27.206503 -463.62917)
			(xy 27.182306 -463.570755) (xy 27.165942 -463.509681) (xy 27.157689 -463.446994) (xy 27.157172 -463.41538)
			(xy 27.157172 -462.614518) (xy 27.15768 -462.603596) (xy 27.157934 -462.599024) (xy 27.15895 -462.586578)
			(xy 27.160468 -462.564399) (xy 27.156655 -462.520112) (xy 27.145194 -462.477163) (xy 27.126433 -462.436865)
			(xy 27.100947 -462.400446) (xy 27.069511 -462.369017) (xy 27.033086 -462.343538) (xy 26.992784 -462.324787)
			(xy 26.949833 -462.313335) (xy 26.905544 -462.309532) (xy 26.88336 -462.310988) (xy 26.866314 -462.312368)
			(xy 26.832119 -462.313002) (xy 26.815034 -462.312258) (xy 26.79065 -462.31048) (xy 26.767536 -462.307432)
			(xy 26.733029 -462.30155) (xy 26.66607 -462.281147) (xy 26.60275 -462.251308) (xy 26.573226 -462.232502)
			(xy 26.541222 -462.21142) (xy 26.483818 -462.21142) (xy 26.483818 -462.159096) (xy 26.457402 -462.124806)
			(xy 26.450544 -462.115662) (xy 26.449274 -462.114138) (xy 26.435266 -462.09436) (xy 26.410837 -462.052497)
			(xy 26.400506 -462.030572) (xy 26.386282 -461.995774) (xy 26.376995 -461.969121) (xy 26.363979 -461.914199)
			(xy 26.35745 -461.858134) (xy 26.357072 -461.829912) (xy 26.357072 -461.067658) (xy 26.357502 -461.037792)
			(xy 26.364839 -460.978512) (xy 26.379431 -460.920591) (xy 26.401058 -460.864911) (xy 26.429387 -460.812325)
			(xy 26.463987 -460.763635) (xy 26.504328 -460.719584) (xy 26.549795 -460.680847) (xy 26.574496 -460.664052)
			(xy 26.5853 -460.65706) (xy 26.607537 -460.644099) (xy 26.618946 -460.638144) (xy 26.619962 -460.637636)
			(xy 26.650254 -460.622749) (xy 26.714027 -460.600643) (xy 26.780259 -460.587639) (xy 26.847656 -460.583993)
			(xy 26.881328 -460.586328) (xy 26.903559 -460.587819) (xy 26.947942 -460.583934) (xy 26.990972 -460.572385)
			(xy 27.031334 -460.553523) (xy 27.067799 -460.527924) (xy 27.099251 -460.49637) (xy 27.124733 -460.459824)
			(xy 27.143465 -460.4194) (xy 27.154876 -460.376334) (xy 27.157172 -460.354172) (xy 27.157172 -460.265526)
			(xy 27.157426 -460.256382) (xy 27.158188 -460.243174) (xy 27.160474 -460.219806) (xy 27.161236 -460.21371)
			(xy 27.16149 -460.211678) (xy 27.161744 -460.210154) (xy 27.163014 -460.202534) (xy 27.163014 -460.202026)
			(xy 27.164538 -460.19212) (xy 27.164538 -460.18196) (xy 27.164052 -460.165768) (xy 27.155901 -460.134426)
			(xy 27.140133 -460.106139) (xy 27.117761 -460.082725) (xy 27.090221 -460.065686) (xy 27.059282 -460.056118)
			(xy 27.043126 -460.05496) (xy 25.224232 -460.05496) (xy 24.51608 -459.346808) (xy 23.109428 -457.94041)
			(xy 23.109428 -453.491346) (xy 23.108939 -453.474686) (xy 23.100326 -453.442499) (xy 23.083675 -453.413638)
			(xy 23.060121 -453.39007) (xy 23.03127 -453.373402) (xy 22.999088 -453.364771) (xy 22.982428 -453.364346)
			(xy 18.0594 -453.364346) (xy 17.493742 -453.930004) (xy 16.921988 -454.501504) (xy 16.787368 -454.501504)
			(xy 16.771109 -454.502001) (xy 16.739649 -454.510232) (xy 16.711294 -454.526151) (xy 16.69923 -454.537064)
			(xy 16.675989 -454.558804) (xy 16.625036 -454.596933) (xy 16.569722 -454.628404) (xy 16.510913 -454.652726)
			(xy 16.449528 -454.669518) (xy 16.386527 -454.678518) (xy 16.322896 -454.679584) (xy 16.259629 -454.672701)
			(xy 16.197716 -454.657975) (xy 16.138125 -454.635638) (xy 16.081787 -454.606038) (xy 16.029584 -454.569637)
			(xy 15.982333 -454.527007) (xy 15.940771 -454.478812) (xy 15.90555 -454.425808) (xy 15.877218 -454.368821)
			(xy 15.856221 -454.308745) (xy 15.849092 -454.27773) (xy 15.844245 -454.253688) (xy 15.838642 -454.204962)
			(xy 15.837916 -454.180448) (xy 15.8369 -454.12914) (xy 15.733522 -454.025762) (xy 15.708884 -454.00087)
			(xy 15.579344 -453.87133) (xy 15.579344 -453.259444) (xy 15.553944 -453.259444) (xy 15.553944 -452.496936)
			(xy 16.265652 -452.496936) (xy 16.265652 -453.259444) (xy 16.240252 -453.259444) (xy 16.240252 -453.535796)
			(xy 16.240762 -453.552106) (xy 16.24905 -453.583656) (xy 16.265062 -453.612076) (xy 16.287752 -453.635512)
			(xy 16.315639 -453.652436) (xy 16.346904 -453.661741) (xy 16.363188 -453.662796) (xy 16.382746 -453.663812)
			(xy 16.418306 -453.667622) (xy 16.445738 -453.672448) (xy 16.475115 -453.678768) (xy 16.532244 -453.697403)
			(xy 16.586782 -453.722632) (xy 16.612616 -453.73798) (xy 16.61287 -453.738234) (xy 16.62762 -453.746636)
			(xy 16.660208 -453.756092) (xy 16.694136 -453.75661) (xy 16.726998 -453.748154) (xy 16.756462 -453.731322)
			(xy 16.768826 -453.719692) (xy 17.456912 -453.031606) (xy 17.456912 -451.273418) (xy 17.473168 -451.257162)
			(xy 18.879566 -451.257162) (xy 18.92173 -451.214998) (xy 18.92173 -450.653404) (xy 18.695924 -450.427598)
			(xy 18.695924 -446.432432) (xy 18.871184 -446.257172) (xy 18.871184 -445.47155) (xy 18.769584 -445.36995)
			(xy 18.769584 -445.08674) (xy 18.769096 -445.070477) (xy 18.760879 -445.039008) (xy 18.744968 -445.01064)
			(xy 18.734024 -444.998602) (xy 18.712584 -444.975668) (xy 18.67493 -444.925431) (xy 18.643746 -444.870942)
			(xy 18.619504 -444.813029) (xy 18.602575 -444.752572) (xy 18.593215 -444.690492) (xy 18.591567 -444.627731)
			(xy 18.597655 -444.565245) (xy 18.611388 -444.503983) (xy 18.632556 -444.444878) (xy 18.660838 -444.388826)
			(xy 18.695803 -444.336682) (xy 18.736919 -444.289237) (xy 18.783563 -444.247214) (xy 18.835024 -444.21125)
			(xy 18.89052 -444.181894) (xy 18.919698 -444.170308) (xy 18.945352 -444.160656) (xy 19.604736 -443.501272)
			(xy 19.91106 -443.501272) (xy 19.927717 -443.500782) (xy 19.959897 -443.492167) (xy 19.98875 -443.475514)
			(xy 20.012307 -443.451959) (xy 20.028963 -443.423108) (xy 20.037581 -443.390929) (xy 20.03806 -443.374272)
			(xy 20.03806 -443.236604) (xy 21.410168 -443.236604) (xy 21.410168 -443.385448) (xy 21.41207 -443.401081)
			(xy 21.422514 -443.430781) (xy 21.439893 -443.457032) (xy 21.463155 -443.478246) (xy 21.490892 -443.493138)
			(xy 21.521426 -443.500808) (xy 21.537168 -443.501272) (xy 21.81098 -443.501272) (xy 21.827635 -443.50078)
			(xy 21.859811 -443.492161) (xy 21.888659 -443.475507) (xy 21.912212 -443.451953) (xy 21.928865 -443.423104)
			(xy 21.937481 -443.390927) (xy 21.93798 -443.374272) (xy 21.93798 -443.236604) (xy 23.310088 -443.236604)
			(xy 23.310088 -443.385448) (xy 23.31199 -443.40108) (xy 23.322435 -443.430778) (xy 23.339814 -443.457026)
			(xy 23.363077 -443.478237) (xy 23.390814 -443.493125) (xy 23.421347 -443.500791) (xy 23.437088 -443.501272)
			(xy 24.839676 -443.501272) (xy 27.939746 -440.401202) (xy 27.939746 -380.331472) (xy 26.19629 -378.588016)
			(xy 26.19629 -373.393462) (xy 22.540214 -369.737386) (xy 22.540214 -362.914438) (xy 22.543516 -362.914438)
			(xy 22.543516 -355.258116) (xy 22.53869 -355.253544) (xy 22.53869 -347.079824) (xy 21.253196 -345.79433)
			(xy 12.28725 -345.79433) (xy 11.611356 -346.470224) (xy 11.611356 -351.237804) (xy 8.836152 -354.013008)
			(xy 4.87045 -354.013008) (xy 2.46126 -356.422198) (xy 2.46126 -384.79984) (xy 8.597656 -384.79984)
			(xy 8.601644 -384.54722) (xy 8.613605 -384.294852) (xy 8.633527 -384.042988) (xy 8.661391 -383.791878)
			(xy 8.697167 -383.541772) (xy 8.740821 -383.292921) (xy 8.79231 -383.045572) (xy 8.851581 -382.799971)
			(xy 8.918576 -382.556364) (xy 8.993227 -382.314994) (xy 9.075462 -382.0761) (xy 9.165196 -381.839922)
			(xy 9.262342 -381.606694) (xy 9.366802 -381.376648) (xy 9.478473 -381.150016) (xy 9.597242 -380.927021)
			(xy 9.722991 -380.707887) (xy 9.855596 -380.492832) (xy 9.994923 -380.28207) (xy 10.140835 -380.075812)
			(xy 10.293185 -379.874263) (xy 10.451821 -379.677623) (xy 10.616586 -379.48609) (xy 10.787316 -379.299853)
			(xy 10.96384 -379.119099) (xy 11.145982 -378.944008) (xy 11.33356 -378.774754) (xy 11.526388 -378.611505)
			(xy 11.724273 -378.454426) (xy 11.927019 -378.303671) (xy 12.134423 -378.159393) (xy 12.346278 -378.021733)
			(xy 12.562373 -377.89083) (xy 12.782493 -377.766814) (xy 13.006418 -377.649809) (xy 13.233925 -377.539931)
			(xy 13.464787 -377.43729) (xy 13.698775 -377.341988) (xy 13.935654 -377.254121) (xy 14.17519 -377.173774)
			(xy 14.417142 -377.10103) (xy 14.66127 -377.03596) (xy 14.907331 -376.97863) (xy 15.155079 -376.929096)
			(xy 15.404267 -376.887407) (xy 15.654647 -376.853606) (xy 15.905969 -376.827725) (xy 16.157983 -376.809792)
			(xy 16.410437 -376.799823) (xy 16.663081 -376.797829) (xy 16.915661 -376.803811) (xy 17.167927 -376.817764)
			(xy 17.419626 -376.839674) (xy 17.670509 -376.869518) (xy 17.920324 -376.907268) (xy 18.168823 -376.952885)
			(xy 18.415758 -377.006324) (xy 18.660883 -377.067532) (xy 18.903953 -377.136447) (xy 19.144727 -377.213002)
			(xy 19.382964 -377.297119) (xy 19.618427 -377.388716) (xy 19.850881 -377.4877) (xy 20.080095 -377.593972)
			(xy 20.305839 -377.707428) (xy 20.527889 -377.827953) (xy 20.746023 -377.955429) (xy 20.960025 -378.089727)
			(xy 21.169681 -378.230713) (xy 21.374781 -378.378248) (xy 21.575121 -378.532184) (xy 21.770502 -378.692368)
			(xy 21.960729 -378.85864) (xy 22.145612 -379.030835) (xy 22.324968 -379.208779) (xy 22.498616 -379.392298)
			(xy 22.666384 -379.581206) (xy 22.828105 -379.775317) (xy 22.983618 -379.974436) (xy 23.132767 -380.178365)
			(xy 23.275404 -380.386901) (xy 23.411387 -380.599836) (xy 23.54058 -380.816958) (xy 23.662855 -381.03805)
			(xy 23.778089 -381.262891) (xy 23.886168 -381.491259) (xy 23.986983 -381.722924) (xy 24.080435 -381.957657)
			(xy 24.16643 -382.195222) (xy 24.244883 -382.435384) (xy 24.315715 -382.677903) (xy 24.378856 -382.922538)
			(xy 24.434243 -383.169043) (xy 24.48182 -383.417174) (xy 24.52154 -383.666684) (xy 24.553364 -383.917323)
			(xy 24.57726 -384.168841) (xy 24.593204 -384.420989) (xy 24.601179 -384.673514) (xy 24.601678 -384.79984)
			(xy 24.601179 -384.926166) (xy 24.593204 -385.178691) (xy 24.57726 -385.430839) (xy 24.553364 -385.682357)
			(xy 24.52154 -385.932996) (xy 24.48182 -386.182506) (xy 24.434243 -386.430637) (xy 24.378856 -386.677142)
			(xy 24.315715 -386.921777) (xy 24.244883 -387.164296) (xy 24.16643 -387.404458) (xy 24.080435 -387.642023)
			(xy 23.986983 -387.876756) (xy 23.886168 -388.108421) (xy 23.778089 -388.336789) (xy 23.662855 -388.56163)
			(xy 23.54058 -388.782722) (xy 23.411387 -388.999844) (xy 23.275404 -389.212779) (xy 23.132767 -389.421315)
			(xy 22.983618 -389.625244) (xy 22.828105 -389.824363) (xy 22.666384 -390.018474) (xy 22.498616 -390.207382)
			(xy 22.324968 -390.390901) (xy 22.145612 -390.568845) (xy 21.960729 -390.74104) (xy 21.770502 -390.907312)
			(xy 21.575121 -391.067496) (xy 21.374781 -391.221432) (xy 21.169681 -391.368967) (xy 20.960025 -391.509953)
			(xy 20.746023 -391.644251) (xy 20.527889 -391.771727) (xy 20.305839 -391.892252) (xy 20.080095 -392.005708)
			(xy 19.850881 -392.11198) (xy 19.618427 -392.210964) (xy 19.382964 -392.302561) (xy 19.144727 -392.386678)
			(xy 18.903953 -392.463233) (xy 18.660883 -392.532148) (xy 18.415758 -392.593356) (xy 18.168823 -392.646795)
			(xy 17.920324 -392.692412) (xy 17.670509 -392.730162) (xy 17.419626 -392.760006) (xy 17.167927 -392.781916)
			(xy 16.915661 -392.795869) (xy 16.663081 -392.801851) (xy 16.410437 -392.799857) (xy 16.157983 -392.789888)
			(xy 15.905969 -392.771955) (xy 15.654647 -392.746074) (xy 15.404267 -392.712273) (xy 15.155079 -392.670584)
			(xy 14.907331 -392.62105) (xy 14.66127 -392.56372) (xy 14.417142 -392.49865) (xy 14.17519 -392.425906)
			(xy 13.935654 -392.345559) (xy 13.698775 -392.257692) (xy 13.464787 -392.16239) (xy 13.233925 -392.059749)
			(xy 13.006418 -391.949871) (xy 12.782493 -391.832866) (xy 12.562373 -391.70885) (xy 12.346278 -391.577947)
			(xy 12.134423 -391.440287) (xy 11.927019 -391.296009) (xy 11.724273 -391.145254) (xy 11.526388 -390.988175)
			(xy 11.33356 -390.824926) (xy 11.145982 -390.655672) (xy 10.96384 -390.480581) (xy 10.787316 -390.299827)
			(xy 10.616586 -390.11359) (xy 10.451821 -389.922057) (xy 10.293185 -389.725417) (xy 10.140835 -389.523868)
			(xy 9.994923 -389.31761) (xy 9.855596 -389.106848) (xy 9.722991 -388.891793) (xy 9.597242 -388.672659)
			(xy 9.478473 -388.449664) (xy 9.366802 -388.223032) (xy 9.262342 -387.992986) (xy 9.165196 -387.759758)
			(xy 9.075462 -387.52358) (xy 8.993227 -387.284686) (xy 8.918576 -387.043316) (xy 8.851581 -386.799709)
			(xy 8.79231 -386.554108) (xy 8.740821 -386.306759) (xy 8.697167 -386.057908) (xy 8.661391 -385.807802)
			(xy 8.633527 -385.556692) (xy 8.613605 -385.304828) (xy 8.601644 -385.05246) (xy 8.597656 -384.79984)
			(xy 2.46126 -384.79984) (xy 2.46126 -395.327124) (xy 2.461789 -395.350536) (xy 2.470358 -395.396568)
			(xy 2.487218 -395.440251) (xy 2.511798 -395.480104) (xy 2.543265 -395.514777) (xy 2.580554 -395.543097)
			(xy 2.622401 -395.564103) (xy 2.667389 -395.577085) (xy 2.713994 -395.581601) (xy 2.760637 -395.577501)
			(xy 2.783332 -395.571726) (xy 2.800161 -395.566762) (xy 2.834355 -395.558883) (xy 2.851658 -395.555978)
			(xy 2.887203 -395.550978) (xy 2.958973 -395.549833) (xy 2.99466 -395.553692) (xy 3.004058 -395.554962)
			(xy 3.03695 -395.560248) (xy 3.101087 -395.57826) (xy 3.16233 -395.604476) (xy 3.191256 -395.621002)
			(xy 3.20284 -395.628033) (xy 3.225331 -395.643155) (xy 3.236214 -395.651228) (xy 3.27025 -395.676628)
			(xy 4.087622 -395.676628) (xy 4.087622 -396.439644) (xy 4.061968 -396.439644) (xy 4.061968 -397.307396)
			(xy 10.22629 -397.307396) (xy 10.22629 -397.204604) (xy 10.234355 -397.10213) (xy 10.250435 -397.000605)
			(xy 10.274431 -396.900654) (xy 10.306196 -396.802894) (xy 10.345532 -396.707927) (xy 10.392198 -396.61634)
			(xy 10.445906 -396.528696) (xy 10.506325 -396.445536) (xy 10.573083 -396.367373) (xy 10.645767 -396.294689)
			(xy 10.72393 -396.227931) (xy 10.80709 -396.167512) (xy 10.894734 -396.113804) (xy 10.986321 -396.067138)
			(xy 11.081288 -396.027802) (xy 11.179048 -395.996037) (xy 11.278999 -395.972041) (xy 11.380524 -395.955961)
			(xy 11.482998 -395.947896) (xy 11.58579 -395.947896) (xy 11.688264 -395.955961) (xy 11.789789 -395.972041)
			(xy 11.88974 -395.996037) (xy 11.9875 -396.027802) (xy 12.082467 -396.067138) (xy 12.174054 -396.113804)
			(xy 12.261698 -396.167512) (xy 12.344858 -396.227931) (xy 12.423021 -396.294689) (xy 12.495705 -396.367373)
			(xy 12.562463 -396.445536) (xy 12.622882 -396.528696) (xy 12.67659 -396.61634) (xy 12.723256 -396.707927)
			(xy 12.762592 -396.802894) (xy 12.794357 -396.900654) (xy 12.818353 -397.000605) (xy 12.834433 -397.10213)
			(xy 12.842498 -397.204604) (xy 12.843002 -397.256) (xy 12.842498 -397.307396) (xy 12.834433 -397.40987)
			(xy 12.818353 -397.511395) (xy 12.794357 -397.611346) (xy 12.762592 -397.709106) (xy 12.723256 -397.804073)
			(xy 12.67659 -397.89566) (xy 12.622882 -397.983304) (xy 12.562463 -398.066464) (xy 12.495705 -398.144627)
			(xy 12.423021 -398.217311) (xy 12.344858 -398.284069) (xy 12.261698 -398.344488) (xy 12.174054 -398.398196)
			(xy 12.082467 -398.444862) (xy 11.9875 -398.484198) (xy 11.88974 -398.515963) (xy 11.789789 -398.539959)
			(xy 11.688264 -398.556039) (xy 11.58579 -398.564104) (xy 11.482998 -398.564104) (xy 11.380524 -398.556039)
			(xy 11.278999 -398.539959) (xy 11.179048 -398.515963) (xy 11.081288 -398.484198) (xy 10.986321 -398.444862)
			(xy 10.894734 -398.398196) (xy 10.80709 -398.344488) (xy 10.72393 -398.284069) (xy 10.645767 -398.217311)
			(xy 10.573083 -398.144627) (xy 10.506325 -398.066464) (xy 10.445906 -397.983304) (xy 10.392198 -397.89566)
			(xy 10.345532 -397.804073) (xy 10.306196 -397.709106) (xy 10.274431 -397.611346) (xy 10.250435 -397.511395)
			(xy 10.234355 -397.40987) (xy 10.22629 -397.307396) (xy 4.061968 -397.307396) (xy 4.061968 -398.153128)
			(xy 4.062516 -398.170845) (xy 4.072202 -398.204926) (xy 4.0909 -398.23502) (xy 4.103624 -398.247362)
			(xy 4.133251 -398.274916) (xy 4.187311 -398.335119) (xy 4.234916 -398.400545) (xy 4.275565 -398.470507)
			(xy 4.308829 -398.544265) (xy 4.334358 -398.621045) (xy 4.351883 -398.700037) (xy 4.361219 -398.78041)
			(xy 4.362269 -398.861316) (xy 4.35502 -398.941903) (xy 4.33955 -399.021323) (xy 4.316022 -399.098739)
			(xy 4.284682 -399.173336) (xy 4.245862 -399.244328) (xy 4.19997 -399.310968) (xy 4.14749 -399.372552)
			(xy 4.088974 -399.428434) (xy 4.025039 -399.478024) (xy 4.023337 -399.479084) (xy 5.677649 -399.479084)
			(xy 5.677649 -399.352948) (xy 5.685569 -399.22706) (xy 5.701379 -399.101918) (xy 5.725014 -398.978015)
			(xy 5.756383 -398.855842) (xy 5.795361 -398.735879) (xy 5.841795 -398.6186) (xy 5.895502 -398.504468)
			(xy 5.956269 -398.393933) (xy 6.023856 -398.287433) (xy 6.097997 -398.185386) (xy 6.1784 -398.088196)
			(xy 6.264746 -397.996246) (xy 6.356696 -397.9099) (xy 6.453886 -397.829497) (xy 6.555933 -397.755356)
			(xy 6.662433 -397.687769) (xy 6.772968 -397.627002) (xy 6.8871 -397.573295) (xy 7.004379 -397.526861)
			(xy 7.124342 -397.487883) (xy 7.246515 -397.456514) (xy 7.370418 -397.432879) (xy 7.49556 -397.417069)
			(xy 7.621448 -397.409149) (xy 7.747584 -397.409149) (xy 7.873472 -397.417069) (xy 7.998614 -397.432879)
			(xy 8.122517 -397.456514) (xy 8.24469 -397.487883) (xy 8.364653 -397.526861) (xy 8.481932 -397.573295)
			(xy 8.596064 -397.627002) (xy 8.706599 -397.687769) (xy 8.813099 -397.755356) (xy 8.915146 -397.829497)
			(xy 9.012336 -397.9099) (xy 9.104286 -397.996246) (xy 9.190632 -398.088196) (xy 9.271035 -398.185386)
			(xy 9.345176 -398.287433) (xy 9.412763 -398.393933) (xy 9.47353 -398.504468) (xy 9.527237 -398.6186)
			(xy 9.573671 -398.735879) (xy 9.612649 -398.855842) (xy 9.644018 -398.978015) (xy 9.667653 -399.101918)
			(xy 9.683463 -399.22706) (xy 9.691383 -399.352948) (xy 9.691878 -399.416016) (xy 9.691383 -399.479084)
			(xy 9.683463 -399.604972) (xy 9.667653 -399.730114) (xy 9.644018 -399.854017) (xy 9.612649 -399.97619)
			(xy 9.573671 -400.096153) (xy 9.527237 -400.213432) (xy 9.47353 -400.327564) (xy 9.412763 -400.438099)
			(xy 9.345176 -400.544599) (xy 9.271035 -400.646646) (xy 9.205429 -400.725949) (xy 15.787113 -400.725949)
			(xy 15.787113 -400.646083) (xy 15.795193 -400.566628) (xy 15.81127 -400.488398) (xy 15.835179 -400.412196)
			(xy 15.866674 -400.338803) (xy 15.905433 -400.268973) (xy 15.951057 -400.203423) (xy 16.003079 -400.142824)
			(xy 16.060964 -400.0878) (xy 16.12412 -400.038914) (xy 16.191897 -399.996668) (xy 16.2636 -399.961496)
			(xy 16.338494 -399.933759) (xy 16.415809 -399.91374) (xy 16.494753 -399.901647) (xy 16.574516 -399.897602)
			(xy 16.654279 -399.901647) (xy 16.733223 -399.91374) (xy 16.810538 -399.933759) (xy 16.885432 -399.961496)
			(xy 16.957135 -399.996668) (xy 17.024912 -400.038914) (xy 17.088068 -400.0878) (xy 17.145953 -400.142824)
			(xy 17.197975 -400.203423) (xy 17.243599 -400.268973) (xy 17.282358 -400.338803) (xy 17.313853 -400.412196)
			(xy 17.337762 -400.488398) (xy 17.353839 -400.566628) (xy 17.361919 -400.646083) (xy 17.362424 -400.686016)
			(xy 17.361919 -400.725949) (xy 17.353839 -400.805404) (xy 17.337762 -400.883634) (xy 17.313853 -400.959836)
			(xy 17.282358 -401.033229) (xy 17.243599 -401.103059) (xy 17.197975 -401.168609) (xy 17.145953 -401.229208)
			(xy 17.088068 -401.284232) (xy 17.024912 -401.333118) (xy 16.957135 -401.375364) (xy 16.885432 -401.410536)
			(xy 16.810538 -401.438273) (xy 16.733223 -401.458292) (xy 16.654279 -401.470385) (xy 16.574516 -401.474431)
			(xy 16.494753 -401.470385) (xy 16.415809 -401.458292) (xy 16.338494 -401.438273) (xy 16.2636 -401.410536)
			(xy 16.191897 -401.375364) (xy 16.12412 -401.333118) (xy 16.060964 -401.284232) (xy 16.003079 -401.229208)
			(xy 15.951057 -401.168609) (xy 15.905433 -401.103059) (xy 15.866674 -401.033229) (xy 15.835179 -400.959836)
			(xy 15.81127 -400.883634) (xy 15.795193 -400.805404) (xy 15.787113 -400.725949) (xy 9.205429 -400.725949)
			(xy 9.190632 -400.743836) (xy 9.104286 -400.835786) (xy 9.012336 -400.922132) (xy 8.915146 -401.002535)
			(xy 8.813099 -401.076676) (xy 8.706599 -401.144263) (xy 8.596064 -401.20503) (xy 8.481932 -401.258737)
			(xy 8.364653 -401.305171) (xy 8.24469 -401.344149) (xy 8.122517 -401.375518) (xy 7.998614 -401.399153)
			(xy 7.873472 -401.414963) (xy 7.747584 -401.422883) (xy 7.621448 -401.422883) (xy 7.49556 -401.414963)
			(xy 7.370418 -401.399153) (xy 7.246515 -401.375518) (xy 7.124342 -401.344149) (xy 7.004379 -401.305171)
			(xy 6.8871 -401.258737) (xy 6.772968 -401.20503) (xy 6.662433 -401.144263) (xy 6.555933 -401.076676)
			(xy 6.453886 -401.002535) (xy 6.356696 -400.922132) (xy 6.264746 -400.835786) (xy 6.1784 -400.743836)
			(xy 6.097997 -400.646646) (xy 6.023856 -400.544599) (xy 5.956269 -400.438099) (xy 5.895502 -400.327564)
			(xy 5.841795 -400.213432) (xy 5.795361 -400.096153) (xy 5.756383 -399.97619) (xy 5.725014 -399.854017)
			(xy 5.701379 -399.730114) (xy 5.685569 -399.604972) (xy 5.677649 -399.479084) (xy 4.023337 -399.479084)
			(xy 3.956357 -399.520799) (xy 3.883653 -399.55631) (xy 3.807693 -399.584182) (xy 3.729275 -399.604121)
			(xy 3.649227 -399.615919) (xy 3.608832 -399.6182) (xy 3.568888 -399.619461) (xy 3.489099 -399.61486)
			(xy 3.410186 -399.6022) (xy 3.332962 -399.581612) (xy 3.25822 -399.553307) (xy 3.222244 -399.535904)
			(xy 3.186542 -399.517514) (xy 3.118716 -399.474506) (xy 3.055617 -399.42482) (xy 2.9979 -399.368972)
			(xy 2.946165 -399.307543) (xy 2.900948 -399.241168) (xy 2.862718 -399.170538) (xy 2.831872 -399.096385)
			(xy 2.808731 -399.019478) (xy 2.793534 -398.940616) (xy 2.786439 -398.860617) (xy 2.78752 -398.780311)
			(xy 2.796765 -398.700532) (xy 2.814079 -398.622108) (xy 2.839281 -398.545852) (xy 2.872112 -398.472556)
			(xy 2.912228 -398.40298) (xy 2.959215 -398.337846) (xy 3.012585 -398.277831) (xy 3.071784 -398.223557)
			(xy 3.136197 -398.175588) (xy 3.205157 -398.13442) (xy 3.277947 -398.100482) (xy 3.315716 -398.086834)
			(xy 3.330401 -398.081225) (xy 3.356652 -398.063947) (xy 3.377884 -398.040778) (xy 3.39281 -398.013123)
			(xy 3.400525 -397.982658) (xy 3.40106 -397.966946) (xy 3.40106 -397.547084) (xy 3.39909 -397.524334)
			(xy 3.388084 -397.480022) (xy 3.369347 -397.438385) (xy 3.343479 -397.400761) (xy 3.311312 -397.368357)
			(xy 3.273878 -397.342215) (xy 3.23238 -397.323173) (xy 3.188149 -397.311843) (xy 3.142607 -397.308588)
			(xy 3.097215 -397.313514) (xy 3.075178 -397.3195) (xy 3.063992 -397.322749) (xy 3.041377 -397.328339)
			(xy 3.029966 -397.330676) (xy 2.993321 -397.337182) (xy 2.918983 -397.340754) (xy 2.881884 -397.337788)
			(xy 2.868719 -397.336423) (xy 2.842543 -397.332486) (xy 2.82956 -397.329914) (xy 2.817888 -397.327467)
			(xy 2.794765 -397.321621) (xy 2.783332 -397.31823) (xy 2.760639 -397.312477) (xy 2.714005 -397.308411)
			(xy 2.667416 -397.312951) (xy 2.622445 -397.325944) (xy 2.580613 -397.346952) (xy 2.543335 -397.375263)
			(xy 2.511869 -397.40992) (xy 2.487281 -397.449753) (xy 2.470402 -397.493414) (xy 2.461801 -397.539427)
			(xy 2.46126 -397.562832) (xy 2.46126 -401.360949) (xy 2.787139 -401.360949) (xy 2.787139 -401.281083)
			(xy 2.795219 -401.201628) (xy 2.811296 -401.123398) (xy 2.835205 -401.047196) (xy 2.8667 -400.973803)
			(xy 2.905459 -400.903973) (xy 2.951083 -400.838423) (xy 3.003105 -400.777824) (xy 3.06099 -400.7228)
			(xy 3.124146 -400.673914) (xy 3.191923 -400.631668) (xy 3.263626 -400.596496) (xy 3.33852 -400.568759)
			(xy 3.415835 -400.54874) (xy 3.494779 -400.536647) (xy 3.574542 -400.532602) (xy 3.654305 -400.536647)
			(xy 3.733249 -400.54874) (xy 3.810564 -400.568759) (xy 3.885458 -400.596496) (xy 3.957161 -400.631668)
			(xy 4.024938 -400.673914) (xy 4.088094 -400.7228) (xy 4.145979 -400.777824) (xy 4.198001 -400.838423)
			(xy 4.243625 -400.903973) (xy 4.282384 -400.973803) (xy 4.313879 -401.047196) (xy 4.337788 -401.123398)
			(xy 4.353865 -401.201628) (xy 4.361945 -401.281083) (xy 4.36245 -401.321016) (xy 4.361945 -401.360949)
			(xy 4.353865 -401.440404) (xy 4.337788 -401.518634) (xy 4.313879 -401.594836) (xy 4.282384 -401.668229)
			(xy 4.243625 -401.738059) (xy 4.198001 -401.803609) (xy 4.145979 -401.864208) (xy 4.088094 -401.919232)
			(xy 4.024938 -401.968118) (xy 3.980288 -401.995949) (xy 13.247113 -401.995949) (xy 13.247113 -401.916083)
			(xy 13.255193 -401.836628) (xy 13.27127 -401.758398) (xy 13.295179 -401.682196) (xy 13.326674 -401.608803)
			(xy 13.365433 -401.538973) (xy 13.411057 -401.473423) (xy 13.463079 -401.412824) (xy 13.520964 -401.3578)
			(xy 13.58412 -401.308914) (xy 13.651897 -401.266668) (xy 13.7236 -401.231496) (xy 13.798494 -401.203759)
			(xy 13.875809 -401.18374) (xy 13.954753 -401.171647) (xy 14.034516 -401.167602) (xy 14.114279 -401.171647)
			(xy 14.193223 -401.18374) (xy 14.270538 -401.203759) (xy 14.345432 -401.231496) (xy 14.417135 -401.266668)
			(xy 14.484912 -401.308914) (xy 14.548068 -401.3578) (xy 14.605953 -401.412824) (xy 14.657975 -401.473423)
			(xy 14.703599 -401.538973) (xy 14.742358 -401.608803) (xy 14.773853 -401.682196) (xy 14.797762 -401.758398)
			(xy 14.813839 -401.836628) (xy 14.821919 -401.916083) (xy 14.822424 -401.956016) (xy 14.821919 -401.995949)
			(xy 14.813839 -402.075404) (xy 14.797762 -402.153634) (xy 14.773853 -402.229836) (xy 14.742358 -402.303229)
			(xy 14.703599 -402.373059) (xy 14.657975 -402.438609) (xy 14.605953 -402.499208) (xy 14.548068 -402.554232)
			(xy 14.484912 -402.603118) (xy 14.417135 -402.645364) (xy 14.345432 -402.680536) (xy 14.270538 -402.708273)
			(xy 14.193223 -402.728292) (xy 14.114279 -402.740385) (xy 14.034516 -402.744431) (xy 13.954753 -402.740385)
			(xy 13.875809 -402.728292) (xy 13.798494 -402.708273) (xy 13.7236 -402.680536) (xy 13.651897 -402.645364)
			(xy 13.58412 -402.603118) (xy 13.520964 -402.554232) (xy 13.463079 -402.499208) (xy 13.411057 -402.438609)
			(xy 13.365433 -402.373059) (xy 13.326674 -402.303229) (xy 13.295179 -402.229836) (xy 13.27127 -402.153634)
			(xy 13.255193 -402.075404) (xy 13.247113 -401.995949) (xy 3.980288 -401.995949) (xy 3.957161 -402.010364)
			(xy 3.885458 -402.045536) (xy 3.810564 -402.073273) (xy 3.733249 -402.093292) (xy 3.654305 -402.105385)
			(xy 3.574542 -402.109431) (xy 3.494779 -402.105385) (xy 3.415835 -402.093292) (xy 3.33852 -402.073273)
			(xy 3.263626 -402.045536) (xy 3.191923 -402.010364) (xy 3.124146 -401.968118) (xy 3.06099 -401.919232)
			(xy 3.003105 -401.864208) (xy 2.951083 -401.803609) (xy 2.905459 -401.738059) (xy 2.8667 -401.668229)
			(xy 2.835205 -401.594836) (xy 2.811296 -401.518634) (xy 2.795219 -401.440404) (xy 2.787139 -401.360949)
			(xy 2.46126 -401.360949) (xy 2.46126 -403.265949) (xy 15.787113 -403.265949) (xy 15.787113 -403.186083)
			(xy 15.795193 -403.106628) (xy 15.81127 -403.028398) (xy 15.835179 -402.952196) (xy 15.866674 -402.878803)
			(xy 15.905433 -402.808973) (xy 15.951057 -402.743423) (xy 16.003079 -402.682824) (xy 16.060964 -402.6278)
			(xy 16.12412 -402.578914) (xy 16.191897 -402.536668) (xy 16.2636 -402.501496) (xy 16.338494 -402.473759)
			(xy 16.415809 -402.45374) (xy 16.494753 -402.441647) (xy 16.574516 -402.437602) (xy 16.654279 -402.441647)
			(xy 16.733223 -402.45374) (xy 16.810538 -402.473759) (xy 16.885432 -402.501496) (xy 16.957135 -402.536668)
			(xy 17.024912 -402.578914) (xy 17.088068 -402.6278) (xy 17.145953 -402.682824) (xy 17.197975 -402.743423)
			(xy 17.243599 -402.808973) (xy 17.282358 -402.878803) (xy 17.313853 -402.952196) (xy 17.337762 -403.028398)
			(xy 17.353839 -403.106628) (xy 17.361919 -403.186083) (xy 17.362424 -403.226016) (xy 17.361919 -403.265949)
			(xy 17.353839 -403.345404) (xy 17.337762 -403.423634) (xy 17.313853 -403.499836) (xy 17.282358 -403.573229)
			(xy 17.243599 -403.643059) (xy 17.197975 -403.708609) (xy 17.145953 -403.769208) (xy 17.088068 -403.824232)
			(xy 17.024912 -403.873118) (xy 16.957135 -403.915364) (xy 16.885432 -403.950536) (xy 16.810538 -403.978273)
			(xy 16.733223 -403.998292) (xy 16.654279 -404.010385) (xy 16.574516 -404.014431) (xy 16.494753 -404.010385)
			(xy 16.415809 -403.998292) (xy 16.338494 -403.978273) (xy 16.2636 -403.950536) (xy 16.191897 -403.915364)
			(xy 16.12412 -403.873118) (xy 16.060964 -403.824232) (xy 16.003079 -403.769208) (xy 15.951057 -403.708609)
			(xy 15.905433 -403.643059) (xy 15.866674 -403.573229) (xy 15.835179 -403.499836) (xy 15.81127 -403.423634)
			(xy 15.795193 -403.345404) (xy 15.787113 -403.265949) (xy 2.46126 -403.265949) (xy 2.46126 -404.535949)
			(xy 13.247113 -404.535949) (xy 13.247113 -404.456083) (xy 13.255193 -404.376628) (xy 13.27127 -404.298398)
			(xy 13.295179 -404.222196) (xy 13.326674 -404.148803) (xy 13.365433 -404.078973) (xy 13.411057 -404.013423)
			(xy 13.463079 -403.952824) (xy 13.520964 -403.8978) (xy 13.58412 -403.848914) (xy 13.651897 -403.806668)
			(xy 13.7236 -403.771496) (xy 13.798494 -403.743759) (xy 13.875809 -403.72374) (xy 13.954753 -403.711647)
			(xy 14.034516 -403.707602) (xy 14.114279 -403.711647) (xy 14.193223 -403.72374) (xy 14.270538 -403.743759)
			(xy 14.345432 -403.771496) (xy 14.417135 -403.806668) (xy 14.484912 -403.848914) (xy 14.548068 -403.8978)
			(xy 14.605953 -403.952824) (xy 14.657975 -404.013423) (xy 14.703599 -404.078973) (xy 14.742358 -404.148803)
			(xy 14.773853 -404.222196) (xy 14.797762 -404.298398) (xy 14.813839 -404.376628) (xy 14.821919 -404.456083)
			(xy 14.822424 -404.496016) (xy 14.821919 -404.535949) (xy 14.813839 -404.615404) (xy 14.797762 -404.693634)
			(xy 14.773853 -404.769836) (xy 14.742358 -404.843229) (xy 14.703599 -404.913059) (xy 14.657975 -404.978609)
			(xy 14.605953 -405.039208) (xy 14.548068 -405.094232) (xy 14.484912 -405.143118) (xy 14.417135 -405.185364)
			(xy 14.345432 -405.220536) (xy 14.270538 -405.248273) (xy 14.193223 -405.268292) (xy 14.114279 -405.280385)
			(xy 14.034516 -405.284431) (xy 13.954753 -405.280385) (xy 13.875809 -405.268292) (xy 13.798494 -405.248273)
			(xy 13.7236 -405.220536) (xy 13.651897 -405.185364) (xy 13.58412 -405.143118) (xy 13.520964 -405.094232)
			(xy 13.463079 -405.039208) (xy 13.411057 -404.978609) (xy 13.365433 -404.913059) (xy 13.326674 -404.843229)
			(xy 13.295179 -404.769836) (xy 13.27127 -404.693634) (xy 13.255193 -404.615404) (xy 13.247113 -404.535949)
			(xy 2.46126 -404.535949) (xy 2.46126 -405.805949) (xy 15.787113 -405.805949) (xy 15.787113 -405.726083)
			(xy 15.795193 -405.646628) (xy 15.81127 -405.568398) (xy 15.835179 -405.492196) (xy 15.866674 -405.418803)
			(xy 15.905433 -405.348973) (xy 15.951057 -405.283423) (xy 16.003079 -405.222824) (xy 16.060964 -405.1678)
			(xy 16.12412 -405.118914) (xy 16.191897 -405.076668) (xy 16.2636 -405.041496) (xy 16.338494 -405.013759)
			(xy 16.415809 -404.99374) (xy 16.494753 -404.981647) (xy 16.574516 -404.977602) (xy 16.654279 -404.981647)
			(xy 16.733223 -404.99374) (xy 16.810538 -405.013759) (xy 16.885432 -405.041496) (xy 16.957135 -405.076668)
			(xy 17.024912 -405.118914) (xy 17.088068 -405.1678) (xy 17.145953 -405.222824) (xy 17.197975 -405.283423)
			(xy 17.243599 -405.348973) (xy 17.282358 -405.418803) (xy 17.313853 -405.492196) (xy 17.337762 -405.568398)
			(xy 17.353839 -405.646628) (xy 17.361919 -405.726083) (xy 17.362424 -405.766016) (xy 17.361919 -405.805949)
			(xy 17.353839 -405.885404) (xy 17.337762 -405.963634) (xy 17.313853 -406.039836) (xy 17.282358 -406.113229)
			(xy 17.243599 -406.183059) (xy 17.197975 -406.248609) (xy 17.145953 -406.309208) (xy 17.088068 -406.364232)
			(xy 17.024912 -406.413118) (xy 16.957135 -406.455364) (xy 16.885432 -406.490536) (xy 16.810538 -406.518273)
			(xy 16.733223 -406.538292) (xy 16.654279 -406.550385) (xy 16.574516 -406.554431) (xy 16.494753 -406.550385)
			(xy 16.415809 -406.538292) (xy 16.338494 -406.518273) (xy 16.2636 -406.490536) (xy 16.191897 -406.455364)
			(xy 16.12412 -406.413118) (xy 16.060964 -406.364232) (xy 16.003079 -406.309208) (xy 15.951057 -406.248609)
			(xy 15.905433 -406.183059) (xy 15.866674 -406.113229) (xy 15.835179 -406.039836) (xy 15.81127 -405.963634)
			(xy 15.795193 -405.885404) (xy 15.787113 -405.805949) (xy 2.46126 -405.805949) (xy 2.46126 -407.075949)
			(xy 13.247113 -407.075949) (xy 13.247113 -406.996083) (xy 13.255193 -406.916628) (xy 13.27127 -406.838398)
			(xy 13.295179 -406.762196) (xy 13.326674 -406.688803) (xy 13.365433 -406.618973) (xy 13.411057 -406.553423)
			(xy 13.463079 -406.492824) (xy 13.520964 -406.4378) (xy 13.58412 -406.388914) (xy 13.651897 -406.346668)
			(xy 13.7236 -406.311496) (xy 13.798494 -406.283759) (xy 13.875809 -406.26374) (xy 13.954753 -406.251647)
			(xy 14.034516 -406.247602) (xy 14.114279 -406.251647) (xy 14.193223 -406.26374) (xy 14.270538 -406.283759)
			(xy 14.345432 -406.311496) (xy 14.417135 -406.346668) (xy 14.484912 -406.388914) (xy 14.548068 -406.4378)
			(xy 14.605953 -406.492824) (xy 14.657975 -406.553423) (xy 14.703599 -406.618973) (xy 14.742358 -406.688803)
			(xy 14.773853 -406.762196) (xy 14.797762 -406.838398) (xy 14.813839 -406.916628) (xy 14.821919 -406.996083)
			(xy 14.822424 -407.036016) (xy 14.821919 -407.075949) (xy 14.813839 -407.155404) (xy 14.797762 -407.233634)
			(xy 14.773853 -407.309836) (xy 14.742358 -407.383229) (xy 14.703599 -407.453059) (xy 14.657975 -407.518609)
			(xy 14.605953 -407.579208) (xy 14.548068 -407.634232) (xy 14.484912 -407.683118) (xy 14.417135 -407.725364)
			(xy 14.345432 -407.760536) (xy 14.270538 -407.788273) (xy 14.193223 -407.808292) (xy 14.114279 -407.820385)
			(xy 14.034516 -407.824431) (xy 13.954753 -407.820385) (xy 13.875809 -407.808292) (xy 13.798494 -407.788273)
			(xy 13.7236 -407.760536) (xy 13.651897 -407.725364) (xy 13.58412 -407.683118) (xy 13.520964 -407.634232)
			(xy 13.463079 -407.579208) (xy 13.411057 -407.518609) (xy 13.365433 -407.453059) (xy 13.326674 -407.383229)
			(xy 13.295179 -407.309836) (xy 13.27127 -407.233634) (xy 13.255193 -407.155404) (xy 13.247113 -407.075949)
			(xy 2.46126 -407.075949) (xy 2.46126 -409.28036) (xy 2.461674 -409.295352) (xy 2.468672 -409.324507)
			(xy 2.48229 -409.351219) (xy 2.501773 -409.374009) (xy 2.526043 -409.391615) (xy 2.539746 -409.397708)
			(xy 2.575306 -409.412186) (xy 2.650744 -409.3972) (xy 2.780284 -409.26766) (xy 2.791735 -409.255544)
			(xy 2.808441 -409.226706) (xy 2.817111 -409.194525) (xy 2.817153 -409.161198) (xy 2.813304 -409.144978)
			(xy 2.803507 -409.106527) (xy 2.790771 -409.028203) (xy 2.785975 -408.948996) (xy 2.789166 -408.869707)
			(xy 2.800312 -408.791142) (xy 2.819301 -408.714095) (xy 2.84594 -408.639347) (xy 2.879959 -408.567657)
			(xy 2.921014 -408.49975) (xy 2.968687 -408.436314) (xy 3.022498 -408.377994) (xy 3.081898 -408.325378)
			(xy 3.146288 -408.279002) (xy 3.215015 -408.239334) (xy 3.287381 -408.206777) (xy 3.32486 -408.193748)
			(xy 3.363222 -408.181465) (xy 3.441832 -408.163869) (xy 3.521827 -408.154385) (xy 3.602371 -408.153113)
			(xy 3.682626 -408.160067) (xy 3.761752 -408.175173) (xy 3.838923 -408.198274) (xy 3.913335 -408.229129)
			(xy 3.984209 -408.267416) (xy 4.050807 -408.312735) (xy 4.090262 -408.345949) (xy 15.787113 -408.345949)
			(xy 15.787113 -408.266083) (xy 15.795193 -408.186628) (xy 15.81127 -408.108398) (xy 15.835179 -408.032196)
			(xy 15.866674 -407.958803) (xy 15.905433 -407.888973) (xy 15.951057 -407.823423) (xy 16.003079 -407.762824)
			(xy 16.060964 -407.7078) (xy 16.12412 -407.658914) (xy 16.191897 -407.616668) (xy 16.2636 -407.581496)
			(xy 16.338494 -407.553759) (xy 16.415809 -407.53374) (xy 16.494753 -407.521647) (xy 16.574516 -407.517602)
			(xy 16.654279 -407.521647) (xy 16.733223 -407.53374) (xy 16.810538 -407.553759) (xy 16.885432 -407.581496)
			(xy 16.957135 -407.616668) (xy 17.024912 -407.658914) (xy 17.088068 -407.7078) (xy 17.145953 -407.762824)
			(xy 17.197975 -407.823423) (xy 17.243599 -407.888973) (xy 17.282358 -407.958803) (xy 17.313853 -408.032196)
			(xy 17.337762 -408.108398) (xy 17.353839 -408.186628) (xy 17.361919 -408.266083) (xy 17.362424 -408.306016)
			(xy 17.361919 -408.345949) (xy 17.353839 -408.425404) (xy 17.337762 -408.503634) (xy 17.313853 -408.579836)
			(xy 17.282358 -408.653229) (xy 17.243599 -408.723059) (xy 17.197975 -408.788609) (xy 17.145953 -408.849208)
			(xy 17.088068 -408.904232) (xy 17.024912 -408.953118) (xy 16.957135 -408.995364) (xy 16.885432 -409.030536)
			(xy 16.810538 -409.058273) (xy 16.733223 -409.078292) (xy 16.654279 -409.090385) (xy 16.574516 -409.094431)
			(xy 16.494753 -409.090385) (xy 16.415809 -409.078292) (xy 16.338494 -409.058273) (xy 16.2636 -409.030536)
			(xy 16.191897 -408.995364) (xy 16.12412 -408.953118) (xy 16.060964 -408.904232) (xy 16.003079 -408.849208)
			(xy 15.951057 -408.788609) (xy 15.905433 -408.723059) (xy 15.866674 -408.653229) (xy 15.835179 -408.579836)
			(xy 15.81127 -408.503634) (xy 15.795193 -408.425404) (xy 15.787113 -408.345949) (xy 4.090262 -408.345949)
			(xy 4.112433 -408.364613) (xy 4.168444 -408.422508) (xy 4.218255 -408.485817) (xy 4.261347 -408.553877)
			(xy 4.297268 -408.62598) (xy 4.325645 -408.701371) (xy 4.346181 -408.779264) (xy 4.347568 -408.788108)
			(xy 13.246608 -408.788108) (xy 14.822424 -408.788108) (xy 14.822424 -410.363924) (xy 13.246608 -410.363924)
			(xy 13.246608 -408.788108) (xy 4.347568 -408.788108) (xy 4.358662 -408.858846) (xy 4.362957 -408.939287)
			(xy 4.359021 -409.019746) (xy 4.346897 -409.099383) (xy 4.326709 -409.177367) (xy 4.29867 -409.252885)
			(xy 4.263071 -409.325147) (xy 4.220285 -409.3934) (xy 4.170758 -409.45693) (xy 4.143248 -409.486354)
			(xy 4.116667 -409.513416) (xy 4.059139 -409.562868) (xy 3.997125 -409.606563) (xy 3.931201 -409.644098)
			(xy 3.861975 -409.675126) (xy 3.790089 -409.699359) (xy 3.716207 -409.716574) (xy 3.641012 -409.72661)
			(xy 3.565201 -409.729376) (xy 3.489476 -409.724845) (xy 3.414536 -409.713059) (xy 3.377692 -409.704032)
			(xy 3.370326 -409.702254) (xy 3.353562 -409.699968) (xy 3.339063 -409.698431) (xy 3.31005 -409.701236)
			(xy 3.282442 -409.710584) (xy 3.257691 -409.72598) (xy 3.247136 -409.736036) (xy 3.009392 -409.97378)
			(xy 3.009392 -410.45257) (xy 3.011363 -410.475535) (xy 3.022546 -410.520246) (xy 3.0416 -410.562211)
			(xy 3.067901 -410.600057) (xy 3.10059 -410.632547) (xy 3.138596 -410.658616) (xy 3.180677 -410.677413)
			(xy 3.225456 -410.688322) (xy 3.271467 -410.690986) (xy 3.317205 -410.685318) (xy 3.339338 -410.678884)
			(xy 3.379033 -410.667025) (xy 3.460266 -410.650729) (xy 3.54276 -410.643045) (xy 3.625605 -410.64406)
			(xy 3.707886 -410.653761) (xy 3.788695 -410.672042) (xy 3.86714 -410.6987) (xy 3.942355 -410.733442)
			(xy 4.01351 -410.775884) (xy 4.046982 -410.800296) (xy 4.077703 -410.823888) (xy 4.134843 -410.876191)
			(xy 4.164357 -410.909084) (xy 5.677649 -410.909084) (xy 5.677649 -410.782948) (xy 5.685569 -410.65706)
			(xy 5.701379 -410.531918) (xy 5.725014 -410.408015) (xy 5.756383 -410.285842) (xy 5.795361 -410.165879)
			(xy 5.841795 -410.0486) (xy 5.895502 -409.934468) (xy 5.956269 -409.823933) (xy 6.023856 -409.717433)
			(xy 6.097997 -409.615386) (xy 6.1784 -409.518196) (xy 6.264746 -409.426246) (xy 6.356696 -409.3399)
			(xy 6.453886 -409.259497) (xy 6.555933 -409.185356) (xy 6.662433 -409.117769) (xy 6.772968 -409.057002)
			(xy 6.8871 -409.003295) (xy 7.004379 -408.956861) (xy 7.124342 -408.917883) (xy 7.246515 -408.886514)
			(xy 7.370418 -408.862879) (xy 7.49556 -408.847069) (xy 7.621448 -408.839149) (xy 7.747584 -408.839149)
			(xy 7.873472 -408.847069) (xy 7.998614 -408.862879) (xy 8.122517 -408.886514) (xy 8.24469 -408.917883)
			(xy 8.364653 -408.956861) (xy 8.481932 -409.003295) (xy 8.596064 -409.057002) (xy 8.706599 -409.117769)
			(xy 8.813099 -409.185356) (xy 8.915146 -409.259497) (xy 9.012336 -409.3399) (xy 9.104286 -409.426246)
			(xy 9.190632 -409.518196) (xy 9.271035 -409.615386) (xy 9.345176 -409.717433) (xy 9.412763 -409.823933)
			(xy 9.47353 -409.934468) (xy 9.527237 -410.0486) (xy 9.573671 -410.165879) (xy 9.612649 -410.285842)
			(xy 9.644018 -410.408015) (xy 9.667653 -410.531918) (xy 9.683463 -410.65706) (xy 9.691383 -410.782948)
			(xy 9.691878 -410.846016) (xy 9.691383 -410.909084) (xy 9.683463 -411.034972) (xy 9.667653 -411.160114)
			(xy 9.644018 -411.284017) (xy 9.612649 -411.40619) (xy 9.573671 -411.526153) (xy 9.527237 -411.643432)
			(xy 9.47353 -411.757564) (xy 9.412763 -411.868099) (xy 9.345176 -411.974599) (xy 9.271035 -412.076646)
			(xy 9.190632 -412.173836) (xy 9.104286 -412.265786) (xy 9.012336 -412.352132) (xy 8.915146 -412.432535)
			(xy 8.813099 -412.506676) (xy 8.706599 -412.574263) (xy 8.596064 -412.63503) (xy 8.481932 -412.688737)
			(xy 8.364653 -412.735171) (xy 8.24469 -412.774149) (xy 8.122517 -412.805518) (xy 7.998614 -412.829153)
			(xy 7.873472 -412.844963) (xy 7.747584 -412.852883) (xy 7.621448 -412.852883) (xy 7.49556 -412.844963)
			(xy 7.370418 -412.829153) (xy 7.246515 -412.805518) (xy 7.124342 -412.774149) (xy 7.004379 -412.735171)
			(xy 6.8871 -412.688737) (xy 6.772968 -412.63503) (xy 6.662433 -412.574263) (xy 6.555933 -412.506676)
			(xy 6.453886 -412.432535) (xy 6.356696 -412.352132) (xy 6.264746 -412.265786) (xy 6.1784 -412.173836)
			(xy 6.097997 -412.076646) (xy 6.023856 -411.974599) (xy 5.956269 -411.868099) (xy 5.895502 -411.757564)
			(xy 5.841795 -411.643432) (xy 5.795361 -411.526153) (xy 5.756383 -411.40619) (xy 5.725014 -411.284017)
			(xy 5.701379 -411.160114) (xy 5.685569 -411.034972) (xy 5.677649 -410.909084) (xy 4.164357 -410.909084)
			(xy 4.186576 -410.933847) (xy 4.232404 -410.996299) (xy 4.271884 -411.062947) (xy 4.304636 -411.133146)
			(xy 4.330343 -411.206219) (xy 4.348757 -411.281462) (xy 4.359702 -411.358148) (xy 4.363071 -411.435538)
			(xy 4.358831 -411.512885) (xy 4.347024 -411.589443) (xy 4.337812 -411.627066) (xy 4.337558 -411.627828)
			(xy 4.33578 -411.635194) (xy 4.333494 -411.65145) (xy 4.331938 -411.666007) (xy 4.334724 -411.695144)
			(xy 4.344072 -411.72288) (xy 4.359491 -411.747759) (xy 4.369562 -411.758384) (xy 4.534916 -411.923738)
			(xy 4.534916 -413.057428) (xy 10.22629 -413.057428) (xy 10.22629 -412.954636) (xy 10.234355 -412.852162)
			(xy 10.250435 -412.750637) (xy 10.274431 -412.650686) (xy 10.306196 -412.552926) (xy 10.345532 -412.457959)
			(xy 10.392198 -412.366372) (xy 10.445906 -412.278728) (xy 10.506325 -412.195568) (xy 10.573083 -412.117405)
			(xy 10.645767 -412.044721) (xy 10.72393 -411.977963) (xy 10.80709 -411.917544) (xy 10.894734 -411.863836)
			(xy 10.986321 -411.81717) (xy 11.081288 -411.777834) (xy 11.179048 -411.746069) (xy 11.278999 -411.722073)
			(xy 11.380524 -411.705993) (xy 11.482998 -411.697928) (xy 11.58579 -411.697928) (xy 11.688264 -411.705993)
			(xy 11.789789 -411.722073) (xy 11.88974 -411.746069) (xy 11.9875 -411.777834) (xy 12.082467 -411.81717)
			(xy 12.174054 -411.863836) (xy 12.261698 -411.917544) (xy 12.344858 -411.977963) (xy 12.423021 -412.044721)
			(xy 12.495705 -412.117405) (xy 12.562463 -412.195568) (xy 12.622882 -412.278728) (xy 12.67659 -412.366372)
			(xy 12.723256 -412.457959) (xy 12.762592 -412.552926) (xy 12.794357 -412.650686) (xy 12.818353 -412.750637)
			(xy 12.834433 -412.852162) (xy 12.842498 -412.954636) (xy 12.843002 -413.006032) (xy 12.842498 -413.057428)
			(xy 12.834433 -413.159902) (xy 12.818353 -413.261427) (xy 12.794357 -413.361378) (xy 12.762592 -413.459138)
			(xy 12.723256 -413.554105) (xy 12.67659 -413.645692) (xy 12.622882 -413.733336) (xy 12.562463 -413.816496)
			(xy 12.495705 -413.894659) (xy 12.423021 -413.967343) (xy 12.344858 -414.034101) (xy 12.261698 -414.09452)
			(xy 12.174054 -414.148228) (xy 12.082467 -414.194894) (xy 11.9875 -414.23423) (xy 11.88974 -414.265995)
			(xy 11.789789 -414.289991) (xy 11.688264 -414.306071) (xy 11.58579 -414.314136) (xy 11.482998 -414.314136)
			(xy 11.380524 -414.306071) (xy 11.278999 -414.289991) (xy 11.179048 -414.265995) (xy 11.081288 -414.23423)
			(xy 10.986321 -414.194894) (xy 10.894734 -414.148228) (xy 10.80709 -414.09452) (xy 10.72393 -414.034101)
			(xy 10.645767 -413.967343) (xy 10.573083 -413.894659) (xy 10.506325 -413.816496) (xy 10.445906 -413.733336)
			(xy 10.392198 -413.645692) (xy 10.345532 -413.554105) (xy 10.306196 -413.459138) (xy 10.274431 -413.361378)
			(xy 10.250435 -413.261427) (xy 10.234355 -413.159902) (xy 10.22629 -413.057428) (xy 4.534916 -413.057428)
			(xy 4.534916 -414.159954) (xy 4.585716 -414.210754) (xy 4.585716 -415.03092) (xy 4.605617 -415.054179)
			(xy 4.640296 -415.104625) (xy 4.668663 -415.158872) (xy 4.690307 -415.216134) (xy 4.704914 -415.275582)
			(xy 4.712273 -415.336354) (xy 4.712716 -415.366962) (xy 4.712716 -416.05327) (xy 4.712214 -416.085231)
			(xy 4.704203 -416.148649) (xy 4.688306 -416.210563) (xy 4.664774 -416.269996) (xy 4.63398 -416.326011)
			(xy 4.596407 -416.377726) (xy 4.55265 -416.424323) (xy 4.503397 -416.465068) (xy 4.449426 -416.499319)
			(xy 4.391587 -416.526536) (xy 4.330794 -416.546289) (xy 4.268004 -416.558267) (xy 4.204208 -416.562281)
			(xy 4.140412 -416.558267) (xy 4.077622 -416.546289) (xy 4.016829 -416.526536) (xy 3.95899 -416.499319)
			(xy 3.905019 -416.465068) (xy 3.855766 -416.424323) (xy 3.812009 -416.377726) (xy 3.774436 -416.326011)
			(xy 3.743642 -416.269996) (xy 3.72011 -416.210563) (xy 3.704213 -416.148649) (xy 3.696202 -416.085231)
			(xy 3.6957 -416.05327) (xy 3.6957 -415.366962) (xy 3.696175 -415.336357) (xy 3.703557 -415.275593)
			(xy 3.718172 -415.216153) (xy 3.739811 -415.158895) (xy 3.76816 -415.104645) (xy 3.802811 -415.054186)
			(xy 3.8227 -415.03092) (xy 3.8227 -414.210754) (xy 3.8735 -414.159954) (xy 3.8735 -412.47187) (xy 3.873015 -412.449267)
			(xy 3.865028 -412.404772) (xy 3.849288 -412.362394) (xy 3.826292 -412.323473) (xy 3.796768 -412.28924)
			(xy 3.761649 -412.260775) (xy 3.722044 -412.238979) (xy 3.679206 -412.22454) (xy 3.634488 -412.217916)
			(xy 3.61188 -412.218124) (xy 3.597346 -412.218725) (xy 3.568256 -412.218978) (xy 3.553714 -412.218632)
			(xy 3.517398 -412.217264) (xy 3.445227 -412.208682) (xy 3.374152 -412.193498) (xy 3.339338 -412.183072)
			(xy 3.317204 -412.176643) (xy 3.271467 -412.170978) (xy 3.225458 -412.173643) (xy 3.180681 -412.184553)
			(xy 3.138602 -412.203349) (xy 3.100597 -412.229418) (xy 3.067909 -412.261906) (xy 3.041607 -412.29975)
			(xy 3.022553 -412.341713) (xy 3.011369 -412.386422) (xy 3.009392 -412.409386) (xy 3.009392 -414.128458)
			(xy 3.011295 -414.144089) (xy 3.021741 -414.173784) (xy 3.039121 -414.20003) (xy 3.062384 -414.221238)
			(xy 3.09012 -414.236125) (xy 3.120652 -414.243788) (xy 3.136392 -414.244282) (xy 3.21437 -414.244282)
			(xy 3.21437 -415.064448) (xy 3.230047 -415.082616) (xy 3.258289 -415.121415) (xy 3.270758 -415.141918)
			(xy 3.283632 -415.164402) (xy 3.305262 -415.211485) (xy 3.313938 -415.235898) (xy 3.318772 -415.250342)
			(xy 3.326906 -415.279699) (xy 3.330194 -415.294572) (xy 3.335369 -415.320743) (xy 3.340841 -415.373813)
			(xy 3.341116 -415.40049) (xy 3.341116 -416.16249) (xy 3.340609 -416.195176) (xy 3.332226 -416.260008)
			(xy 3.315599 -416.32323) (xy 3.291005 -416.383799) (xy 3.258848 -416.440714) (xy 3.219659 -416.493038)
			(xy 3.174086 -416.539905) (xy 3.12288 -416.580543) (xy 3.066887 -416.61428) (xy 3.00703 -416.640561)
			(xy 2.944298 -416.65895) (xy 2.879726 -416.669145) (xy 2.81438 -416.670977) (xy 2.781808 -416.668204)
			(xy 2.74574 -416.663378) (xy 2.724348 -416.661243) (xy 2.681411 -416.663337) (xy 2.63944 -416.67263)
			(xy 2.599633 -416.688856) (xy 2.563125 -416.711552) (xy 2.530959 -416.74007) (xy 2.504054 -416.773597)
			(xy 2.483177 -416.811174) (xy 2.468924 -416.85173) (xy 2.461702 -416.894106) (xy 2.46126 -416.9156)
			(xy 2.46126 -423.940932) (xy 4.839198 -423.940932) (xy 4.839198 -423.84706) (xy 4.847159 -423.753526)
			(xy 4.863023 -423.661004) (xy 4.886677 -423.570161) (xy 4.917949 -423.481652) (xy 4.956615 -423.396113)
			(xy 5.002396 -423.314161) (xy 5.054962 -423.236387) (xy 5.113935 -423.163352) (xy 5.178888 -423.09558)
			(xy 5.249355 -423.033561) (xy 5.324828 -422.977742) (xy 5.404763 -422.928524) (xy 5.488584 -422.886262)
			(xy 5.575687 -422.851262) (xy 5.665444 -422.823774) (xy 5.757209 -422.803997) (xy 5.850321 -422.792074)
			(xy 5.944108 -422.78809) (xy 6.037895 -422.792074) (xy 6.131007 -422.803997) (xy 6.222772 -422.823774)
			(xy 6.312529 -422.851262) (xy 6.399632 -422.886262) (xy 6.483453 -422.928524) (xy 6.563388 -422.977742)
			(xy 6.638861 -423.033561) (xy 6.709328 -423.09558) (xy 6.774281 -423.163352) (xy 6.833254 -423.236387)
			(xy 6.88582 -423.314161) (xy 6.931601 -423.396113) (xy 6.970267 -423.481652) (xy 7.001539 -423.570161)
			(xy 7.025193 -423.661004) (xy 7.041057 -423.753526) (xy 7.049018 -423.84706) (xy 7.049516 -423.893996)
			(xy 7.049018 -423.940932) (xy 10.339314 -423.940932) (xy 10.339314 -423.84706) (xy 10.347275 -423.753526)
			(xy 10.363139 -423.661004) (xy 10.386793 -423.570161) (xy 10.418065 -423.481652) (xy 10.456731 -423.396113)
			(xy 10.502512 -423.314161) (xy 10.555078 -423.236387) (xy 10.614051 -423.163352) (xy 10.679004 -423.09558)
			(xy 10.749471 -423.033561) (xy 10.824944 -422.977742) (xy 10.904879 -422.928524) (xy 10.9887 -422.886262)
			(xy 11.075803 -422.851262) (xy 11.16556 -422.823774) (xy 11.257325 -422.803997) (xy 11.350437 -422.792074)
			(xy 11.444224 -422.78809) (xy 11.538011 -422.792074) (xy 11.631123 -422.803997) (xy 11.722888 -422.823774)
			(xy 11.812645 -422.851262) (xy 11.899748 -422.886262) (xy 11.983569 -422.928524) (xy 12.063504 -422.977742)
			(xy 12.138977 -423.033561) (xy 12.209444 -423.09558) (xy 12.274397 -423.163352) (xy 12.33337 -423.236387)
			(xy 12.385936 -423.314161) (xy 12.431717 -423.396113) (xy 12.470383 -423.481652) (xy 12.501655 -423.570161)
			(xy 12.525309 -423.661004) (xy 12.541173 -423.753526) (xy 12.549134 -423.84706) (xy 12.549632 -423.893996)
			(xy 12.549134 -423.940932) (xy 12.541173 -424.034466) (xy 12.525309 -424.126988) (xy 12.501655 -424.217831)
			(xy 12.470383 -424.30634) (xy 12.431717 -424.391879) (xy 12.385936 -424.473831) (xy 12.33337 -424.551605)
			(xy 12.274397 -424.62464) (xy 12.209444 -424.692412) (xy 12.138977 -424.754431) (xy 12.063504 -424.81025)
			(xy 11.983569 -424.859468) (xy 11.899748 -424.90173) (xy 11.812645 -424.93673) (xy 11.722888 -424.964218)
			(xy 11.631123 -424.983995) (xy 11.538011 -424.995918) (xy 11.444224 -424.999903) (xy 11.350437 -424.995918)
			(xy 11.257325 -424.983995) (xy 11.16556 -424.964218) (xy 11.075803 -424.93673) (xy 10.9887 -424.90173)
			(xy 10.904879 -424.859468) (xy 10.824944 -424.81025) (xy 10.749471 -424.754431) (xy 10.679004 -424.692412)
			(xy 10.614051 -424.62464) (xy 10.555078 -424.551605) (xy 10.502512 -424.473831) (xy 10.456731 -424.391879)
			(xy 10.418065 -424.30634) (xy 10.386793 -424.217831) (xy 10.363139 -424.126988) (xy 10.347275 -424.034466)
			(xy 10.339314 -423.940932) (xy 7.049018 -423.940932) (xy 7.041057 -424.034466) (xy 7.025193 -424.126988)
			(xy 7.001539 -424.217831) (xy 6.970267 -424.30634) (xy 6.931601 -424.391879) (xy 6.88582 -424.473831)
			(xy 6.833254 -424.551605) (xy 6.774281 -424.62464) (xy 6.709328 -424.692412) (xy 6.638861 -424.754431)
			(xy 6.563388 -424.81025) (xy 6.483453 -424.859468) (xy 6.399632 -424.90173) (xy 6.312529 -424.93673)
			(xy 6.222772 -424.964218) (xy 6.131007 -424.983995) (xy 6.037895 -424.995918) (xy 5.944108 -424.999903)
			(xy 5.850321 -424.995918) (xy 5.757209 -424.983995) (xy 5.665444 -424.964218) (xy 5.575687 -424.93673)
			(xy 5.488584 -424.90173) (xy 5.404763 -424.859468) (xy 5.324828 -424.81025) (xy 5.249355 -424.754431)
			(xy 5.178888 -424.692412) (xy 5.113935 -424.62464) (xy 5.054962 -424.551605) (xy 5.002396 -424.473831)
			(xy 4.956615 -424.391879) (xy 4.917949 -424.30634) (xy 4.886677 -424.217831) (xy 4.863023 -424.126988)
			(xy 4.847159 -424.034466) (xy 4.839198 -423.940932) (xy 2.46126 -423.940932) (xy 2.46126 -428.141076)
			(xy 4.839198 -428.141076) (xy 4.839198 -428.047204) (xy 4.847159 -427.95367) (xy 4.863023 -427.861148)
			(xy 4.886677 -427.770305) (xy 4.917949 -427.681796) (xy 4.956615 -427.596257) (xy 5.002396 -427.514305)
			(xy 5.054962 -427.436531) (xy 5.113935 -427.363496) (xy 5.178888 -427.295724) (xy 5.249355 -427.233705)
			(xy 5.324828 -427.177886) (xy 5.404763 -427.128668) (xy 5.488584 -427.086406) (xy 5.575687 -427.051406)
			(xy 5.665444 -427.023918) (xy 5.757209 -427.004141) (xy 5.850321 -426.992218) (xy 5.944108 -426.988234)
			(xy 6.037895 -426.992218) (xy 6.131007 -427.004141) (xy 6.222772 -427.023918) (xy 6.312529 -427.051406)
			(xy 6.399632 -427.086406) (xy 6.483453 -427.128668) (xy 6.563388 -427.177886) (xy 6.638861 -427.233705)
			(xy 6.709328 -427.295724) (xy 6.774281 -427.363496) (xy 6.833254 -427.436531) (xy 6.88582 -427.514305)
			(xy 6.931601 -427.596257) (xy 6.970267 -427.681796) (xy 7.001539 -427.770305) (xy 7.025193 -427.861148)
			(xy 7.041057 -427.95367) (xy 7.049018 -428.047204) (xy 7.049516 -428.09414) (xy 7.049018 -428.141076)
			(xy 7.041057 -428.23461) (xy 7.025193 -428.327132) (xy 7.001539 -428.417975) (xy 6.970267 -428.506484)
			(xy 6.931601 -428.592023) (xy 6.88582 -428.673975) (xy 6.833254 -428.751749) (xy 6.774281 -428.824784)
			(xy 6.709328 -428.892556) (xy 6.638861 -428.954575) (xy 6.563388 -429.010394) (xy 6.483453 -429.059612)
			(xy 6.399632 -429.101874) (xy 6.312529 -429.136874) (xy 6.222772 -429.164362) (xy 6.131007 -429.184139)
			(xy 6.037895 -429.196062) (xy 5.944108 -429.200047) (xy 5.850321 -429.196062) (xy 5.757209 -429.184139)
			(xy 5.665444 -429.164362) (xy 5.575687 -429.136874) (xy 5.488584 -429.101874) (xy 5.404763 -429.059612)
			(xy 5.324828 -429.010394) (xy 5.249355 -428.954575) (xy 5.178888 -428.892556) (xy 5.113935 -428.824784)
			(xy 5.054962 -428.751749) (xy 5.002396 -428.673975) (xy 4.956615 -428.592023) (xy 4.917949 -428.506484)
			(xy 4.886677 -428.417975) (xy 4.863023 -428.327132) (xy 4.847159 -428.23461) (xy 4.839198 -428.141076)
			(xy 2.46126 -428.141076) (xy 2.46126 -432.340966) (xy 4.839198 -432.340966) (xy 4.839198 -432.247094)
			(xy 4.847159 -432.15356) (xy 4.863023 -432.061038) (xy 4.886677 -431.970195) (xy 4.917949 -431.881686)
			(xy 4.956615 -431.796147) (xy 5.002396 -431.714195) (xy 5.054962 -431.636421) (xy 5.113935 -431.563386)
			(xy 5.178888 -431.495614) (xy 5.249355 -431.433595) (xy 5.324828 -431.377776) (xy 5.404763 -431.328558)
			(xy 5.488584 -431.286296) (xy 5.575687 -431.251296) (xy 5.665444 -431.223808) (xy 5.757209 -431.204031)
			(xy 5.850321 -431.192108) (xy 5.944108 -431.188124) (xy 6.037895 -431.192108) (xy 6.131007 -431.204031)
			(xy 6.222772 -431.223808) (xy 6.312529 -431.251296) (xy 6.399632 -431.286296) (xy 6.483453 -431.328558)
			(xy 6.563388 -431.377776) (xy 6.638861 -431.433595) (xy 6.709328 -431.495614) (xy 6.774281 -431.563386)
			(xy 6.833254 -431.636421) (xy 6.88582 -431.714195) (xy 6.931601 -431.796147) (xy 6.970267 -431.881686)
			(xy 7.001539 -431.970195) (xy 7.025193 -432.061038) (xy 7.041057 -432.15356) (xy 7.049018 -432.247094)
			(xy 7.049516 -432.29403) (xy 7.049018 -432.340966) (xy 7.041057 -432.4345) (xy 7.025193 -432.527022)
			(xy 7.001539 -432.617865) (xy 6.970267 -432.706374) (xy 6.931601 -432.791913) (xy 6.88582 -432.873865)
			(xy 6.833254 -432.951639) (xy 6.774281 -433.024674) (xy 6.709328 -433.092446) (xy 6.638861 -433.154465)
			(xy 6.563388 -433.210284) (xy 6.483453 -433.259502) (xy 6.399632 -433.301764) (xy 6.312529 -433.336764)
			(xy 6.222772 -433.364252) (xy 6.131007 -433.384029) (xy 6.037895 -433.395952) (xy 5.944108 -433.399937)
			(xy 5.850321 -433.395952) (xy 5.757209 -433.384029) (xy 5.665444 -433.364252) (xy 5.575687 -433.336764)
			(xy 5.488584 -433.301764) (xy 5.404763 -433.259502) (xy 5.324828 -433.210284) (xy 5.249355 -433.154465)
			(xy 5.178888 -433.092446) (xy 5.113935 -433.024674) (xy 5.054962 -432.951639) (xy 5.002396 -432.873865)
			(xy 4.956615 -432.791913) (xy 4.917949 -432.706374) (xy 4.886677 -432.617865) (xy 4.863023 -432.527022)
			(xy 4.847159 -432.4345) (xy 4.839198 -432.340966) (xy 2.46126 -432.340966) (xy 2.46126 -436.540856)
			(xy 4.839198 -436.540856) (xy 4.839198 -436.446984) (xy 4.847159 -436.35345) (xy 4.863023 -436.260928)
			(xy 4.886677 -436.170085) (xy 4.917949 -436.081576) (xy 4.956615 -435.996037) (xy 5.002396 -435.914085)
			(xy 5.054962 -435.836311) (xy 5.113935 -435.763276) (xy 5.178888 -435.695504) (xy 5.249355 -435.633485)
			(xy 5.324828 -435.577666) (xy 5.404763 -435.528448) (xy 5.488584 -435.486186) (xy 5.575687 -435.451186)
			(xy 5.665444 -435.423698) (xy 5.757209 -435.403921) (xy 5.850321 -435.391998) (xy 5.944108 -435.388014)
			(xy 6.037895 -435.391998) (xy 6.131007 -435.403921) (xy 6.222772 -435.423698) (xy 6.312529 -435.451186)
			(xy 6.399632 -435.486186) (xy 6.483453 -435.528448) (xy 6.563388 -435.577666) (xy 6.638861 -435.633485)
			(xy 6.709328 -435.695504) (xy 6.774281 -435.763276) (xy 6.833254 -435.836311) (xy 6.88582 -435.914085)
			(xy 6.931601 -435.996037) (xy 6.970267 -436.081576) (xy 7.001539 -436.170085) (xy 7.025193 -436.260928)
			(xy 7.041057 -436.35345) (xy 7.049018 -436.446984) (xy 7.049516 -436.49392) (xy 7.049018 -436.540856)
			(xy 10.339314 -436.540856) (xy 10.339314 -436.446984) (xy 10.347275 -436.35345) (xy 10.363139 -436.260928)
			(xy 10.386793 -436.170085) (xy 10.418065 -436.081576) (xy 10.456731 -435.996037) (xy 10.502512 -435.914085)
			(xy 10.555078 -435.836311) (xy 10.614051 -435.763276) (xy 10.679004 -435.695504) (xy 10.749471 -435.633485)
			(xy 10.824944 -435.577666) (xy 10.904879 -435.528448) (xy 10.9887 -435.486186) (xy 11.075803 -435.451186)
			(xy 11.16556 -435.423698) (xy 11.257325 -435.403921) (xy 11.350437 -435.391998) (xy 11.444224 -435.388014)
			(xy 11.538011 -435.391998) (xy 11.631123 -435.403921) (xy 11.722888 -435.423698) (xy 11.812645 -435.451186)
			(xy 11.899748 -435.486186) (xy 11.983569 -435.528448) (xy 12.063504 -435.577666) (xy 12.138977 -435.633485)
			(xy 12.209444 -435.695504) (xy 12.274397 -435.763276) (xy 12.33337 -435.836311) (xy 12.385936 -435.914085)
			(xy 12.431717 -435.996037) (xy 12.470383 -436.081576) (xy 12.501655 -436.170085) (xy 12.525309 -436.260928)
			(xy 12.541173 -436.35345) (xy 12.549134 -436.446984) (xy 12.549632 -436.49392) (xy 12.549134 -436.540856)
			(xy 12.541173 -436.63439) (xy 12.525309 -436.726912) (xy 12.501655 -436.817755) (xy 12.470383 -436.906264)
			(xy 12.431717 -436.991803) (xy 12.385936 -437.073755) (xy 12.33337 -437.151529) (xy 12.274397 -437.224564)
			(xy 12.209444 -437.292336) (xy 12.138977 -437.354355) (xy 12.063504 -437.410174) (xy 11.983569 -437.459392)
			(xy 11.899748 -437.501654) (xy 11.812645 -437.536654) (xy 11.722888 -437.564142) (xy 11.631123 -437.583919)
			(xy 11.538011 -437.595842) (xy 11.444224 -437.599827) (xy 11.350437 -437.595842) (xy 11.257325 -437.583919)
			(xy 11.16556 -437.564142) (xy 11.075803 -437.536654) (xy 10.9887 -437.501654) (xy 10.904879 -437.459392)
			(xy 10.824944 -437.410174) (xy 10.749471 -437.354355) (xy 10.679004 -437.292336) (xy 10.614051 -437.224564)
			(xy 10.555078 -437.151529) (xy 10.502512 -437.073755) (xy 10.456731 -436.991803) (xy 10.418065 -436.906264)
			(xy 10.386793 -436.817755) (xy 10.363139 -436.726912) (xy 10.347275 -436.63439) (xy 10.339314 -436.540856)
			(xy 7.049018 -436.540856) (xy 7.041057 -436.63439) (xy 7.025193 -436.726912) (xy 7.001539 -436.817755)
			(xy 6.970267 -436.906264) (xy 6.931601 -436.991803) (xy 6.88582 -437.073755) (xy 6.833254 -437.151529)
			(xy 6.774281 -437.224564) (xy 6.709328 -437.292336) (xy 6.638861 -437.354355) (xy 6.563388 -437.410174)
			(xy 6.483453 -437.459392) (xy 6.399632 -437.501654) (xy 6.312529 -437.536654) (xy 6.222772 -437.564142)
			(xy 6.131007 -437.583919) (xy 6.037895 -437.595842) (xy 5.944108 -437.599827) (xy 5.850321 -437.595842)
			(xy 5.757209 -437.583919) (xy 5.665444 -437.564142) (xy 5.575687 -437.536654) (xy 5.488584 -437.501654)
			(xy 5.404763 -437.459392) (xy 5.324828 -437.410174) (xy 5.249355 -437.354355) (xy 5.178888 -437.292336)
			(xy 5.113935 -437.224564) (xy 5.054962 -437.151529) (xy 5.002396 -437.073755) (xy 4.956615 -436.991803)
			(xy 4.917949 -436.906264) (xy 4.886677 -436.817755) (xy 4.863023 -436.726912) (xy 4.847159 -436.63439)
			(xy 4.839198 -436.540856) (xy 2.46126 -436.540856) (xy 2.46126 -440.741) (xy 4.839198 -440.741) (xy 4.839198 -440.647128)
			(xy 4.847159 -440.553594) (xy 4.863023 -440.461072) (xy 4.886677 -440.370229) (xy 4.917949 -440.28172)
			(xy 4.956615 -440.196181) (xy 5.002396 -440.114229) (xy 5.054962 -440.036455) (xy 5.113935 -439.96342)
			(xy 5.178888 -439.895648) (xy 5.249355 -439.833629) (xy 5.324828 -439.77781) (xy 5.404763 -439.728592)
			(xy 5.488584 -439.68633) (xy 5.575687 -439.65133) (xy 5.665444 -439.623842) (xy 5.757209 -439.604065)
			(xy 5.850321 -439.592142) (xy 5.944108 -439.588158) (xy 6.037895 -439.592142) (xy 6.131007 -439.604065)
			(xy 6.222772 -439.623842) (xy 6.312529 -439.65133) (xy 6.399632 -439.68633) (xy 6.483453 -439.728592)
			(xy 6.563388 -439.77781) (xy 6.638861 -439.833629) (xy 6.709328 -439.895648) (xy 6.774281 -439.96342)
			(xy 6.833254 -440.036455) (xy 6.88582 -440.114229) (xy 6.931601 -440.196181) (xy 6.970267 -440.28172)
			(xy 7.001539 -440.370229) (xy 7.025193 -440.461072) (xy 7.041057 -440.553594) (xy 7.049018 -440.647128)
			(xy 7.049516 -440.694064) (xy 7.049018 -440.741) (xy 7.041057 -440.834534) (xy 7.025193 -440.927056)
			(xy 7.001539 -441.017899) (xy 6.970267 -441.106408) (xy 6.931601 -441.191947) (xy 6.88582 -441.273899)
			(xy 6.833254 -441.351673) (xy 6.774281 -441.424708) (xy 6.709328 -441.49248) (xy 6.638861 -441.554499)
			(xy 6.563388 -441.610318) (xy 6.483453 -441.659536) (xy 6.399632 -441.701798) (xy 6.312529 -441.736798)
			(xy 6.222772 -441.764286) (xy 6.131007 -441.784063) (xy 6.037895 -441.795986) (xy 5.944108 -441.799971)
			(xy 5.850321 -441.795986) (xy 5.757209 -441.784063) (xy 5.665444 -441.764286) (xy 5.575687 -441.736798)
			(xy 5.488584 -441.701798) (xy 5.404763 -441.659536) (xy 5.324828 -441.610318) (xy 5.249355 -441.554499)
			(xy 5.178888 -441.49248) (xy 5.113935 -441.424708) (xy 5.054962 -441.351673) (xy 5.002396 -441.273899)
			(xy 4.956615 -441.191947) (xy 4.917949 -441.106408) (xy 4.886677 -441.017899) (xy 4.863023 -440.927056)
			(xy 4.847159 -440.834534) (xy 4.839198 -440.741) (xy 2.46126 -440.741) (xy 2.46126 -444.94089) (xy 4.839198 -444.94089)
			(xy 4.839198 -444.847018) (xy 4.847159 -444.753484) (xy 4.863023 -444.660962) (xy 4.886677 -444.570119)
			(xy 4.917949 -444.48161) (xy 4.956615 -444.396071) (xy 5.002396 -444.314119) (xy 5.054962 -444.236345)
			(xy 5.113935 -444.16331) (xy 5.178888 -444.095538) (xy 5.249355 -444.033519) (xy 5.324828 -443.9777)
			(xy 5.404763 -443.928482) (xy 5.488584 -443.88622) (xy 5.575687 -443.85122) (xy 5.665444 -443.823732)
			(xy 5.757209 -443.803955) (xy 5.850321 -443.792032) (xy 5.944108 -443.788048) (xy 6.037895 -443.792032)
			(xy 6.131007 -443.803955) (xy 6.222772 -443.823732) (xy 6.312529 -443.85122) (xy 6.399632 -443.88622)
			(xy 6.483453 -443.928482) (xy 6.563388 -443.9777) (xy 6.638861 -444.033519) (xy 6.709328 -444.095538)
			(xy 6.774281 -444.16331) (xy 6.833254 -444.236345) (xy 6.88582 -444.314119) (xy 6.931601 -444.396071)
			(xy 6.970267 -444.48161) (xy 7.001539 -444.570119) (xy 7.025193 -444.660962) (xy 7.041057 -444.753484)
			(xy 7.049018 -444.847018) (xy 7.049516 -444.893954) (xy 7.049018 -444.94089) (xy 7.041057 -445.034424)
			(xy 7.025193 -445.126946) (xy 7.001539 -445.217789) (xy 6.970267 -445.306298) (xy 6.931601 -445.391837)
			(xy 6.88582 -445.473789) (xy 6.833254 -445.551563) (xy 6.774281 -445.624598) (xy 6.709328 -445.69237)
			(xy 6.638861 -445.754389) (xy 6.563388 -445.810208) (xy 6.558155 -445.81343) (xy 13.448017 -445.81343)
			(xy 13.452029 -445.749664) (xy 13.464001 -445.686903) (xy 13.483745 -445.626138) (xy 13.510949 -445.568326)
			(xy 13.545184 -445.51438) (xy 13.585911 -445.46515) (xy 13.632487 -445.421413) (xy 13.684177 -445.383858)
			(xy 13.740166 -445.353078) (xy 13.799572 -445.329558) (xy 13.861457 -445.313668) (xy 13.924846 -445.305661)
			(xy 13.956792 -445.30518) (xy 14.500352 -445.30518) (xy 14.517006 -445.304663) (xy 14.549182 -445.296052)
			(xy 14.578031 -445.279403) (xy 14.601586 -445.255854) (xy 14.618241 -445.227008) (xy 14.62686 -445.194834)
			(xy 14.627352 -445.17818) (xy 14.627352 -445.00038) (xy 15.99946 -445.00038) (xy 15.99946 -446.626488)
			(xy 14.627352 -446.626488) (xy 14.627352 -446.448688) (xy 14.626915 -446.432029) (xy 14.618287 -446.399847)
			(xy 14.601623 -446.370995) (xy 14.578057 -446.347441) (xy 14.549198 -446.33079) (xy 14.517011 -446.322177)
			(xy 14.500352 -446.321688) (xy 13.956792 -446.321688) (xy 13.924846 -446.321199) (xy 13.861457 -446.313192)
			(xy 13.799572 -446.297302) (xy 13.740166 -446.273782) (xy 13.684177 -446.243002) (xy 13.632487 -446.205447)
			(xy 13.585911 -446.16171) (xy 13.545184 -446.11248) (xy 13.510949 -446.058534) (xy 13.483745 -446.000722)
			(xy 13.464001 -445.939957) (xy 13.452029 -445.877196) (xy 13.448017 -445.81343) (xy 6.558155 -445.81343)
			(xy 6.483453 -445.859426) (xy 6.399632 -445.901688) (xy 6.312529 -445.936688) (xy 6.222772 -445.964176)
			(xy 6.131007 -445.983953) (xy 6.037895 -445.995876) (xy 5.944108 -445.999861) (xy 5.850321 -445.995876)
			(xy 5.757209 -445.983953) (xy 5.665444 -445.964176) (xy 5.575687 -445.936688) (xy 5.488584 -445.901688)
			(xy 5.404763 -445.859426) (xy 5.324828 -445.810208) (xy 5.249355 -445.754389) (xy 5.178888 -445.69237)
			(xy 5.113935 -445.624598) (xy 5.054962 -445.551563) (xy 5.002396 -445.473789) (xy 4.956615 -445.391837)
			(xy 4.917949 -445.306298) (xy 4.886677 -445.217789) (xy 4.863023 -445.126946) (xy 4.847159 -445.034424)
			(xy 4.839198 -444.94089) (xy 2.46126 -444.94089) (xy 2.46126 -447.79743) (xy 13.481308 -447.79743)
			(xy 13.485321 -447.733634) (xy 13.497299 -447.670844) (xy 13.517052 -447.61005) (xy 13.544269 -447.552211)
			(xy 13.57852 -447.49824) (xy 13.619266 -447.448987) (xy 13.665863 -447.405229) (xy 13.717577 -447.367657)
			(xy 13.773593 -447.336862) (xy 13.833026 -447.31333) (xy 13.894941 -447.297434) (xy 13.958359 -447.289422)
			(xy 13.99032 -447.28892) (xy 14.500352 -447.28892) (xy 14.517003 -447.288364) (xy 14.549173 -447.279756)
			(xy 14.578018 -447.263114) (xy 14.601572 -447.239572) (xy 14.61823 -447.210736) (xy 14.626855 -447.178571)
			(xy 14.627352 -447.16192) (xy 14.627352 -446.98412) (xy 15.99946 -446.98412) (xy 15.99946 -448.610736)
			(xy 14.627352 -448.610736) (xy 14.627352 -448.432936) (xy 14.626874 -448.416279) (xy 14.618257 -448.384098)
			(xy 14.601602 -448.355247) (xy 14.578044 -448.331691) (xy 14.54919 -448.315039) (xy 14.517009 -448.306425)
			(xy 14.500352 -448.305936) (xy 13.99032 -448.305936) (xy 13.958359 -448.305438) (xy 13.894941 -448.297426)
			(xy 13.833026 -448.28153) (xy 13.773593 -448.257998) (xy 13.717577 -448.227203) (xy 13.665863 -448.189631)
			(xy 13.619266 -448.145873) (xy 13.57852 -448.09662) (xy 13.544269 -448.042649) (xy 13.517052 -447.98481)
			(xy 13.497299 -447.924016) (xy 13.485321 -447.861226) (xy 13.481308 -447.79743) (xy 2.46126 -447.79743)
			(xy 2.46126 -449.141034) (xy 4.839198 -449.141034) (xy 4.839198 -449.047162) (xy 4.847159 -448.953628)
			(xy 4.863023 -448.861106) (xy 4.886677 -448.770263) (xy 4.917949 -448.681754) (xy 4.956615 -448.596215)
			(xy 5.002396 -448.514263) (xy 5.054962 -448.436489) (xy 5.113935 -448.363454) (xy 5.178888 -448.295682)
			(xy 5.249355 -448.233663) (xy 5.324828 -448.177844) (xy 5.404763 -448.128626) (xy 5.488584 -448.086364)
			(xy 5.575687 -448.051364) (xy 5.665444 -448.023876) (xy 5.757209 -448.004099) (xy 5.850321 -447.992176)
			(xy 5.944108 -447.988192) (xy 6.037895 -447.992176) (xy 6.131007 -448.004099) (xy 6.222772 -448.023876)
			(xy 6.312529 -448.051364) (xy 6.399632 -448.086364) (xy 6.483453 -448.128626) (xy 6.563388 -448.177844)
			(xy 6.638861 -448.233663) (xy 6.709328 -448.295682) (xy 6.774281 -448.363454) (xy 6.833254 -448.436489)
			(xy 6.88582 -448.514263) (xy 6.931601 -448.596215) (xy 6.970267 -448.681754) (xy 7.001539 -448.770263)
			(xy 7.025193 -448.861106) (xy 7.041057 -448.953628) (xy 7.049018 -449.047162) (xy 7.049516 -449.094098)
			(xy 7.049018 -449.141034) (xy 10.339314 -449.141034) (xy 10.339314 -449.047162) (xy 10.347275 -448.953628)
			(xy 10.363139 -448.861106) (xy 10.386793 -448.770263) (xy 10.418065 -448.681754) (xy 10.456731 -448.596215)
			(xy 10.502512 -448.514263) (xy 10.555078 -448.436489) (xy 10.614051 -448.363454) (xy 10.679004 -448.295682)
			(xy 10.749471 -448.233663) (xy 10.824944 -448.177844) (xy 10.904879 -448.128626) (xy 10.9887 -448.086364)
			(xy 11.075803 -448.051364) (xy 11.16556 -448.023876) (xy 11.257325 -448.004099) (xy 11.350437 -447.992176)
			(xy 11.444224 -447.988192) (xy 11.538011 -447.992176) (xy 11.631123 -448.004099) (xy 11.722888 -448.023876)
			(xy 11.812645 -448.051364) (xy 11.899748 -448.086364) (xy 11.983569 -448.128626) (xy 12.063504 -448.177844)
			(xy 12.138977 -448.233663) (xy 12.209444 -448.295682) (xy 12.274397 -448.363454) (xy 12.33337 -448.436489)
			(xy 12.385936 -448.514263) (xy 12.431717 -448.596215) (xy 12.470383 -448.681754) (xy 12.501655 -448.770263)
			(xy 12.525309 -448.861106) (xy 12.541173 -448.953628) (xy 12.549134 -449.047162) (xy 12.549632 -449.094098)
			(xy 12.549134 -449.141034) (xy 12.541173 -449.234568) (xy 12.525309 -449.32709) (xy 12.501655 -449.417933)
			(xy 12.470383 -449.506442) (xy 12.431717 -449.591981) (xy 12.385936 -449.673933) (xy 12.33337 -449.751707)
			(xy 12.300762 -449.79209) (xy 13.599423 -449.79209) (xy 13.603435 -449.728326) (xy 13.615407 -449.665568)
			(xy 13.63515 -449.604805) (xy 13.662353 -449.546996) (xy 13.696586 -449.493052) (xy 13.737311 -449.443824)
			(xy 13.783885 -449.400088) (xy 13.835572 -449.362534) (xy 13.891559 -449.331755) (xy 13.950963 -449.308235)
			(xy 14.012845 -449.292346) (xy 14.076231 -449.284338) (xy 14.108176 -449.283836) (xy 14.500352 -449.283836)
			(xy 14.517002 -449.283264) (xy 14.549169 -449.274657) (xy 14.578013 -449.258018) (xy 14.601566 -449.23448)
			(xy 14.618225 -449.205647) (xy 14.626853 -449.173485) (xy 14.627352 -449.156836) (xy 14.627352 -448.979036)
			(xy 15.99946 -448.979036) (xy 15.99946 -450.605144) (xy 14.627352 -450.605144) (xy 14.627352 -450.427344)
			(xy 14.626867 -450.410687) (xy 14.618252 -450.378507) (xy 14.601598 -450.349655) (xy 14.578042 -450.326099)
			(xy 14.549189 -450.309447) (xy 14.517009 -450.300833) (xy 14.500352 -450.300344) (xy 14.108176 -450.300344)
			(xy 14.076231 -450.299842) (xy 14.012845 -450.291834) (xy 13.950963 -450.275945) (xy 13.891559 -450.252425)
			(xy 13.835572 -450.221646) (xy 13.783885 -450.184092) (xy 13.737311 -450.140356) (xy 13.696586 -450.091128)
			(xy 13.662353 -450.037184) (xy 13.63515 -449.979375) (xy 13.615407 -449.918612) (xy 13.603435 -449.855854)
			(xy 13.599423 -449.79209) (xy 12.300762 -449.79209) (xy 12.274397 -449.824742) (xy 12.209444 -449.892514)
			(xy 12.138977 -449.954533) (xy 12.063504 -450.010352) (xy 11.983569 -450.05957) (xy 11.899748 -450.101832)
			(xy 11.812645 -450.136832) (xy 11.722888 -450.16432) (xy 11.631123 -450.184097) (xy 11.538011 -450.19602)
			(xy 11.444224 -450.200005) (xy 11.350437 -450.19602) (xy 11.257325 -450.184097) (xy 11.16556 -450.16432)
			(xy 11.075803 -450.136832) (xy 10.9887 -450.101832) (xy 10.904879 -450.05957) (xy 10.824944 -450.010352)
			(xy 10.749471 -449.954533) (xy 10.679004 -449.892514) (xy 10.614051 -449.824742) (xy 10.555078 -449.751707)
			(xy 10.502512 -449.673933) (xy 10.456731 -449.591981) (xy 10.418065 -449.506442) (xy 10.386793 -449.417933)
			(xy 10.363139 -449.32709) (xy 10.347275 -449.234568) (xy 10.339314 -449.141034) (xy 7.049018 -449.141034)
			(xy 7.041057 -449.234568) (xy 7.025193 -449.32709) (xy 7.001539 -449.417933) (xy 6.970267 -449.506442)
			(xy 6.931601 -449.591981) (xy 6.88582 -449.673933) (xy 6.833254 -449.751707) (xy 6.774281 -449.824742)
			(xy 6.709328 -449.892514) (xy 6.638861 -449.954533) (xy 6.563388 -450.010352) (xy 6.483453 -450.05957)
			(xy 6.399632 -450.101832) (xy 6.312529 -450.136832) (xy 6.222772 -450.16432) (xy 6.131007 -450.184097)
			(xy 6.037895 -450.19602) (xy 5.944108 -450.200005) (xy 5.850321 -450.19602) (xy 5.757209 -450.184097)
			(xy 5.665444 -450.16432) (xy 5.575687 -450.136832) (xy 5.488584 -450.101832) (xy 5.404763 -450.05957)
			(xy 5.324828 -450.010352) (xy 5.249355 -449.954533) (xy 5.178888 -449.892514) (xy 5.113935 -449.824742)
			(xy 5.054962 -449.751707) (xy 5.002396 -449.673933) (xy 4.956615 -449.591981) (xy 4.917949 -449.506442)
			(xy 4.886677 -449.417933) (xy 4.863023 -449.32709) (xy 4.847159 -449.234568) (xy 4.839198 -449.141034)
			(xy 2.46126 -449.141034) (xy 2.46126 -451.70623) (xy 13.823198 -451.70623) (xy 13.827209 -451.642466)
			(xy 13.839181 -451.579708) (xy 13.858924 -451.518946) (xy 13.886127 -451.461137) (xy 13.920361 -451.407193)
			(xy 13.961085 -451.357965) (xy 14.007659 -451.314229) (xy 14.059347 -451.276676) (xy 14.115334 -451.245897)
			(xy 14.174737 -451.222378) (xy 14.236619 -451.206489) (xy 14.300005 -451.198481) (xy 14.33195 -451.19798)
			(xy 15.14094 -451.19798) (xy 15.173641 -451.1985) (xy 15.238499 -451.206913) (xy 15.301744 -451.223568)
			(xy 15.362333 -451.248191) (xy 15.419267 -451.280376) (xy 15.44574 -451.29958) (xy 15.479522 -451.32498)
			(xy 15.49654 -451.32498) (xy 15.49654 -451.34022) (xy 15.52702 -451.376034) (xy 15.547876 -451.401208)
			(xy 15.583628 -451.45594) (xy 15.612065 -451.514806) (xy 15.63272 -451.576831) (xy 15.645251 -451.640994)
			(xy 15.649451 -451.706233) (xy 15.64525 -451.771472) (xy 15.632719 -451.835635) (xy 15.612063 -451.89766)
			(xy 15.583625 -451.956525) (xy 15.547873 -452.011257) (xy 15.52702 -452.036434) (xy 15.49654 -452.072248)
			(xy 15.49654 -452.087488) (xy 15.479522 -452.087488) (xy 15.44574 -452.112888) (xy 15.419251 -452.132116)
			(xy 15.362279 -452.164344) (xy 15.301638 -452.188984) (xy 15.238333 -452.205628) (xy 15.173414 -452.213999)
			(xy 15.140686 -452.214488) (xy 14.33195 -452.214488) (xy 14.300005 -452.213979) (xy 14.236619 -452.205971)
			(xy 14.174737 -452.190082) (xy 14.115334 -452.166563) (xy 14.059347 -452.135784) (xy 14.007659 -452.098231)
			(xy 13.961085 -452.054495) (xy 13.920361 -452.005267) (xy 13.886127 -451.951323) (xy 13.858924 -451.893514)
			(xy 13.839181 -451.832752) (xy 13.827209 -451.769994) (xy 13.823198 -451.70623) (xy 2.46126 -451.70623)
			(xy 2.46126 -453.340924) (xy 4.839198 -453.340924) (xy 4.839198 -453.247052) (xy 4.847159 -453.153518)
			(xy 4.863023 -453.060996) (xy 4.886677 -452.970153) (xy 4.917949 -452.881644) (xy 4.956615 -452.796105)
			(xy 5.002396 -452.714153) (xy 5.054962 -452.636379) (xy 5.113935 -452.563344) (xy 5.178888 -452.495572)
			(xy 5.249355 -452.433553) (xy 5.324828 -452.377734) (xy 5.404763 -452.328516) (xy 5.488584 -452.286254)
			(xy 5.575687 -452.251254) (xy 5.665444 -452.223766) (xy 5.757209 -452.203989) (xy 5.850321 -452.192066)
			(xy 5.944108 -452.188082) (xy 6.037895 -452.192066) (xy 6.131007 -452.203989) (xy 6.222772 -452.223766)
			(xy 6.312529 -452.251254) (xy 6.399632 -452.286254) (xy 6.483453 -452.328516) (xy 6.563388 -452.377734)
			(xy 6.638861 -452.433553) (xy 6.709328 -452.495572) (xy 6.774281 -452.563344) (xy 6.833254 -452.636379)
			(xy 6.88582 -452.714153) (xy 6.931601 -452.796105) (xy 6.970267 -452.881644) (xy 7.001539 -452.970153)
			(xy 7.025193 -453.060996) (xy 7.041057 -453.153518) (xy 7.049018 -453.247052) (xy 7.049516 -453.293988)
			(xy 7.049018 -453.340924) (xy 7.041057 -453.434458) (xy 7.025193 -453.52698) (xy 7.001539 -453.617823)
			(xy 6.970267 -453.706332) (xy 6.931601 -453.791871) (xy 6.88582 -453.873823) (xy 6.833254 -453.951597)
			(xy 6.774281 -454.024632) (xy 6.709328 -454.092404) (xy 6.638861 -454.154423) (xy 6.563388 -454.210242)
			(xy 6.483453 -454.25946) (xy 6.399632 -454.301722) (xy 6.312529 -454.336722) (xy 6.222772 -454.36421)
			(xy 6.131007 -454.383987) (xy 6.037895 -454.39591) (xy 5.944108 -454.399895) (xy 5.850321 -454.39591)
			(xy 5.757209 -454.383987) (xy 5.665444 -454.36421) (xy 5.575687 -454.336722) (xy 5.488584 -454.301722)
			(xy 5.404763 -454.25946) (xy 5.324828 -454.210242) (xy 5.249355 -454.154423) (xy 5.178888 -454.092404)
			(xy 5.113935 -454.024632) (xy 5.054962 -453.951597) (xy 5.002396 -453.873823) (xy 4.956615 -453.791871)
			(xy 4.917949 -453.706332) (xy 4.886677 -453.617823) (xy 4.863023 -453.52698) (xy 4.847159 -453.434458)
			(xy 4.839198 -453.340924) (xy 2.46126 -453.340924) (xy 2.46126 -457.541068) (xy 4.839198 -457.541068)
			(xy 4.839198 -457.447196) (xy 4.847159 -457.353662) (xy 4.863023 -457.26114) (xy 4.886677 -457.170297)
			(xy 4.917949 -457.081788) (xy 4.956615 -456.996249) (xy 5.002396 -456.914297) (xy 5.054962 -456.836523)
			(xy 5.113935 -456.763488) (xy 5.178888 -456.695716) (xy 5.249355 -456.633697) (xy 5.324828 -456.577878)
			(xy 5.404763 -456.52866) (xy 5.488584 -456.486398) (xy 5.575687 -456.451398) (xy 5.665444 -456.42391)
			(xy 5.757209 -456.404133) (xy 5.850321 -456.39221) (xy 5.944108 -456.388226) (xy 6.037895 -456.39221)
			(xy 6.131007 -456.404133) (xy 6.222772 -456.42391) (xy 6.312529 -456.451398) (xy 6.399632 -456.486398)
			(xy 6.483453 -456.52866) (xy 6.563388 -456.577878) (xy 6.638861 -456.633697) (xy 6.709328 -456.695716)
			(xy 6.774281 -456.763488) (xy 6.833254 -456.836523) (xy 6.88582 -456.914297) (xy 6.931601 -456.996249)
			(xy 6.970267 -457.081788) (xy 7.001539 -457.170297) (xy 7.025193 -457.26114) (xy 7.041057 -457.353662)
			(xy 7.049018 -457.447196) (xy 7.049516 -457.494132) (xy 7.049018 -457.541068) (xy 7.049013 -457.541122)
			(xy 17.366996 -457.541122) (xy 17.366996 -456.281282) (xy 17.367472 -456.249826) (xy 17.375243 -456.187397)
			(xy 17.390658 -456.126403) (xy 17.413479 -456.067777) (xy 17.44336 -456.012415) (xy 17.479843 -455.961162)
			(xy 17.52237 -455.914802) (xy 17.570293 -455.874043) (xy 17.622877 -455.839508) (xy 17.679321 -455.811725)
			(xy 17.738762 -455.791117) (xy 17.800291 -455.778001) (xy 17.862968 -455.772577) (xy 17.925835 -455.774926)
			(xy 17.987933 -455.785014) (xy 18.048311 -455.802687) (xy 18.106047 -455.827673) (xy 18.16026 -455.859593)
			(xy 18.21012 -455.897956) (xy 18.254866 -455.942179) (xy 18.293815 -455.991584) (xy 18.32637 -456.045417)
			(xy 18.352035 -456.102855) (xy 18.370417 -456.163021) (xy 18.381235 -456.224995) (xy 18.38325 -456.25639)
			(xy 18.38579 -456.30719) (xy 18.459196 -456.377294) (xy 18.509996 -456.377294) (xy 18.526651 -456.376802)
			(xy 18.558826 -456.368181) (xy 18.587674 -456.351526) (xy 18.611227 -456.327972) (xy 18.627882 -456.299124)
			(xy 18.636502 -456.266949) (xy 18.636996 -456.250294) (xy 18.636996 -456.243944) (xy 18.637513 -456.211638)
			(xy 18.645705 -456.147549) (xy 18.661949 -456.085013) (xy 18.685985 -456.025039) (xy 18.717424 -455.968593)
			(xy 18.75576 -455.916584) (xy 18.800376 -455.869851) (xy 18.850553 -455.829145) (xy 18.905481 -455.795124)
			(xy 18.964277 -455.768336) (xy 19.025993 -455.749211) (xy 19.089634 -455.738058) (xy 19.154176 -455.735057)
			(xy 19.218577 -455.740256) (xy 19.281801 -455.753571) (xy 19.342829 -455.774789) (xy 19.400678 -455.803566)
			(xy 19.454415 -455.839439) (xy 19.503176 -455.881831) (xy 19.546173 -455.930058) (xy 19.564858 -455.956416)
			(xy 19.57811 -455.974919) (xy 19.610101 -456.007285) (xy 19.647344 -456.033437) (xy 19.688649 -456.052538)
			(xy 19.732696 -456.063979) (xy 19.778075 -456.067392) (xy 19.823338 -456.06267) (xy 19.867035 -456.049962)
			(xy 19.907772 -456.029676) (xy 19.944244 -456.002459) (xy 19.975287 -455.969183) (xy 19.988022 -455.95032)
			(xy 20.005615 -455.923885) (xy 20.046361 -455.87518) (xy 20.092856 -455.83193) (xy 20.144376 -455.794808)
			(xy 20.200119 -455.764391) (xy 20.259216 -455.741154) (xy 20.320747 -455.725459) (xy 20.383753 -455.71755)
			(xy 20.447255 -455.71755) (xy 20.510261 -455.725459) (xy 20.571792 -455.741154) (xy 20.630889 -455.764391)
			(xy 20.686632 -455.794808) (xy 20.738152 -455.83193) (xy 20.784647 -455.87518) (xy 20.825393 -455.923885)
			(xy 20.842986 -455.95032) (xy 20.855733 -455.969174) (xy 20.886773 -456.002447) (xy 20.923243 -456.02966)
			(xy 20.963976 -456.049944) (xy 21.007671 -456.06265) (xy 21.052929 -456.067371) (xy 21.098305 -456.063957)
			(xy 21.142348 -456.052517) (xy 21.18365 -456.033417) (xy 21.220889 -456.007266) (xy 21.252877 -455.974902)
			(xy 21.26615 -455.956416) (xy 21.284767 -455.930004) (xy 21.327766 -455.881763) (xy 21.376529 -455.839358)
			(xy 21.430272 -455.803473) (xy 21.488128 -455.774686) (xy 21.549166 -455.753461) (xy 21.6124 -455.740141)
			(xy 21.676813 -455.734939) (xy 21.741365 -455.737939) (xy 21.805018 -455.749094) (xy 21.866744 -455.768224)
			(xy 21.925549 -455.79502) (xy 21.980485 -455.82905) (xy 22.030667 -455.869766) (xy 22.075287 -455.916511)
			(xy 22.113624 -455.968533) (xy 22.145062 -456.024993) (xy 22.169093 -456.084981) (xy 22.18533 -456.14753)
			(xy 22.193512 -456.211633) (xy 22.194012 -456.243944) (xy 22.194012 -457.541122) (xy 22.1936 -457.570292)
			(xy 22.18687 -457.628244) (xy 22.173559 -457.685047) (xy 22.153842 -457.739955) (xy 22.127976 -457.792249)
			(xy 22.112478 -457.816966) (xy 22.092412 -457.848462) (xy 22.092412 -458.531976) (xy 21.278596 -458.531976)
			(xy 21.278596 -457.848462) (xy 21.25853 -457.816966) (xy 21.240393 -457.787886) (xy 21.211292 -457.725833)
			(xy 21.190785 -457.660436) (xy 21.179246 -457.592877) (xy 21.177504 -457.558648) (xy 21.176425 -457.542397)
			(xy 21.167059 -457.511214) (xy 21.150107 -457.483415) (xy 21.126674 -457.46081) (xy 21.098283 -457.44487)
			(xy 21.066784 -457.436632) (xy 21.034224 -457.436632) (xy 21.002725 -457.44487) (xy 20.974334 -457.46081)
			(xy 20.950901 -457.483415) (xy 20.933949 -457.511214) (xy 20.924583 -457.542397) (xy 20.923504 -457.558648)
			(xy 20.921754 -457.592876) (xy 20.910225 -457.660436) (xy 20.889717 -457.725832) (xy 20.860602 -457.787877)
			(xy 20.842478 -457.816966) (xy 20.822412 -457.848462) (xy 20.822412 -458.531976) (xy 20.008596 -458.531976)
			(xy 20.008596 -457.848462) (xy 19.98853 -457.816966) (xy 19.970393 -457.787886) (xy 19.941292 -457.725833)
			(xy 19.920785 -457.660436) (xy 19.909246 -457.592877) (xy 19.907504 -457.558648) (xy 19.906425 -457.542397)
			(xy 19.897059 -457.511214) (xy 19.880107 -457.483415) (xy 19.856674 -457.46081) (xy 19.828283 -457.44487)
			(xy 19.796784 -457.436632) (xy 19.764224 -457.436632) (xy 19.732725 -457.44487) (xy 19.704334 -457.46081)
			(xy 19.680901 -457.483415) (xy 19.663949 -457.511214) (xy 19.654583 -457.542397) (xy 19.653504 -457.558648)
			(xy 19.651754 -457.592876) (xy 19.640225 -457.660436) (xy 19.619717 -457.725832) (xy 19.590602 -457.787877)
			(xy 19.572478 -457.816966) (xy 19.552412 -457.848462) (xy 19.552412 -458.531976) (xy 18.738596 -458.531976)
			(xy 18.738596 -457.848462) (xy 18.71853 -457.816966) (xy 18.700393 -457.787886) (xy 18.671292 -457.725833)
			(xy 18.650785 -457.660436) (xy 18.639246 -457.592877) (xy 18.637504 -457.558648) (xy 18.636425 -457.542397)
			(xy 18.627059 -457.511214) (xy 18.610107 -457.483415) (xy 18.586674 -457.46081) (xy 18.558283 -457.44487)
			(xy 18.526784 -457.436632) (xy 18.494224 -457.436632) (xy 18.462725 -457.44487) (xy 18.434334 -457.46081)
			(xy 18.410901 -457.483415) (xy 18.393949 -457.511214) (xy 18.384583 -457.542397) (xy 18.383504 -457.558648)
			(xy 18.381754 -457.592876) (xy 18.370225 -457.660436) (xy 18.349717 -457.725832) (xy 18.320602 -457.787877)
			(xy 18.302478 -457.816966) (xy 18.282412 -457.848462) (xy 18.282412 -458.531976) (xy 17.468596 -458.531976)
			(xy 17.468596 -457.848462) (xy 17.44853 -457.816966) (xy 17.433037 -457.792245) (xy 17.407153 -457.73996)
			(xy 17.387429 -457.685053) (xy 17.374125 -457.628248) (xy 17.367416 -457.570293) (xy 17.366996 -457.541122)
			(xy 7.049013 -457.541122) (xy 7.041057 -457.634602) (xy 7.025193 -457.727124) (xy 7.001539 -457.817967)
			(xy 6.970267 -457.906476) (xy 6.931601 -457.992015) (xy 6.88582 -458.073967) (xy 6.833254 -458.151741)
			(xy 6.774281 -458.224776) (xy 6.709328 -458.292548) (xy 6.638861 -458.354567) (xy 6.563388 -458.410386)
			(xy 6.483453 -458.459604) (xy 6.399632 -458.501866) (xy 6.312529 -458.536866) (xy 6.222772 -458.564354)
			(xy 6.131007 -458.584131) (xy 6.037895 -458.596054) (xy 5.944108 -458.600039) (xy 5.850321 -458.596054)
			(xy 5.757209 -458.584131) (xy 5.665444 -458.564354) (xy 5.575687 -458.536866) (xy 5.488584 -458.501866)
			(xy 5.404763 -458.459604) (xy 5.324828 -458.410386) (xy 5.249355 -458.354567) (xy 5.178888 -458.292548)
			(xy 5.113935 -458.224776) (xy 5.054962 -458.151741) (xy 5.002396 -458.073967) (xy 4.956615 -457.992015)
			(xy 4.917949 -457.906476) (xy 4.886677 -457.817967) (xy 4.863023 -457.727124) (xy 4.847159 -457.634602)
			(xy 4.839198 -457.541068) (xy 2.46126 -457.541068) (xy 2.46126 -461.740958) (xy 4.839198 -461.740958)
			(xy 4.839198 -461.647086) (xy 4.847159 -461.553552) (xy 4.863023 -461.46103) (xy 4.886677 -461.370187)
			(xy 4.917949 -461.281678) (xy 4.956615 -461.196139) (xy 5.002396 -461.114187) (xy 5.054962 -461.036413)
			(xy 5.113935 -460.963378) (xy 5.178888 -460.895606) (xy 5.249355 -460.833587) (xy 5.324828 -460.777768)
			(xy 5.404763 -460.72855) (xy 5.488584 -460.686288) (xy 5.575687 -460.651288) (xy 5.665444 -460.6238)
			(xy 5.757209 -460.604023) (xy 5.850321 -460.5921) (xy 5.944108 -460.588116) (xy 5.961811 -460.588868)
			(xy 10.338816 -460.588868) (xy 12.549632 -460.588868) (xy 12.549632 -462.799176) (xy 10.338816 -462.799176)
			(xy 10.338816 -460.588868) (xy 5.961811 -460.588868) (xy 6.037895 -460.5921) (xy 6.131007 -460.604023)
			(xy 6.222772 -460.6238) (xy 6.312529 -460.651288) (xy 6.399632 -460.686288) (xy 6.483453 -460.72855)
			(xy 6.563388 -460.777768) (xy 6.638861 -460.833587) (xy 6.709328 -460.895606) (xy 6.774281 -460.963378)
			(xy 6.833254 -461.036413) (xy 6.88582 -461.114187) (xy 6.931601 -461.196139) (xy 6.970267 -461.281678)
			(xy 7.001539 -461.370187) (xy 7.025193 -461.46103) (xy 7.041057 -461.553552) (xy 7.049018 -461.647086)
			(xy 7.049516 -461.694022) (xy 7.049018 -461.740958) (xy 7.041057 -461.834492) (xy 7.025193 -461.927014)
			(xy 7.001539 -462.017857) (xy 6.970267 -462.106366) (xy 6.931601 -462.191905) (xy 6.88582 -462.273857)
			(xy 6.833254 -462.351631) (xy 6.774281 -462.424666) (xy 6.709328 -462.492438) (xy 6.638861 -462.554457)
			(xy 6.563388 -462.610276) (xy 6.483453 -462.659494) (xy 6.399632 -462.701756) (xy 6.312529 -462.736756)
			(xy 6.222772 -462.764244) (xy 6.131007 -462.784021) (xy 6.037895 -462.795944) (xy 5.944108 -462.799929)
			(xy 5.850321 -462.795944) (xy 5.757209 -462.784021) (xy 5.665444 -462.764244) (xy 5.575687 -462.736756)
			(xy 5.488584 -462.701756) (xy 5.404763 -462.659494) (xy 5.324828 -462.610276) (xy 5.249355 -462.554457)
			(xy 5.178888 -462.492438) (xy 5.113935 -462.424666) (xy 5.054962 -462.351631) (xy 5.002396 -462.273857)
			(xy 4.956615 -462.191905) (xy 4.917949 -462.106366) (xy 4.886677 -462.017857) (xy 4.863023 -461.927014)
			(xy 4.847159 -461.834492) (xy 4.839198 -461.740958) (xy 2.46126 -461.740958) (xy 2.46126 -464.413362)
			(xy 29.519874 -464.413362) (xy 29.519874 -464.326462) (xy 29.527892 -464.239933) (xy 29.54386 -464.154513)
			(xy 29.567641 -464.070931) (xy 29.599033 -463.989899) (xy 29.637767 -463.91211) (xy 29.683514 -463.838226)
			(xy 29.735883 -463.768879) (xy 29.794427 -463.704659) (xy 29.858647 -463.646115) (xy 29.927994 -463.593746)
			(xy 30.001878 -463.547999) (xy 30.079667 -463.509265) (xy 30.160699 -463.477873) (xy 30.244281 -463.454092)
			(xy 30.329701 -463.438124) (xy 30.41623 -463.430106) (xy 30.50313 -463.430106) (xy 30.589659 -463.438124)
			(xy 30.675079 -463.454092) (xy 30.758661 -463.477873) (xy 30.839693 -463.509265) (xy 30.917482 -463.547999)
			(xy 30.991366 -463.593746) (xy 31.060713 -463.646115) (xy 31.124933 -463.704659) (xy 31.183477 -463.768879)
			(xy 31.235846 -463.838226) (xy 31.281593 -463.91211) (xy 31.320327 -463.989899) (xy 31.351719 -464.070931)
			(xy 31.3755 -464.154513) (xy 31.391468 -464.239933) (xy 31.399486 -464.326462) (xy 31.399988 -464.369912)
			(xy 31.399486 -464.413362) (xy 31.391468 -464.499891) (xy 31.3755 -464.585311) (xy 31.351719 -464.668893)
			(xy 31.320327 -464.749925) (xy 31.281593 -464.827714) (xy 31.235846 -464.901598) (xy 31.183477 -464.970945)
			(xy 31.124933 -465.035165) (xy 31.060713 -465.093709) (xy 30.991366 -465.146078) (xy 30.917482 -465.191825)
			(xy 30.839693 -465.230559) (xy 30.758661 -465.261951) (xy 30.675079 -465.285732) (xy 30.589659 -465.3017)
			(xy 30.50313 -465.309718) (xy 30.41623 -465.309718) (xy 30.329701 -465.3017) (xy 30.244281 -465.285732)
			(xy 30.160699 -465.261951) (xy 30.079667 -465.230559) (xy 30.001878 -465.191825) (xy 29.927994 -465.146078)
			(xy 29.858647 -465.093709) (xy 29.794427 -465.035165) (xy 29.735883 -464.970945) (xy 29.683514 -464.901598)
			(xy 29.637767 -464.827714) (xy 29.599033 -464.749925) (xy 29.567641 -464.668893) (xy 29.54386 -464.585311)
			(xy 29.527892 -464.499891) (xy 29.519874 -464.413362) (xy 2.46126 -464.413362) (xy 2.46126 -471.199869)
			(xy 6.67223 -471.199869) (xy 6.673838 -471.107133) (xy 6.683486 -471.014885) (xy 6.701101 -470.923822)
			(xy 6.72655 -470.834632) (xy 6.759642 -470.747985) (xy 6.800126 -470.664536) (xy 6.847698 -470.584915)
			(xy 6.901999 -470.509721) (xy 6.962619 -470.439522) (xy 7.0291 -470.374847) (xy 7.100943 -470.316184)
			(xy 7.177604 -470.263975) (xy 7.258506 -470.218614) (xy 7.343038 -470.180444) (xy 7.430563 -470.149751)
			(xy 7.520421 -470.126769) (xy 7.611934 -470.111669) (xy 7.704413 -470.104565) (xy 7.797158 -470.105512)
			(xy 7.889472 -470.114503) (xy 7.980658 -470.131468) (xy 8.070028 -470.156282) (xy 8.156908 -470.188755)
			(xy 8.240643 -470.228644) (xy 8.320602 -470.275647) (xy 8.396181 -470.32941) (xy 8.46681 -470.389528)
			(xy 8.531958 -470.455547) (xy 8.591131 -470.52697) (xy 8.643885 -470.603257) (xy 8.689821 -470.683833)
			(xy 8.70966 -470.725754) (xy 8.719485 -470.745936) (xy 8.745132 -470.782771) (xy 8.776848 -470.81453)
			(xy 8.813648 -470.840226) (xy 8.854389 -470.859061) (xy 8.897804 -470.870449) (xy 8.942544 -470.874038)
			(xy 8.987218 -470.869714) (xy 9.03044 -470.857613) (xy 9.070865 -470.838111) (xy 9.107238 -470.811813)
			(xy 9.138428 -470.779537) (xy 9.163465 -470.742286) (xy 9.172956 -470.721944) (xy 9.22028 -470.605244)
			(xy 9.321321 -470.374541) (xy 9.429572 -470.147133) (xy 9.544926 -469.923244) (xy 9.667269 -469.703096)
			(xy 9.796479 -469.486907) (xy 9.932429 -469.274892) (xy 10.074983 -469.06726) (xy 10.224001 -468.864216)
			(xy 10.379335 -468.665963) (xy 10.540831 -468.472696) (xy 10.708328 -468.284608) (xy 10.881662 -468.101883)
			(xy 11.060661 -467.924704) (xy 11.245146 -467.753246) (xy 11.434936 -467.587678) (xy 11.629843 -467.428165)
			(xy 11.829672 -467.274865) (xy 12.034227 -467.127929) (xy 12.243305 -466.987503) (xy 12.456698 -466.853726)
			(xy 12.674196 -466.726731) (xy 12.895582 -466.606644) (xy 13.120638 -466.493582) (xy 13.34914 -466.38766)
			(xy 13.580862 -466.28898) (xy 13.815575 -466.197642) (xy 14.053047 -466.113736) (xy 14.293041 -466.037344)
			(xy 14.53532 -465.968542) (xy 14.779644 -465.907399) (xy 15.025772 -465.853976) (xy 15.273459 -465.808324)
			(xy 15.52246 -465.770489) (xy 15.772528 -465.740509) (xy 16.023416 -465.718414) (xy 16.274874 -465.704225)
			(xy 16.526655 -465.697956) (xy 16.778509 -465.699614) (xy 17.030185 -465.709197) (xy 17.281436 -465.726695)
			(xy 17.532011 -465.752092) (xy 17.781663 -465.785361) (xy 18.030144 -465.82647) (xy 18.277208 -465.875379)
			(xy 18.522611 -465.932038) (xy 18.766109 -465.996392) (xy 19.007462 -466.068377) (xy 19.24643 -466.147922)
			(xy 19.482776 -466.234947) (xy 19.716266 -466.329368) (xy 19.946669 -466.431089) (xy 20.173757 -466.540011)
			(xy 20.397305 -466.656025) (xy 20.617091 -466.779016) (xy 20.832898 -466.908864) (xy 20.901845 -466.953362)
			(xy 29.519874 -466.953362) (xy 29.519874 -466.866462) (xy 29.527892 -466.779933) (xy 29.54386 -466.694513)
			(xy 29.567641 -466.610931) (xy 29.599033 -466.529899) (xy 29.637767 -466.45211) (xy 29.683514 -466.378226)
			(xy 29.735883 -466.308879) (xy 29.794427 -466.244659) (xy 29.858647 -466.186115) (xy 29.927994 -466.133746)
			(xy 30.001878 -466.087999) (xy 30.079667 -466.049265) (xy 30.160699 -466.017873) (xy 30.244281 -465.994092)
			(xy 30.329701 -465.978124) (xy 30.41623 -465.970106) (xy 30.50313 -465.970106) (xy 30.589659 -465.978124)
			(xy 30.675079 -465.994092) (xy 30.758661 -466.017873) (xy 30.839693 -466.049265) (xy 30.917482 -466.087999)
			(xy 30.991366 -466.133746) (xy 31.060713 -466.186115) (xy 31.124933 -466.244659) (xy 31.183477 -466.308879)
			(xy 31.235846 -466.378226) (xy 31.281593 -466.45211) (xy 31.320327 -466.529899) (xy 31.351719 -466.610931)
			(xy 31.3755 -466.694513) (xy 31.391468 -466.779933) (xy 31.399486 -466.866462) (xy 31.399988 -466.909912)
			(xy 31.399486 -466.953362) (xy 34.599874 -466.953362) (xy 34.599874 -466.866462) (xy 34.607892 -466.779933)
			(xy 34.62386 -466.694513) (xy 34.647641 -466.610931) (xy 34.679033 -466.529899) (xy 34.717767 -466.45211)
			(xy 34.763514 -466.378226) (xy 34.815883 -466.308879) (xy 34.874427 -466.244659) (xy 34.938647 -466.186115)
			(xy 35.007994 -466.133746) (xy 35.081878 -466.087999) (xy 35.159667 -466.049265) (xy 35.240699 -466.017873)
			(xy 35.324281 -465.994092) (xy 35.409701 -465.978124) (xy 35.49623 -465.970106) (xy 35.58313 -465.970106)
			(xy 35.669659 -465.978124) (xy 35.682508 -465.980526) (xy 70.882256 -465.980526) (xy 70.882256 -464.787234)
			(xy 70.882946 -464.751168) (xy 70.893269 -464.679777) (xy 70.90283 -464.644994) (xy 70.907656 -464.627468)
			(xy 70.907656 -464.25358) (xy 71.873872 -464.25358) (xy 71.873872 -464.627468) (xy 71.878698 -464.644994)
			(xy 71.884895 -464.6676) (xy 72.293988 -464.6676) (xy 72.293988 -463.942684) (xy 72.294476 -463.909957)
			(xy 72.302873 -463.845045) (xy 72.319526 -463.781745) (xy 72.34416 -463.721104) (xy 72.376368 -463.664123)
			(xy 72.395588 -463.63763) (xy 72.420988 -463.603848) (xy 72.420988 -463.586576) (xy 72.436228 -463.586576)
			(xy 72.472042 -463.55635) (xy 72.497219 -463.535497) (xy 72.551951 -463.499746) (xy 72.610816 -463.471307)
			(xy 72.672841 -463.450652) (xy 72.737003 -463.438121) (xy 72.802242 -463.433921) (xy 72.867481 -463.438121)
			(xy 72.931643 -463.450652) (xy 72.993668 -463.471307) (xy 73.052533 -463.499746) (xy 73.107265 -463.535497)
			(xy 73.132442 -463.55635) (xy 73.168256 -463.586576) (xy 73.183496 -463.586576) (xy 73.183496 -463.603848)
			(xy 73.208896 -463.63763) (xy 73.219564 -463.652362) (xy 73.232666 -463.670324) (xy 73.264069 -463.701793)
			(xy 73.300465 -463.727322) (xy 73.340746 -463.746133) (xy 73.383684 -463.757655) (xy 73.427971 -463.761534)
			(xy 73.472258 -463.757655) (xy 73.515196 -463.746133) (xy 73.555477 -463.727322) (xy 73.591873 -463.701793)
			(xy 73.623276 -463.670324) (xy 73.636378 -463.652362) (xy 73.647046 -463.63763) (xy 73.672192 -463.603848)
			(xy 73.672192 -463.586576) (xy 73.687686 -463.586576) (xy 73.7235 -463.55635) (xy 73.748677 -463.535497)
			(xy 73.803409 -463.499746) (xy 73.862274 -463.471307) (xy 73.924299 -463.450652) (xy 73.988461 -463.438121)
			(xy 74.0537 -463.433921) (xy 74.118939 -463.438121) (xy 74.183101 -463.450652) (xy 74.245126 -463.471307)
			(xy 74.303991 -463.499746) (xy 74.358723 -463.535497) (xy 74.3839 -463.55635) (xy 74.419714 -463.586576)
			(xy 74.435208 -463.586576) (xy 74.435208 -463.603848) (xy 74.460354 -463.63763) (xy 74.479619 -463.664101)
			(xy 74.511879 -463.721073) (xy 74.536561 -463.781714) (xy 74.553255 -463.845022) (xy 74.561686 -463.909948)
			(xy 74.562208 -463.942684) (xy 74.562208 -464.51012) (xy 86.39887 -464.51012) (xy 86.402874 -464.310022)
			(xy 86.414881 -464.110244) (xy 86.434872 -463.911107) (xy 86.462814 -463.712929) (xy 86.498662 -463.516027)
			(xy 86.54236 -463.320718) (xy 86.593837 -463.127313) (xy 86.653011 -462.936123) (xy 86.719787 -462.747453)
			(xy 86.794059 -462.561606) (xy 86.875706 -462.378879) (xy 86.964599 -462.199566) (xy 87.060595 -462.023952)
			(xy 87.16354 -461.85232) (xy 87.27327 -461.684944) (xy 87.389608 -461.522093) (xy 87.512369 -461.364026)
			(xy 87.641356 -461.210998) (xy 87.776363 -461.063253) (xy 87.917172 -460.921027) (xy 88.063559 -460.78455)
			(xy 88.215289 -460.654038) (xy 88.37212 -460.529702) (xy 88.533799 -460.41174) (xy 88.700069 -460.300341)
			(xy 88.870662 -460.195684) (xy 89.045306 -460.097936) (xy 89.223722 -460.007253) (xy 89.405622 -459.923782)
			(xy 89.590717 -459.847655) (xy 89.778709 -459.778995) (xy 89.969298 -459.717911) (xy 90.162178 -459.664501)
			(xy 90.35704 -459.618852) (xy 90.553573 -459.581035) (xy 90.751462 -459.551111) (xy 90.950389 -459.529129)
			(xy 91.150037 -459.515124) (xy 91.350085 -459.509118) (xy 91.550213 -459.51112) (xy 91.750101 -459.521128)
			(xy 91.949428 -459.539125) (xy 92.147876 -459.565083) (xy 92.345126 -459.59896) (xy 92.540863 -459.640702)
			(xy 92.734773 -459.690241) (xy 92.926546 -459.747499) (xy 93.115875 -459.812384) (xy 93.302455 -459.884792)
			(xy 93.48599 -459.964608) (xy 93.666184 -460.051702) (xy 93.842749 -460.145936) (xy 94.015402 -460.247159)
			(xy 94.183867 -460.355209) (xy 94.347875 -460.469912) (xy 94.507162 -460.591086) (xy 94.661473 -460.718535)
			(xy 94.810561 -460.852056) (xy 94.954188 -460.991436) (xy 95.092124 -461.13645) (xy 95.224147 -461.286867)
			(xy 95.350046 -461.442445) (xy 95.46962 -461.602937) (xy 95.582676 -461.768083) (xy 95.689035 -461.937621)
			(xy 95.788526 -462.111279) (xy 95.880989 -462.288778) (xy 95.966276 -462.469834) (xy 96.044251 -462.654158)
			(xy 96.114788 -462.841454) (xy 96.177776 -463.031422) (xy 96.233113 -463.223758) (xy 96.28071 -463.418154)
			(xy 96.320491 -463.614299) (xy 96.352393 -463.811878) (xy 96.376364 -464.010575) (xy 96.392366 -464.210073)
			(xy 96.400373 -464.410051) (xy 96.400874 -464.51012) (xy 96.400373 -464.610189) (xy 96.392366 -464.810167)
			(xy 96.376364 -465.009665) (xy 96.352393 -465.208362) (xy 96.320491 -465.405941) (xy 96.28071 -465.602086)
			(xy 96.233113 -465.796482) (xy 96.177776 -465.988818) (xy 96.114788 -466.178786) (xy 96.044251 -466.366082)
			(xy 95.966276 -466.550406) (xy 95.880989 -466.731462) (xy 95.788526 -466.908961) (xy 95.689035 -467.082619)
			(xy 95.582676 -467.252157) (xy 95.46962 -467.417303) (xy 95.350046 -467.577795) (xy 95.224147 -467.733373)
			(xy 95.092124 -467.88379) (xy 94.954188 -468.028804) (xy 94.810561 -468.168184) (xy 94.661473 -468.301705)
			(xy 94.507162 -468.429154) (xy 94.347875 -468.550328) (xy 94.183867 -468.665031) (xy 94.015402 -468.773081)
			(xy 93.842749 -468.874304) (xy 93.666184 -468.968538) (xy 93.48599 -469.055632) (xy 93.302455 -469.135448)
			(xy 93.115875 -469.207856) (xy 92.926546 -469.272741) (xy 92.734773 -469.329999) (xy 92.540863 -469.379538)
			(xy 92.345126 -469.42128) (xy 92.147876 -469.455157) (xy 91.949428 -469.481115) (xy 91.750101 -469.499112)
			(xy 91.550213 -469.50912) (xy 91.350085 -469.511122) (xy 91.150037 -469.505116) (xy 90.950389 -469.491111)
			(xy 90.751462 -469.469129) (xy 90.553573 -469.439205) (xy 90.35704 -469.401388) (xy 90.162178 -469.355739)
			(xy 89.969298 -469.302329) (xy 89.778709 -469.241245) (xy 89.590717 -469.172585) (xy 89.405622 -469.096458)
			(xy 89.223722 -469.012987) (xy 89.045306 -468.922304) (xy 88.870662 -468.824556) (xy 88.700069 -468.719899)
			(xy 88.533799 -468.6085) (xy 88.37212 -468.490538) (xy 88.215289 -468.366202) (xy 88.063559 -468.23569)
			(xy 87.917172 -468.099213) (xy 87.776363 -467.956987) (xy 87.641356 -467.809242) (xy 87.512369 -467.656214)
			(xy 87.389608 -467.498147) (xy 87.27327 -467.335296) (xy 87.16354 -467.16792) (xy 87.060595 -466.996288)
			(xy 86.964599 -466.820674) (xy 86.875706 -466.641361) (xy 86.794059 -466.458634) (xy 86.719787 -466.272787)
			(xy 86.653011 -466.084117) (xy 86.593837 -465.892927) (xy 86.54236 -465.699522) (xy 86.498662 -465.504213)
			(xy 86.462814 -465.307311) (xy 86.434872 -465.109133) (xy 86.414881 -464.909996) (xy 86.402874 -464.710218)
			(xy 86.39887 -464.51012) (xy 74.562208 -464.51012) (xy 74.562208 -464.780884) (xy 74.561773 -464.812731)
			(xy 74.553807 -464.875924) (xy 74.538011 -464.937628) (xy 74.514633 -464.996876) (xy 74.484038 -465.05274)
			(xy 74.446705 -465.104345) (xy 74.403219 -465.150884) (xy 74.354261 -465.191627) (xy 74.300598 -465.225936)
			(xy 74.24307 -465.253275) (xy 74.182579 -465.273214) (xy 74.12007 -465.285442) (xy 74.056523 -465.289768)
			(xy 73.992934 -465.286123) (xy 73.930298 -465.274564) (xy 73.869597 -465.255273) (xy 73.811779 -465.228552)
			(xy 73.757752 -465.194819) (xy 73.708361 -465.154602) (xy 73.66438 -465.108531) (xy 73.626497 -465.057328)
			(xy 73.61047 -465.029804) (xy 73.599156 -465.010488) (xy 73.57073 -464.975907) (xy 73.536683 -464.946845)
			(xy 73.498068 -464.924201) (xy 73.456082 -464.908677) (xy 73.412025 -464.900753) (xy 73.367261 -464.900674)
			(xy 73.323176 -464.908444) (xy 73.281136 -464.923822) (xy 73.242443 -464.94633) (xy 73.208294 -464.975274)
			(xy 73.193656 -464.992212) (xy 73.173353 -465.015827) (xy 73.128043 -465.05855) (xy 73.077853 -465.095418)
			(xy 73.023536 -465.125878) (xy 72.965903 -465.149474) (xy 72.90582 -465.165853) (xy 72.844186 -465.174768)
			(xy 72.781924 -465.176087) (xy 72.719968 -465.169789) (xy 72.659245 -465.15597) (xy 72.600665 -465.134836)
			(xy 72.545106 -465.106703) (xy 72.4934 -465.071993) (xy 72.446322 -465.031227) (xy 72.404577 -464.985015)
			(xy 72.36879 -464.934048) (xy 72.339498 -464.879092) (xy 72.317139 -464.820968) (xy 72.302049 -464.760549)
			(xy 72.294453 -464.698738) (xy 72.293988 -464.6676) (xy 71.884895 -464.6676) (xy 71.888234 -464.679782)
			(xy 71.898565 -464.75117) (xy 71.899272 -464.787234) (xy 71.899272 -465.980526) (xy 71.89877 -466.012487)
			(xy 71.890759 -466.075905) (xy 71.874862 -466.137819) (xy 71.85133 -466.197252) (xy 71.820536 -466.253267)
			(xy 71.782963 -466.304982) (xy 71.739206 -466.351579) (xy 71.689953 -466.392324) (xy 71.635982 -466.426575)
			(xy 71.578143 -466.453792) (xy 71.51735 -466.473545) (xy 71.45456 -466.485523) (xy 71.390764 -466.489537)
			(xy 71.326968 -466.485523) (xy 71.264178 -466.473545) (xy 71.203385 -466.453792) (xy 71.145546 -466.426575)
			(xy 71.091575 -466.392324) (xy 71.042322 -466.351579) (xy 70.998565 -466.304982) (xy 70.960992 -466.253267)
			(xy 70.930198 -466.197252) (xy 70.906666 -466.137819) (xy 70.890769 -466.075905) (xy 70.882758 -466.012487)
			(xy 70.882256 -465.980526) (xy 35.682508 -465.980526) (xy 35.755079 -465.994092) (xy 35.838661 -466.017873)
			(xy 35.919693 -466.049265) (xy 35.997482 -466.087999) (xy 36.071366 -466.133746) (xy 36.140713 -466.186115)
			(xy 36.204933 -466.244659) (xy 36.263477 -466.308879) (xy 36.315846 -466.378226) (xy 36.361593 -466.45211)
			(xy 36.400327 -466.529899) (xy 36.431719 -466.610931) (xy 36.4555 -466.694513) (xy 36.471468 -466.779933)
			(xy 36.479486 -466.866462) (xy 36.479988 -466.909912) (xy 36.479486 -466.953362) (xy 36.471468 -467.039891)
			(xy 36.4555 -467.125311) (xy 36.431719 -467.208893) (xy 36.400327 -467.289925) (xy 36.361593 -467.367714)
			(xy 36.315846 -467.441598) (xy 36.263477 -467.510945) (xy 36.204933 -467.575165) (xy 36.140713 -467.633709)
			(xy 36.071366 -467.686078) (xy 35.997482 -467.731825) (xy 35.919693 -467.770559) (xy 35.838661 -467.801951)
			(xy 35.755079 -467.825732) (xy 35.669659 -467.8417) (xy 35.58313 -467.849718) (xy 35.49623 -467.849718)
			(xy 35.409701 -467.8417) (xy 35.324281 -467.825732) (xy 35.240699 -467.801951) (xy 35.159667 -467.770559)
			(xy 35.081878 -467.731825) (xy 35.007994 -467.686078) (xy 34.938647 -467.633709) (xy 34.874427 -467.575165)
			(xy 34.815883 -467.510945) (xy 34.763514 -467.441598) (xy 34.717767 -467.367714) (xy 34.679033 -467.289925)
			(xy 34.647641 -467.208893) (xy 34.62386 -467.125311) (xy 34.607892 -467.039891) (xy 34.599874 -466.953362)
			(xy 31.399486 -466.953362) (xy 31.391468 -467.039891) (xy 31.3755 -467.125311) (xy 31.351719 -467.208893)
			(xy 31.320327 -467.289925) (xy 31.281593 -467.367714) (xy 31.235846 -467.441598) (xy 31.183477 -467.510945)
			(xy 31.124933 -467.575165) (xy 31.060713 -467.633709) (xy 30.991366 -467.686078) (xy 30.917482 -467.731825)
			(xy 30.839693 -467.770559) (xy 30.758661 -467.801951) (xy 30.675079 -467.825732) (xy 30.589659 -467.8417)
			(xy 30.50313 -467.849718) (xy 30.41623 -467.849718) (xy 30.329701 -467.8417) (xy 30.244281 -467.825732)
			(xy 30.160699 -467.801951) (xy 30.079667 -467.770559) (xy 30.001878 -467.731825) (xy 29.927994 -467.686078)
			(xy 29.858647 -467.633709) (xy 29.794427 -467.575165) (xy 29.735883 -467.510945) (xy 29.683514 -467.441598)
			(xy 29.637767 -467.367714) (xy 29.599033 -467.289925) (xy 29.567641 -467.208893) (xy 29.54386 -467.125311)
			(xy 29.527892 -467.039891) (xy 29.519874 -466.953362) (xy 20.901845 -466.953362) (xy 21.044512 -467.045438)
			(xy 21.251722 -467.188604) (xy 21.454325 -467.33822) (xy 21.652119 -467.494138) (xy 21.844909 -467.656203)
			(xy 22.032503 -467.824255) (xy 22.214715 -467.998127) (xy 22.391365 -468.177647) (xy 22.562279 -468.362638)
			(xy 22.727286 -468.552915) (xy 22.886224 -468.748291) (xy 23.038934 -468.948572) (xy 23.185266 -469.15356)
			(xy 23.325074 -469.363051) (xy 23.406232 -469.493362) (xy 29.519874 -469.493362) (xy 29.519874 -469.406462)
			(xy 29.527892 -469.319933) (xy 29.54386 -469.234513) (xy 29.567641 -469.150931) (xy 29.599033 -469.069899)
			(xy 29.637767 -468.99211) (xy 29.683514 -468.918226) (xy 29.735883 -468.848879) (xy 29.794427 -468.784659)
			(xy 29.858647 -468.726115) (xy 29.927994 -468.673746) (xy 30.001878 -468.627999) (xy 30.079667 -468.589265)
			(xy 30.160699 -468.557873) (xy 30.244281 -468.534092) (xy 30.329701 -468.518124) (xy 30.41623 -468.510106)
			(xy 30.50313 -468.510106) (xy 30.589659 -468.518124) (xy 30.675079 -468.534092) (xy 30.758661 -468.557873)
			(xy 30.839693 -468.589265) (xy 30.917482 -468.627999) (xy 30.991366 -468.673746) (xy 31.060713 -468.726115)
			(xy 31.124933 -468.784659) (xy 31.183477 -468.848879) (xy 31.235846 -468.918226) (xy 31.281593 -468.99211)
			(xy 31.320327 -469.069899) (xy 31.351719 -469.150931) (xy 31.3755 -469.234513) (xy 31.391468 -469.319933)
			(xy 31.399486 -469.406462) (xy 31.399988 -469.449912) (xy 31.399486 -469.493362) (xy 34.599874 -469.493362)
			(xy 34.599874 -469.406462) (xy 34.607892 -469.319933) (xy 34.62386 -469.234513) (xy 34.647641 -469.150931)
			(xy 34.679033 -469.069899) (xy 34.717767 -468.99211) (xy 34.763514 -468.918226) (xy 34.815883 -468.848879)
			(xy 34.874427 -468.784659) (xy 34.938647 -468.726115) (xy 35.007994 -468.673746) (xy 35.081878 -468.627999)
			(xy 35.159667 -468.589265) (xy 35.240699 -468.557873) (xy 35.324281 -468.534092) (xy 35.409701 -468.518124)
			(xy 35.49623 -468.510106) (xy 35.58313 -468.510106) (xy 35.669659 -468.518124) (xy 35.755079 -468.534092)
			(xy 35.838661 -468.557873) (xy 35.919693 -468.589265) (xy 35.997482 -468.627999) (xy 36.071366 -468.673746)
			(xy 36.140713 -468.726115) (xy 36.204933 -468.784659) (xy 36.263477 -468.848879) (xy 36.315846 -468.918226)
			(xy 36.361593 -468.99211) (xy 36.400327 -469.069899) (xy 36.431719 -469.150931) (xy 36.4555 -469.234513)
			(xy 36.471468 -469.319933) (xy 36.479486 -469.406462) (xy 36.479988 -469.449912) (xy 36.479486 -469.493362)
			(xy 36.471468 -469.579891) (xy 36.4555 -469.665311) (xy 36.431719 -469.748893) (xy 36.400327 -469.829925)
			(xy 36.361593 -469.907714) (xy 36.315846 -469.981598) (xy 36.263477 -470.050945) (xy 36.204933 -470.115165)
			(xy 36.140713 -470.173709) (xy 36.071366 -470.226078) (xy 35.997482 -470.271825) (xy 35.919693 -470.310559)
			(xy 35.838661 -470.341951) (xy 35.755079 -470.365732) (xy 35.669659 -470.3817) (xy 35.58313 -470.389718)
			(xy 35.49623 -470.389718) (xy 35.409701 -470.3817) (xy 35.324281 -470.365732) (xy 35.240699 -470.341951)
			(xy 35.159667 -470.310559) (xy 35.081878 -470.271825) (xy 35.007994 -470.226078) (xy 34.938647 -470.173709)
			(xy 34.874427 -470.115165) (xy 34.815883 -470.050945) (xy 34.763514 -469.981598) (xy 34.717767 -469.907714)
			(xy 34.679033 -469.829925) (xy 34.647641 -469.748893) (xy 34.62386 -469.665311) (xy 34.607892 -469.579891)
			(xy 34.599874 -469.493362) (xy 31.399486 -469.493362) (xy 31.391468 -469.579891) (xy 31.3755 -469.665311)
			(xy 31.351719 -469.748893) (xy 31.320327 -469.829925) (xy 31.281593 -469.907714) (xy 31.235846 -469.981598)
			(xy 31.183477 -470.050945) (xy 31.124933 -470.115165) (xy 31.060713 -470.173709) (xy 30.991366 -470.226078)
			(xy 30.917482 -470.271825) (xy 30.839693 -470.310559) (xy 30.758661 -470.341951) (xy 30.675079 -470.365732)
			(xy 30.589659 -470.3817) (xy 30.50313 -470.389718) (xy 30.41623 -470.389718) (xy 30.329701 -470.3817)
			(xy 30.244281 -470.365732) (xy 30.160699 -470.341951) (xy 30.079667 -470.310559) (xy 30.001878 -470.271825)
			(xy 29.927994 -470.226078) (xy 29.858647 -470.173709) (xy 29.794427 -470.115165) (xy 29.735883 -470.050945)
			(xy 29.683514 -469.981598) (xy 29.637767 -469.907714) (xy 29.599033 -469.829925) (xy 29.567641 -469.748893)
			(xy 29.54386 -469.665311) (xy 29.527892 -469.579891) (xy 29.519874 -469.493362) (xy 23.406232 -469.493362)
			(xy 23.458221 -469.576838) (xy 23.584574 -469.794709) (xy 23.704008 -470.016448) (xy 23.816405 -470.241836)
			(xy 23.921653 -470.47065) (xy 24.019648 -470.702663) (xy 24.110294 -470.937644) (xy 24.1935 -471.175362)
			(xy 24.269183 -471.41558) (xy 24.33727 -471.658061) (xy 24.397692 -471.902565) (xy 24.425678 -472.033362)
			(xy 29.519874 -472.033362) (xy 29.519874 -471.946462) (xy 29.527892 -471.859933) (xy 29.54386 -471.774513)
			(xy 29.567641 -471.690931) (xy 29.599033 -471.609899) (xy 29.637767 -471.53211) (xy 29.683514 -471.458226)
			(xy 29.735883 -471.388879) (xy 29.794427 -471.324659) (xy 29.858647 -471.266115) (xy 29.927994 -471.213746)
			(xy 30.001878 -471.167999) (xy 30.079667 -471.129265) (xy 30.160699 -471.097873) (xy 30.244281 -471.074092)
			(xy 30.329701 -471.058124) (xy 30.41623 -471.050106) (xy 30.50313 -471.050106) (xy 30.589659 -471.058124)
			(xy 30.675079 -471.074092) (xy 30.758661 -471.097873) (xy 30.839693 -471.129265) (xy 30.917482 -471.167999)
			(xy 30.991366 -471.213746) (xy 31.060713 -471.266115) (xy 31.124933 -471.324659) (xy 31.183477 -471.388879)
			(xy 31.235846 -471.458226) (xy 31.281593 -471.53211) (xy 31.320327 -471.609899) (xy 31.351719 -471.690931)
			(xy 31.3755 -471.774513) (xy 31.391468 -471.859933) (xy 31.399486 -471.946462) (xy 31.399988 -471.989912)
			(xy 31.399486 -472.033362) (xy 34.599874 -472.033362) (xy 34.599874 -471.946462) (xy 34.607892 -471.859933)
			(xy 34.62386 -471.774513) (xy 34.647641 -471.690931) (xy 34.679033 -471.609899) (xy 34.717767 -471.53211)
			(xy 34.763514 -471.458226) (xy 34.815883 -471.388879) (xy 34.874427 -471.324659) (xy 34.938647 -471.266115)
			(xy 35.007994 -471.213746) (xy 35.081878 -471.167999) (xy 35.159667 -471.129265) (xy 35.240699 -471.097873)
			(xy 35.324281 -471.074092) (xy 35.409701 -471.058124) (xy 35.49623 -471.050106) (xy 35.58313 -471.050106)
			(xy 35.669659 -471.058124) (xy 35.755079 -471.074092) (xy 35.838661 -471.097873) (xy 35.919693 -471.129265)
			(xy 35.997482 -471.167999) (xy 36.071366 -471.213746) (xy 36.140713 -471.266115) (xy 36.204933 -471.324659)
			(xy 36.263477 -471.388879) (xy 36.315846 -471.458226) (xy 36.361593 -471.53211) (xy 36.400327 -471.609899)
			(xy 36.431719 -471.690931) (xy 36.4555 -471.774513) (xy 36.471468 -471.859933) (xy 36.479486 -471.946462)
			(xy 36.479988 -471.989912) (xy 36.479486 -472.033362) (xy 36.471468 -472.119891) (xy 36.468956 -472.133331)
			(xy 70.698381 -472.133331) (xy 70.698381 -472.070069) (xy 70.706638 -472.007349) (xy 70.72301 -471.946242)
			(xy 70.747218 -471.887796) (xy 70.778848 -471.833008) (xy 70.817357 -471.782818) (xy 70.862088 -471.738084)
			(xy 70.912275 -471.69957) (xy 70.96706 -471.667936) (xy 71.025504 -471.643723) (xy 71.086609 -471.627346)
			(xy 71.149329 -471.619084) (xy 71.18096 -471.618564) (xy 72.553576 -471.618564) (xy 72.581843 -471.61901)
			(xy 72.637986 -471.625657) (xy 72.692971 -471.638805) (xy 72.746048 -471.658274) (xy 72.796492 -471.683799)
			(xy 72.820276 -471.699082) (xy 72.85228 -471.720164) (xy 73.015094 -471.720164) (xy 73.048876 -471.694764)
			(xy 73.075345 -471.675556) (xy 73.132284 -471.64338) (xy 73.192874 -471.618762) (xy 73.256119 -471.602107)
			(xy 73.320976 -471.593689) (xy 73.353676 -471.593164) (xy 74.575924 -471.593164) (xy 74.607882 -471.593723)
			(xy 74.671295 -471.601737) (xy 74.733203 -471.617635) (xy 74.79263 -471.641166) (xy 74.848639 -471.67196)
			(xy 74.900348 -471.709531) (xy 74.94694 -471.753286) (xy 74.987681 -471.802535) (xy 75.021928 -471.856503)
			(xy 75.049142 -471.914336) (xy 75.068893 -471.975125) (xy 75.080869 -472.037909) (xy 75.084883 -472.1017)
			(xy 75.080869 -472.165491) (xy 75.068893 -472.228275) (xy 75.049142 -472.289064) (xy 75.021928 -472.346897)
			(xy 74.987681 -472.400865) (xy 74.94694 -472.450114) (xy 74.900348 -472.493869) (xy 74.848639 -472.53144)
			(xy 74.79263 -472.562234) (xy 74.733203 -472.585765) (xy 74.671295 -472.601663) (xy 74.607882 -472.609677)
			(xy 74.575924 -472.61018) (xy 73.353676 -472.61018) (xy 73.320974 -472.609669) (xy 73.256111 -472.601273)
			(xy 73.192861 -472.584623) (xy 73.132272 -472.559994) (xy 73.075343 -472.527794) (xy 73.048876 -472.50858)
			(xy 73.015094 -472.48318) (xy 72.85228 -472.48318) (xy 72.820276 -472.504262) (xy 72.796496 -472.519554)
			(xy 72.746061 -472.545108) (xy 72.692984 -472.564591) (xy 72.637995 -472.577737) (xy 72.581845 -472.584366)
			(xy 72.553576 -472.58478) (xy 71.18096 -472.58478) (xy 71.149329 -472.584316) (xy 71.086609 -472.576054)
			(xy 71.025504 -472.559677) (xy 70.96706 -472.535464) (xy 70.912275 -472.50383) (xy 70.862088 -472.465316)
			(xy 70.817357 -472.420582) (xy 70.778848 -472.370392) (xy 70.747218 -472.315604) (xy 70.72301 -472.257158)
			(xy 70.706638 -472.196051) (xy 70.698381 -472.133331) (xy 36.468956 -472.133331) (xy 36.4555 -472.205311)
			(xy 36.431719 -472.288893) (xy 36.400327 -472.369925) (xy 36.361593 -472.447714) (xy 36.315846 -472.521598)
			(xy 36.263477 -472.590945) (xy 36.204933 -472.655165) (xy 36.140713 -472.713709) (xy 36.071366 -472.766078)
			(xy 35.997482 -472.811825) (xy 35.919693 -472.850559) (xy 35.838661 -472.881951) (xy 35.755079 -472.905732)
			(xy 35.669659 -472.9217) (xy 35.58313 -472.929718) (xy 35.49623 -472.929718) (xy 35.409701 -472.9217)
			(xy 35.324281 -472.905732) (xy 35.240699 -472.881951) (xy 35.159667 -472.850559) (xy 35.081878 -472.811825)
			(xy 35.007994 -472.766078) (xy 34.938647 -472.713709) (xy 34.874427 -472.655165) (xy 34.815883 -472.590945)
			(xy 34.763514 -472.521598) (xy 34.717767 -472.447714) (xy 34.679033 -472.369925) (xy 34.647641 -472.288893)
			(xy 34.62386 -472.205311) (xy 34.607892 -472.119891) (xy 34.599874 -472.033362) (xy 31.399486 -472.033362)
			(xy 31.391468 -472.119891) (xy 31.3755 -472.205311) (xy 31.351719 -472.288893) (xy 31.320327 -472.369925)
			(xy 31.281593 -472.447714) (xy 31.235846 -472.521598) (xy 31.183477 -472.590945) (xy 31.124933 -472.655165)
			(xy 31.060713 -472.713709) (xy 30.991366 -472.766078) (xy 30.917482 -472.811825) (xy 30.839693 -472.850559)
			(xy 30.758661 -472.881951) (xy 30.675079 -472.905732) (xy 30.589659 -472.9217) (xy 30.50313 -472.929718)
			(xy 30.41623 -472.929718) (xy 30.329701 -472.9217) (xy 30.244281 -472.905732) (xy 30.160699 -472.881951)
			(xy 30.079667 -472.850559) (xy 30.001878 -472.811825) (xy 29.927994 -472.766078) (xy 29.858647 -472.713709)
			(xy 29.794427 -472.655165) (xy 29.735883 -472.590945) (xy 29.683514 -472.521598) (xy 29.637767 -472.447714)
			(xy 29.599033 -472.369925) (xy 29.567641 -472.288893) (xy 29.54386 -472.205311) (xy 29.527892 -472.119891)
			(xy 29.519874 -472.033362) (xy 24.425678 -472.033362) (xy 24.450389 -472.148849) (xy 24.49531 -472.39667)
			(xy 24.53241 -472.645781) (xy 24.561652 -472.895936) (xy 24.583008 -473.146888) (xy 24.596455 -473.398388)
			(xy 24.601981 -473.650186) (xy 24.59958 -473.902034) (xy 24.589255 -474.153681) (xy 24.571016 -474.404878)
			(xy 24.553438 -474.573362) (xy 29.519874 -474.573362) (xy 29.519874 -474.486462) (xy 29.527892 -474.399933)
			(xy 29.54386 -474.314513) (xy 29.567641 -474.230931) (xy 29.599033 -474.149899) (xy 29.637767 -474.07211)
			(xy 29.683514 -473.998226) (xy 29.735883 -473.928879) (xy 29.794427 -473.864659) (xy 29.858647 -473.806115)
			(xy 29.927994 -473.753746) (xy 30.001878 -473.707999) (xy 30.079667 -473.669265) (xy 30.160699 -473.637873)
			(xy 30.244281 -473.614092) (xy 30.329701 -473.598124) (xy 30.41623 -473.590106) (xy 30.50313 -473.590106)
			(xy 30.589659 -473.598124) (xy 30.675079 -473.614092) (xy 30.758661 -473.637873) (xy 30.839693 -473.669265)
			(xy 30.917482 -473.707999) (xy 30.991366 -473.753746) (xy 31.060713 -473.806115) (xy 31.124933 -473.864659)
			(xy 31.183477 -473.928879) (xy 31.235846 -473.998226) (xy 31.281593 -474.07211) (xy 31.320327 -474.149899)
			(xy 31.351719 -474.230931) (xy 31.3755 -474.314513) (xy 31.391468 -474.399933) (xy 31.399486 -474.486462)
			(xy 31.399988 -474.529912) (xy 31.399486 -474.573362) (xy 34.599874 -474.573362) (xy 34.599874 -474.486462)
			(xy 34.607892 -474.399933) (xy 34.62386 -474.314513) (xy 34.647641 -474.230931) (xy 34.679033 -474.149899)
			(xy 34.717767 -474.07211) (xy 34.763514 -473.998226) (xy 34.815883 -473.928879) (xy 34.874427 -473.864659)
			(xy 34.938647 -473.806115) (xy 35.007994 -473.753746) (xy 35.081878 -473.707999) (xy 35.159667 -473.669265)
			(xy 35.240699 -473.637873) (xy 35.324281 -473.614092) (xy 35.409701 -473.598124) (xy 35.49623 -473.590106)
			(xy 35.58313 -473.590106) (xy 35.669659 -473.598124) (xy 35.755079 -473.614092) (xy 35.838661 -473.637873)
			(xy 35.919693 -473.669265) (xy 35.997482 -473.707999) (xy 36.071366 -473.753746) (xy 36.140713 -473.806115)
			(xy 36.204933 -473.864659) (xy 36.263477 -473.928879) (xy 36.290621 -473.964823) (xy 38.249145 -473.964823)
			(xy 38.25303 -473.910461) (xy 38.264612 -473.857206) (xy 38.283656 -473.806142) (xy 38.309773 -473.758308)
			(xy 38.342433 -473.714677) (xy 38.38097 -473.676139) (xy 38.424599 -473.643479) (xy 38.472433 -473.61736)
			(xy 38.523497 -473.598315) (xy 38.576752 -473.586731) (xy 38.631113 -473.582845) (xy 38.685474 -473.586735)
			(xy 38.738728 -473.598322) (xy 38.789791 -473.617371) (xy 38.837623 -473.643493) (xy 38.859714 -473.659454)
			(xy 38.878726 -473.67305) (xy 38.920609 -473.693782) (xy 38.965577 -473.706508) (xy 39.012114 -473.710798)
			(xy 39.058651 -473.706508) (xy 39.103619 -473.693782) (xy 39.145502 -473.67305) (xy 39.164514 -473.659454)
			(xy 39.186637 -473.643546) (xy 39.23446 -473.617433) (xy 39.285512 -473.598391) (xy 39.338754 -473.586809)
			(xy 39.393103 -473.582922) (xy 39.447451 -473.58681) (xy 39.500694 -473.598393) (xy 39.551745 -473.617435)
			(xy 39.599567 -473.643549) (xy 39.643186 -473.676204) (xy 39.681713 -473.714734) (xy 39.714364 -473.758354)
			(xy 39.740475 -473.806178) (xy 39.759514 -473.857231) (xy 39.771094 -473.910474) (xy 39.774978 -473.964823)
			(xy 40.135837 -473.964823) (xy 40.139723 -473.91046) (xy 40.151305 -473.857203) (xy 40.17035 -473.806137)
			(xy 40.196469 -473.758302) (xy 40.22913 -473.71467) (xy 40.267668 -473.676132) (xy 40.311299 -473.64347)
			(xy 40.359135 -473.617351) (xy 40.4102 -473.598306) (xy 40.463457 -473.586723) (xy 40.51782 -473.582837)
			(xy 40.572183 -473.586729) (xy 40.625438 -473.598317) (xy 40.676502 -473.617368) (xy 40.724334 -473.643492)
			(xy 40.746426 -473.659454) (xy 40.765438 -473.67305) (xy 40.807321 -473.693782) (xy 40.852289 -473.706508)
			(xy 40.898826 -473.710798) (xy 40.945363 -473.706508) (xy 40.990331 -473.693782) (xy 41.032214 -473.67305)
			(xy 41.051226 -473.659454) (xy 41.073349 -473.643548) (xy 41.121171 -473.617436) (xy 41.172221 -473.598396)
			(xy 41.225462 -473.586815) (xy 41.27981 -473.582929) (xy 41.334156 -473.586818) (xy 41.387397 -473.598401)
			(xy 41.438447 -473.617444) (xy 41.463481 -473.631115) (xy 70.63155 -473.631115) (xy 70.63155 -473.567885)
			(xy 70.639804 -473.505196) (xy 70.656169 -473.44412) (xy 70.680366 -473.385703) (xy 70.711981 -473.330945)
			(xy 70.750474 -473.280781) (xy 70.795184 -473.236071) (xy 70.845348 -473.197579) (xy 70.900107 -473.165964)
			(xy 70.958524 -473.141768) (xy 71.0196 -473.125403) (xy 71.082289 -473.11715) (xy 71.113904 -473.116656)
			(xy 72.532748 -473.116656) (xy 72.561036 -473.117031) (xy 72.617231 -473.123587) (xy 72.672273 -473.136673)
			(xy 72.725405 -473.15611) (xy 72.775898 -473.181631) (xy 72.799702 -473.19692) (xy 72.831452 -473.218256)
			(xy 72.888856 -473.218256) (xy 72.888856 -473.27312) (xy 72.908721 -473.295438) (xy 72.943348 -473.34413)
			(xy 72.971706 -473.396721) (xy 72.993362 -473.452407) (xy 73.007985 -473.510339) (xy 73.015353 -473.569633)
			(xy 73.015352 -473.629382) (xy 73.007982 -473.688675) (xy 72.993357 -473.746607) (xy 72.9717 -473.802293)
			(xy 72.94334 -473.854883) (xy 72.908712 -473.903574) (xy 72.888856 -473.9259) (xy 72.888856 -473.980764)
			(xy 72.831452 -473.980764) (xy 72.799702 -474.0021) (xy 72.775889 -474.017371) (xy 72.725388 -474.042866)
			(xy 72.672257 -474.062293) (xy 72.617221 -474.075388) (xy 72.561034 -474.081971) (xy 72.532748 -474.082364)
			(xy 71.113904 -474.082364) (xy 71.082289 -474.08185) (xy 71.0196 -474.073597) (xy 70.958524 -474.057232)
			(xy 70.900107 -474.033036) (xy 70.845348 -474.001421) (xy 70.795184 -473.962929) (xy 70.750474 -473.918219)
			(xy 70.711981 -473.868055) (xy 70.680366 -473.813297) (xy 70.656169 -473.75488) (xy 70.639804 -473.693804)
			(xy 70.63155 -473.631115) (xy 41.463481 -473.631115) (xy 41.486267 -473.643558) (xy 41.529884 -473.676212)
			(xy 41.568409 -473.714741) (xy 41.60106 -473.75836) (xy 41.62717 -473.806183) (xy 41.646208 -473.857234)
			(xy 41.657787 -473.910476) (xy 41.661671 -473.964823) (xy 41.65778 -474.01917) (xy 41.646195 -474.07241)
			(xy 41.627151 -474.123459) (xy 41.601035 -474.171278) (xy 41.56838 -474.214894) (xy 41.529849 -474.253418)
			(xy 41.486229 -474.286067) (xy 41.438405 -474.312175) (xy 41.387353 -474.331212) (xy 41.334111 -474.342789)
			(xy 41.279764 -474.346671) (xy 41.225417 -474.342778) (xy 41.172178 -474.331191) (xy 41.121129 -474.312145)
			(xy 41.073311 -474.286028) (xy 41.051226 -474.27007) (xy 41.032214 -474.256474) (xy 40.990331 -474.235742)
			(xy 40.945363 -474.223016) (xy 40.898826 -474.218726) (xy 40.852289 -474.223016) (xy 40.807321 -474.235742)
			(xy 40.765438 -474.256474) (xy 40.746426 -474.27007) (xy 40.724373 -474.286083) (xy 40.676543 -474.312213)
			(xy 40.625482 -474.33127) (xy 40.572228 -474.342865) (xy 40.517866 -474.346763) (xy 40.463502 -474.342883)
			(xy 40.410244 -474.331307) (xy 40.359176 -474.312268) (xy 40.311338 -474.286154) (xy 40.267703 -474.253498)
			(xy 40.22916 -474.214964) (xy 40.196493 -474.171337) (xy 40.170369 -474.123504) (xy 40.151318 -474.072441)
			(xy 40.139729 -474.019185) (xy 40.135837 -473.964823) (xy 39.774978 -473.964823) (xy 39.771087 -474.019171)
			(xy 39.759502 -474.072413) (xy 39.740456 -474.123463) (xy 39.71434 -474.171284) (xy 39.681683 -474.214901)
			(xy 39.643151 -474.253426) (xy 39.599529 -474.286075) (xy 39.551704 -474.312184) (xy 39.50065 -474.33122)
			(xy 39.447406 -474.342797) (xy 39.393057 -474.346678) (xy 39.338709 -474.342784) (xy 39.285468 -474.331196)
			(xy 39.234418 -474.312148) (xy 39.186599 -474.286029) (xy 39.164514 -474.27007) (xy 39.145502 -474.256474)
			(xy 39.103619 -474.235742) (xy 39.058651 -474.223016) (xy 39.012114 -474.218726) (xy 38.965577 -474.223016)
			(xy 38.920609 -474.235742) (xy 38.878726 -474.256474) (xy 38.859714 -474.27007) (xy 38.837661 -474.286082)
			(xy 38.789832 -474.31221) (xy 38.738772 -474.331265) (xy 38.685519 -474.342859) (xy 38.631159 -474.346755)
			(xy 38.576797 -474.342875) (xy 38.523541 -474.331298) (xy 38.472475 -474.312259) (xy 38.424638 -474.286146)
			(xy 38.381005 -474.25349) (xy 38.342463 -474.214957) (xy 38.309798 -474.171331) (xy 38.283675 -474.1235)
			(xy 38.264625 -474.072437) (xy 38.253036 -474.019184) (xy 38.249145 -473.964823) (xy 36.290621 -473.964823)
			(xy 36.315846 -473.998226) (xy 36.361593 -474.07211) (xy 36.400327 -474.149899) (xy 36.431719 -474.230931)
			(xy 36.4555 -474.314513) (xy 36.471468 -474.399933) (xy 36.479486 -474.486462) (xy 36.479988 -474.529912)
			(xy 36.479486 -474.573362) (xy 36.471468 -474.659891) (xy 36.4555 -474.745311) (xy 36.431719 -474.828893)
			(xy 36.400327 -474.909925) (xy 36.361593 -474.987714) (xy 36.315846 -475.061598) (xy 36.263477 -475.130945)
			(xy 36.204933 -475.195165) (xy 36.140713 -475.253709) (xy 36.071366 -475.306078) (xy 35.997482 -475.351825)
			(xy 35.919693 -475.390559) (xy 35.838661 -475.421951) (xy 35.755079 -475.445732) (xy 35.669659 -475.4617)
			(xy 35.58313 -475.469718) (xy 35.49623 -475.469718) (xy 35.409701 -475.4617) (xy 35.324281 -475.445732)
			(xy 35.240699 -475.421951) (xy 35.159667 -475.390559) (xy 35.081878 -475.351825) (xy 35.007994 -475.306078)
			(xy 34.938647 -475.253709) (xy 34.874427 -475.195165) (xy 34.815883 -475.130945) (xy 34.763514 -475.061598)
			(xy 34.717767 -474.987714) (xy 34.679033 -474.909925) (xy 34.647641 -474.828893) (xy 34.62386 -474.745311)
			(xy 34.607892 -474.659891) (xy 34.599874 -474.573362) (xy 31.399486 -474.573362) (xy 31.391468 -474.659891)
			(xy 31.3755 -474.745311) (xy 31.351719 -474.828893) (xy 31.320327 -474.909925) (xy 31.281593 -474.987714)
			(xy 31.235846 -475.061598) (xy 31.183477 -475.130945) (xy 31.124933 -475.195165) (xy 31.060713 -475.253709)
			(xy 30.991366 -475.306078) (xy 30.917482 -475.351825) (xy 30.839693 -475.390559) (xy 30.758661 -475.421951)
			(xy 30.675079 -475.445732) (xy 30.589659 -475.4617) (xy 30.50313 -475.469718) (xy 30.41623 -475.469718)
			(xy 30.329701 -475.4617) (xy 30.244281 -475.445732) (xy 30.160699 -475.421951) (xy 30.079667 -475.390559)
			(xy 30.001878 -475.351825) (xy 29.927994 -475.306078) (xy 29.858647 -475.253709) (xy 29.794427 -475.195165)
			(xy 29.735883 -475.130945) (xy 29.683514 -475.061598) (xy 29.637767 -474.987714) (xy 29.599033 -474.909925)
			(xy 29.567641 -474.828893) (xy 29.54386 -474.745311) (xy 29.527892 -474.659891) (xy 29.519874 -474.573362)
			(xy 24.553438 -474.573362) (xy 24.544881 -474.655377) (xy 24.510875 -474.90493) (xy 24.469033 -475.153289)
			(xy 24.419396 -475.400208) (xy 24.362013 -475.645443) (xy 24.321103 -475.798407) (xy 38.249165 -475.798407)
			(xy 38.253052 -475.744049) (xy 38.264636 -475.690797) (xy 38.283681 -475.639736) (xy 38.309799 -475.591906)
			(xy 38.342459 -475.548279) (xy 38.380995 -475.509745) (xy 38.424624 -475.477088) (xy 38.472456 -475.450972)
			(xy 38.523518 -475.43193) (xy 38.57677 -475.420349) (xy 38.631129 -475.416465) (xy 38.685487 -475.420358)
			(xy 38.738737 -475.431946) (xy 38.789796 -475.450996) (xy 38.837625 -475.477119) (xy 38.859714 -475.49308)
			(xy 38.878726 -475.506676) (xy 38.920609 -475.527408) (xy 38.965577 -475.540134) (xy 39.012114 -475.544424)
			(xy 39.058651 -475.540134) (xy 39.103619 -475.527408) (xy 39.145502 -475.506676) (xy 39.164514 -475.49308)
			(xy 39.186613 -475.477137) (xy 39.234437 -475.451021) (xy 39.285491 -475.431976) (xy 39.338736 -475.420391)
			(xy 39.393087 -475.416501) (xy 39.447439 -475.420387) (xy 39.500684 -475.431968) (xy 39.55174 -475.45101)
			(xy 39.599565 -475.477124) (xy 39.643188 -475.509778) (xy 39.681718 -475.548308) (xy 39.714373 -475.59193)
			(xy 39.740488 -475.639755) (xy 39.75953 -475.69081) (xy 39.771112 -475.744055) (xy 39.774999 -475.798407)
			(xy 40.135858 -475.798407) (xy 40.139745 -475.744047) (xy 40.15133 -475.690794) (xy 40.170375 -475.639732)
			(xy 40.196495 -475.5919) (xy 40.229156 -475.548272) (xy 40.267694 -475.509737) (xy 40.311324 -475.477079)
			(xy 40.359157 -475.450964) (xy 40.410221 -475.431922) (xy 40.463475 -475.420341) (xy 40.517836 -475.416458)
			(xy 40.572195 -475.420352) (xy 40.625447 -475.431942) (xy 40.676507 -475.450993) (xy 40.724336 -475.477118)
			(xy 40.746426 -475.49308) (xy 40.765438 -475.506676) (xy 40.807321 -475.527408) (xy 40.852289 -475.540134)
			(xy 40.898826 -475.544424) (xy 40.945363 -475.540134) (xy 40.990331 -475.527408) (xy 41.032214 -475.506676)
			(xy 41.051226 -475.49308) (xy 41.073325 -475.477138) (xy 41.121148 -475.451023) (xy 41.172201 -475.43198)
			(xy 41.225444 -475.420397) (xy 41.279794 -475.416509) (xy 41.334144 -475.420395) (xy 41.387388 -475.431977)
			(xy 41.438441 -475.451018) (xy 41.486265 -475.477132) (xy 41.529886 -475.509786) (xy 41.568415 -475.548315)
			(xy 41.601069 -475.591936) (xy 41.627182 -475.63976) (xy 41.646223 -475.690813) (xy 41.657805 -475.744057)
			(xy 41.661691 -475.798407) (xy 42.376993 -475.798407) (xy 42.380879 -475.744055) (xy 42.392461 -475.69081)
			(xy 42.411503 -475.639754) (xy 42.437617 -475.591929) (xy 42.470272 -475.548306) (xy 42.508803 -475.509775)
			(xy 42.552425 -475.47712) (xy 42.60025 -475.451005) (xy 42.651305 -475.431963) (xy 42.704551 -475.42038)
			(xy 42.758903 -475.416493) (xy 42.813255 -475.420381) (xy 42.8665 -475.431964) (xy 42.917555 -475.451007)
			(xy 42.96538 -475.477123) (xy 42.987468 -475.49308) (xy 43.00648 -475.506676) (xy 43.048363 -475.527408)
			(xy 43.093331 -475.540134) (xy 43.139868 -475.544424) (xy 43.186405 -475.540134) (xy 43.231373 -475.527408)
			(xy 43.273256 -475.506676) (xy 43.292268 -475.49308) (xy 43.314368 -475.477134) (xy 43.362195 -475.451009)
			(xy 43.413253 -475.431958) (xy 43.466503 -475.420368) (xy 43.520861 -475.416474) (xy 43.575219 -475.420356)
			(xy 43.628472 -475.431936) (xy 43.679534 -475.450977) (xy 43.727366 -475.477091) (xy 43.770995 -475.509748)
			(xy 43.809531 -475.548281) (xy 43.842191 -475.591907) (xy 43.86831 -475.639737) (xy 43.887355 -475.690798)
			(xy 43.898939 -475.744049) (xy 43.902826 -475.798407) (xy 44.281003 -475.798407) (xy 44.284889 -475.744057)
			(xy 44.29647 -475.690814) (xy 44.315511 -475.63976) (xy 44.341624 -475.591937) (xy 44.374277 -475.548316)
			(xy 44.412805 -475.509786) (xy 44.456425 -475.477131) (xy 44.504248 -475.451017) (xy 44.555301 -475.431974)
			(xy 44.608544 -475.420391) (xy 44.662894 -475.416503) (xy 44.717243 -475.420389) (xy 44.770487 -475.43197)
			(xy 44.82154 -475.451011) (xy 44.869364 -475.477124) (xy 44.891452 -475.49308) (xy 44.910464 -475.506676)
			(xy 44.952347 -475.527408) (xy 44.997315 -475.540134) (xy 45.043852 -475.544424) (xy 45.090389 -475.540134)
			(xy 45.135357 -475.527408) (xy 45.17724 -475.506676) (xy 45.196252 -475.49308) (xy 45.218353 -475.477132)
			(xy 45.266181 -475.451005) (xy 45.31724 -475.431952) (xy 45.370492 -475.420359) (xy 45.424852 -475.416464)
			(xy 45.479212 -475.420346) (xy 45.532467 -475.431925) (xy 45.583532 -475.450965) (xy 45.631366 -475.47708)
			(xy 45.674997 -475.509737) (xy 45.713536 -475.548272) (xy 45.746198 -475.591899) (xy 45.772318 -475.639731)
			(xy 45.791364 -475.690794) (xy 45.802948 -475.744047) (xy 45.806836 -475.798407) (xy 45.802946 -475.852767)
			(xy 45.79136 -475.90602) (xy 45.772312 -475.957082) (xy 45.74619 -476.004913) (xy 45.713527 -476.048539)
			(xy 45.674986 -476.087072) (xy 45.631354 -476.119728) (xy 45.583519 -476.145841) (xy 45.532453 -476.164879)
			(xy 45.479198 -476.176456) (xy 45.424837 -476.180336) (xy 45.370478 -476.176439) (xy 45.317227 -476.164844)
			(xy 45.266168 -476.145789) (xy 45.21834 -476.11966) (xy 45.196252 -476.103696) (xy 45.17724 -476.0901)
			(xy 45.135357 -476.069368) (xy 45.090389 -476.056642) (xy 45.043852 -476.052352) (xy 44.997315 -476.056642)
			(xy 44.952347 -476.069368) (xy 44.910464 -476.0901) (xy 44.891452 -476.103696) (xy 44.869376 -476.119668)
			(xy 44.821553 -476.145783) (xy 44.770501 -476.164826) (xy 44.717258 -476.176409) (xy 44.662908 -476.180297)
			(xy 44.608558 -476.176411) (xy 44.555315 -476.16483) (xy 44.504261 -476.145789) (xy 44.456437 -476.119677)
			(xy 44.412816 -476.087024) (xy 44.374286 -476.048495) (xy 44.341632 -476.004876) (xy 44.315517 -475.957053)
			(xy 44.296474 -475.906) (xy 44.284891 -475.852757) (xy 44.281003 -475.798407) (xy 43.902826 -475.798407)
			(xy 43.898937 -475.852765) (xy 43.887351 -475.906016) (xy 43.868304 -475.957076) (xy 43.842184 -476.004905)
			(xy 43.809522 -476.04853) (xy 43.770984 -476.087062) (xy 43.727354 -476.119716) (xy 43.679521 -476.145829)
			(xy 43.628458 -476.164868) (xy 43.575205 -476.176446) (xy 43.520847 -476.180326) (xy 43.466489 -476.17643)
			(xy 43.41324 -476.164838) (xy 43.362182 -476.145785) (xy 43.314356 -476.119659) (xy 43.292268 -476.103696)
			(xy 43.273256 -476.0901) (xy 43.231373 -476.069368) (xy 43.186405 -476.056642) (xy 43.139868 -476.052352)
			(xy 43.093331 -476.056642) (xy 43.048363 -476.069368) (xy 43.00648 -476.0901) (xy 42.987468 -476.103696)
			(xy 42.965392 -476.119669) (xy 42.917568 -476.145787) (xy 42.866514 -476.164832) (xy 42.813269 -476.176417)
			(xy 42.758917 -476.180307) (xy 42.704565 -476.176422) (xy 42.651319 -476.164841) (xy 42.600263 -476.145801)
			(xy 42.552437 -476.119688) (xy 42.508814 -476.087034) (xy 42.470282 -476.048505) (xy 42.437625 -476.004884)
			(xy 42.411509 -475.957059) (xy 42.392465 -475.906004) (xy 42.380881 -475.852759) (xy 42.376993 -475.798407)
			(xy 41.661691 -475.798407) (xy 41.657803 -475.852757) (xy 41.646219 -475.906) (xy 41.627176 -475.957053)
			(xy 41.601061 -476.004876) (xy 41.568406 -476.048496) (xy 41.529875 -476.087024) (xy 41.486253 -476.119676)
			(xy 41.438428 -476.145788) (xy 41.387374 -476.164827) (xy 41.33413 -476.176407) (xy 41.27978 -476.180291)
			(xy 41.22543 -476.176401) (xy 41.172187 -476.164816) (xy 41.121135 -476.145771) (xy 41.073313 -476.119654)
			(xy 41.051226 -476.103696) (xy 41.032214 -476.0901) (xy 40.990331 -476.069368) (xy 40.945363 -476.056642)
			(xy 40.898826 -476.052352) (xy 40.852289 -476.056642) (xy 40.807321 -476.069368) (xy 40.765438 -476.0901)
			(xy 40.746426 -476.103696) (xy 40.724348 -476.119674) (xy 40.67652 -476.145801) (xy 40.625461 -476.164854)
			(xy 40.572209 -476.176446) (xy 40.51785 -476.180342) (xy 40.46349 -476.176461) (xy 40.410235 -476.164882)
			(xy 40.359171 -476.145842) (xy 40.311336 -476.119728) (xy 40.267704 -476.087072) (xy 40.229165 -476.048539)
			(xy 40.196503 -476.004912) (xy 40.170381 -475.957081) (xy 40.151334 -475.90602) (xy 40.139747 -475.852767)
			(xy 40.135858 -475.798407) (xy 39.774999 -475.798407) (xy 39.77111 -475.852759) (xy 39.759526 -475.906004)
			(xy 39.740482 -475.957058) (xy 39.714366 -476.004882) (xy 39.681709 -476.048503) (xy 39.643177 -476.087032)
			(xy 39.599553 -476.119684) (xy 39.551727 -476.145796) (xy 39.500671 -476.164836) (xy 39.447425 -476.176415)
			(xy 39.393073 -476.180299) (xy 39.338721 -476.176407) (xy 39.285477 -476.16482) (xy 39.234424 -476.145774)
			(xy 39.186601 -476.119655) (xy 39.164514 -476.103696) (xy 39.145502 -476.0901) (xy 39.103619 -476.069368)
			(xy 39.058651 -476.056642) (xy 39.012114 -476.052352) (xy 38.965577 -476.056642) (xy 38.920609 -476.069368)
			(xy 38.878726 -476.0901) (xy 38.859714 -476.103696) (xy 38.837637 -476.119673) (xy 38.78981 -476.145798)
			(xy 38.738751 -476.164849) (xy 38.685501 -476.17644) (xy 38.631143 -476.180335) (xy 38.576785 -476.176453)
			(xy 38.523532 -476.164874) (xy 38.472469 -476.145834) (xy 38.424636 -476.11972) (xy 38.381006 -476.087064)
			(xy 38.342469 -476.048532) (xy 38.309807 -476.004906) (xy 38.283687 -475.957077) (xy 38.26464 -475.906017)
			(xy 38.253055 -475.852765) (xy 38.249165 -475.798407) (xy 24.321103 -475.798407) (xy 24.296941 -475.88875)
			(xy 24.261064 -476.009462) (xy 24.224252 -476.129935) (xy 24.144014 -476.368758) (xy 24.056297 -476.604936)
			(xy 23.96119 -476.838237) (xy 23.858785 -477.068427) (xy 23.837075 -477.113362) (xy 29.519874 -477.113362)
			(xy 29.519874 -477.026462) (xy 29.527892 -476.939933) (xy 29.54386 -476.854513) (xy 29.567641 -476.770931)
			(xy 29.599033 -476.689899) (xy 29.637767 -476.61211) (xy 29.683514 -476.538226) (xy 29.735883 -476.468879)
			(xy 29.794427 -476.404659) (xy 29.858647 -476.346115) (xy 29.927994 -476.293746) (xy 30.001878 -476.247999)
			(xy 30.079667 -476.209265) (xy 30.160699 -476.177873) (xy 30.244281 -476.154092) (xy 30.329701 -476.138124)
			(xy 30.41623 -476.130106) (xy 30.50313 -476.130106) (xy 30.589659 -476.138124) (xy 30.675079 -476.154092)
			(xy 30.758661 -476.177873) (xy 30.839693 -476.209265) (xy 30.917482 -476.247999) (xy 30.991366 -476.293746)
			(xy 31.060713 -476.346115) (xy 31.124933 -476.404659) (xy 31.183477 -476.468879) (xy 31.235846 -476.538226)
			(xy 31.281593 -476.61211) (xy 31.320327 -476.689899) (xy 31.351719 -476.770931) (xy 31.3755 -476.854513)
			(xy 31.391468 -476.939933) (xy 31.399486 -477.026462) (xy 31.399988 -477.069912) (xy 31.399486 -477.113362)
			(xy 34.599874 -477.113362) (xy 34.599874 -477.026462) (xy 34.607892 -476.939933) (xy 34.62386 -476.854513)
			(xy 34.647641 -476.770931) (xy 34.679033 -476.689899) (xy 34.717767 -476.61211) (xy 34.763514 -476.538226)
			(xy 34.815883 -476.468879) (xy 34.874427 -476.404659) (xy 34.938647 -476.346115) (xy 35.007994 -476.293746)
			(xy 35.081878 -476.247999) (xy 35.159667 -476.209265) (xy 35.240699 -476.177873) (xy 35.324281 -476.154092)
			(xy 35.409701 -476.138124) (xy 35.49623 -476.130106) (xy 35.58313 -476.130106) (xy 35.669659 -476.138124)
			(xy 35.755079 -476.154092) (xy 35.838661 -476.177873) (xy 35.919693 -476.209265) (xy 35.997482 -476.247999)
			(xy 36.071366 -476.293746) (xy 36.140713 -476.346115) (xy 36.204933 -476.404659) (xy 36.263477 -476.468879)
			(xy 36.315846 -476.538226) (xy 36.361593 -476.61211) (xy 36.400327 -476.689899) (xy 36.431719 -476.770931)
			(xy 36.4555 -476.854513) (xy 36.471468 -476.939933) (xy 36.479486 -477.026462) (xy 36.479988 -477.069912)
			(xy 36.479486 -477.113362) (xy 36.471468 -477.199891) (xy 36.4555 -477.285311) (xy 36.431719 -477.368893)
			(xy 36.400327 -477.449925) (xy 36.361593 -477.527714) (xy 36.315846 -477.601598) (xy 36.263477 -477.670945)
			(xy 36.237641 -477.699286) (xy 38.249194 -477.699286) (xy 38.253084 -477.644932) (xy 38.26467 -477.591685)
			(xy 38.283716 -477.540629) (xy 38.309835 -477.492803) (xy 38.342495 -477.449182) (xy 38.381031 -477.410653)
			(xy 38.424658 -477.378) (xy 38.472488 -477.351889) (xy 38.523547 -477.332852) (xy 38.576796 -477.321275)
			(xy 38.63115 -477.317394) (xy 38.685504 -477.321289) (xy 38.73875 -477.33288) (xy 38.789804 -477.351931)
			(xy 38.837627 -477.378055) (xy 38.859714 -477.394016) (xy 38.878726 -477.407612) (xy 38.920609 -477.428344)
			(xy 38.965577 -477.44107) (xy 39.012114 -477.44536) (xy 39.058651 -477.44107) (xy 39.103619 -477.428344)
			(xy 39.145502 -477.407612) (xy 39.164514 -477.394016) (xy 39.186579 -477.378025) (xy 39.234405 -477.351903)
			(xy 39.285462 -477.332854) (xy 39.33871 -477.321265) (xy 39.393066 -477.317373) (xy 39.447422 -477.321255)
			(xy 39.500672 -477.332835) (xy 39.551732 -477.351875) (xy 39.599563 -477.377988) (xy 39.64319 -477.410642)
			(xy 39.681726 -477.449173) (xy 39.714386 -477.492796) (xy 39.740505 -477.540624) (xy 39.759552 -477.591681)
			(xy 39.771138 -477.64493) (xy 39.775027 -477.699286) (xy 40.135887 -477.699286) (xy 40.139777 -477.64493)
			(xy 40.151364 -477.591681) (xy 40.170411 -477.540624) (xy 40.196531 -477.492797) (xy 40.229192 -477.449175)
			(xy 40.267729 -477.410645) (xy 40.311357 -477.377992) (xy 40.359189 -477.351881) (xy 40.41025 -477.332843)
			(xy 40.463501 -477.321267) (xy 40.517857 -477.317387) (xy 40.572212 -477.321283) (xy 40.62546 -477.332876)
			(xy 40.676515 -477.351928) (xy 40.724339 -477.378054) (xy 40.746426 -477.394016) (xy 40.765438 -477.407612)
			(xy 40.807321 -477.428344) (xy 40.852289 -477.44107) (xy 40.898826 -477.44536) (xy 40.945363 -477.44107)
			(xy 40.990331 -477.428344) (xy 41.032214 -477.407612) (xy 41.051226 -477.394016) (xy 41.073291 -477.378026)
			(xy 41.121116 -477.351906) (xy 41.172172 -477.332859) (xy 41.225419 -477.321271) (xy 41.279772 -477.31738)
			(xy 41.334127 -477.321263) (xy 41.387375 -477.332843) (xy 41.438433 -477.351883) (xy 41.486262 -477.377996)
			(xy 41.529888 -477.41065) (xy 41.568423 -477.44918) (xy 41.601081 -477.492802) (xy 41.627199 -477.540628)
			(xy 41.646245 -477.591685) (xy 41.657831 -477.644932) (xy 41.66172 -477.699286) (xy 42.377022 -477.699286)
			(xy 42.380911 -477.644938) (xy 42.392495 -477.591697) (xy 42.411539 -477.540647) (xy 42.437653 -477.492826)
			(xy 42.470308 -477.449209) (xy 42.508838 -477.410683) (xy 42.552458 -477.378033) (xy 42.600282 -477.351922)
			(xy 42.651334 -477.332884) (xy 42.704576 -477.321306) (xy 42.758924 -477.317422) (xy 42.813272 -477.321312)
			(xy 42.866512 -477.332898) (xy 42.917562 -477.351943) (xy 42.965382 -477.378059) (xy 42.987468 -477.394016)
			(xy 43.00648 -477.407612) (xy 43.048363 -477.428344) (xy 43.093331 -477.44107) (xy 43.139868 -477.44536)
			(xy 43.186405 -477.44107) (xy 43.231373 -477.428344) (xy 43.273256 -477.407612) (xy 43.292268 -477.394016)
			(xy 43.314334 -477.378021) (xy 43.362164 -477.351892) (xy 43.413225 -477.332836) (xy 43.466478 -477.321242)
			(xy 43.520839 -477.317345) (xy 43.575202 -477.321225) (xy 43.628459 -477.332802) (xy 43.679526 -477.351842)
			(xy 43.727364 -477.377955) (xy 43.770997 -477.410612) (xy 43.809539 -477.449146) (xy 43.842204 -477.492773)
			(xy 43.868327 -477.540606) (xy 43.887377 -477.591669) (xy 43.898965 -477.644924) (xy 43.902855 -477.699286)
			(xy 44.281031 -477.699286) (xy 44.28492 -477.64494) (xy 44.296504 -477.591701) (xy 44.315546 -477.540653)
			(xy 44.34166 -477.492834) (xy 44.374313 -477.449218) (xy 44.41284 -477.410693) (xy 44.456459 -477.378044)
			(xy 44.50428 -477.351934) (xy 44.55533 -477.332896) (xy 44.608569 -477.321316) (xy 44.662915 -477.317431)
			(xy 44.717261 -477.32132) (xy 44.770499 -477.332904) (xy 44.821548 -477.351947) (xy 44.869367 -477.37806)
			(xy 44.891452 -477.394016) (xy 44.910464 -477.407612) (xy 44.952347 -477.428344) (xy 44.997315 -477.44107)
			(xy 45.043852 -477.44536) (xy 45.090389 -477.44107) (xy 45.135357 -477.428344) (xy 45.17724 -477.407612)
			(xy 45.196252 -477.394016) (xy 45.218319 -477.37802) (xy 45.266149 -477.351888) (xy 45.317212 -477.33283)
			(xy 45.370467 -477.321234) (xy 45.42483 -477.317336) (xy 45.479195 -477.321214) (xy 45.532455 -477.332791)
			(xy 45.583524 -477.35183) (xy 45.631364 -477.377944) (xy 45.675 -477.410601) (xy 45.713544 -477.449137)
			(xy 45.74621 -477.492765) (xy 45.772335 -477.540599) (xy 45.791385 -477.591665) (xy 45.802974 -477.644922)
			(xy 45.806865 -477.699286) (xy 45.802978 -477.75365) (xy 45.791393 -477.806908) (xy 45.772347 -477.857974)
			(xy 45.746226 -477.90581) (xy 45.713562 -477.949442) (xy 45.675022 -477.98798) (xy 45.631388 -478.02064)
			(xy 45.58355 -478.046758) (xy 45.532482 -478.065801) (xy 45.479224 -478.077382) (xy 45.424859 -478.081265)
			(xy 45.370495 -478.07737) (xy 45.317239 -478.065778) (xy 45.266175 -478.046724) (xy 45.218343 -478.020596)
			(xy 45.196252 -478.004632) (xy 45.17724 -477.991036) (xy 45.135357 -477.970304) (xy 45.090389 -477.957578)
			(xy 45.043852 -477.953288) (xy 44.997315 -477.957578) (xy 44.952347 -477.970304) (xy 44.910464 -477.991036)
			(xy 44.891452 -478.004632) (xy 44.869342 -478.020556) (xy 44.821522 -478.046665) (xy 44.770472 -478.065704)
			(xy 44.717232 -478.077284) (xy 44.662886 -478.081169) (xy 44.608541 -478.07728) (xy 44.555302 -478.065696)
			(xy 44.504253 -478.046654) (xy 44.456435 -478.020541) (xy 44.412819 -477.987888) (xy 44.374294 -477.94936)
			(xy 44.341644 -477.905742) (xy 44.315534 -477.857921) (xy 44.296496 -477.806871) (xy 44.284916 -477.753631)
			(xy 44.281031 -477.699286) (xy 43.902855 -477.699286) (xy 43.898969 -477.753648) (xy 43.887385 -477.806903)
			(xy 43.868339 -477.857968) (xy 43.84222 -477.905802) (xy 43.809558 -477.949432) (xy 43.771019 -477.987969)
			(xy 43.727388 -478.020629) (xy 43.679552 -478.046746) (xy 43.628487 -478.06579) (xy 43.57523 -478.077371)
			(xy 43.520868 -478.081255) (xy 43.466506 -478.077362) (xy 43.413252 -478.065772) (xy 43.36219 -478.04672)
			(xy 43.314359 -478.020595) (xy 43.292268 -478.004632) (xy 43.273256 -477.991036) (xy 43.231373 -477.970304)
			(xy 43.186405 -477.957578) (xy 43.139868 -477.953288) (xy 43.093331 -477.957578) (xy 43.048363 -477.970304)
			(xy 43.00648 -477.991036) (xy 42.987468 -478.004632) (xy 42.965358 -478.020557) (xy 42.917536 -478.046669)
			(xy 42.866485 -478.06571) (xy 42.813243 -478.077292) (xy 42.758895 -478.081178) (xy 42.704548 -478.07729)
			(xy 42.651306 -478.065708) (xy 42.600255 -478.046666) (xy 42.552434 -478.020552) (xy 42.508816 -477.987898)
			(xy 42.470289 -477.949369) (xy 42.437638 -477.90575) (xy 42.411527 -477.857927) (xy 42.392487 -477.806875)
			(xy 42.380907 -477.753634) (xy 42.377022 -477.699286) (xy 41.66172 -477.699286) (xy 41.657835 -477.75364)
			(xy 41.646253 -477.806888) (xy 41.627211 -477.857946) (xy 41.601097 -477.905774) (xy 41.568441 -477.949398)
			(xy 41.52991 -477.987931) (xy 41.486287 -478.020588) (xy 41.43846 -478.046705) (xy 41.387403 -478.065749)
			(xy 41.334155 -478.077332) (xy 41.279801 -478.08122) (xy 41.225447 -478.077333) (xy 41.172199 -478.065749)
			(xy 41.121142 -478.046706) (xy 41.073315 -478.02059) (xy 41.051226 -478.004632) (xy 41.032214 -477.991036)
			(xy 40.990331 -477.970304) (xy 40.945363 -477.957578) (xy 40.898826 -477.953288) (xy 40.852289 -477.957578)
			(xy 40.807321 -477.970304) (xy 40.765438 -477.991036) (xy 40.746426 -478.004632) (xy 40.724315 -478.020562)
			(xy 40.676489 -478.046684) (xy 40.625432 -478.065733) (xy 40.572184 -478.077321) (xy 40.517828 -478.081213)
			(xy 40.463472 -478.077329) (xy 40.410223 -478.065749) (xy 40.359163 -478.046707) (xy 40.311333 -478.020593)
			(xy 40.267707 -477.987936) (xy 40.229173 -477.949404) (xy 40.196515 -477.905779) (xy 40.170399 -477.85795)
			(xy 40.151355 -477.806891) (xy 40.139773 -477.753641) (xy 40.135887 -477.699286) (xy 39.775027 -477.699286)
			(xy 39.771142 -477.753641) (xy 39.75956 -477.806891) (xy 39.740517 -477.85795) (xy 39.714402 -477.90578)
			(xy 39.681745 -477.949405) (xy 39.643212 -477.987939) (xy 39.599587 -478.020597) (xy 39.551758 -478.046713)
			(xy 39.500699 -478.065757) (xy 39.44745 -478.07734) (xy 39.393094 -478.081227) (xy 39.338739 -478.077339)
			(xy 39.28549 -478.065754) (xy 39.234432 -478.046709) (xy 39.186604 -478.020591) (xy 39.164514 -478.004632)
			(xy 39.145502 -477.991036) (xy 39.103619 -477.970304) (xy 39.058651 -477.957578) (xy 39.012114 -477.953288)
			(xy 38.965577 -477.957578) (xy 38.920609 -477.970304) (xy 38.878726 -477.991036) (xy 38.859714 -478.004632)
			(xy 38.837603 -478.020561) (xy 38.789778 -478.046681) (xy 38.738722 -478.065728) (xy 38.685475 -478.077315)
			(xy 38.631122 -478.081206) (xy 38.576767 -478.077321) (xy 38.523519 -478.06574) (xy 38.472461 -478.046699)
			(xy 38.424633 -478.020584) (xy 38.381009 -477.987929) (xy 38.342476 -477.949397) (xy 38.30982 -477.905773)
			(xy 38.283704 -477.857945) (xy 38.264662 -477.806888) (xy 38.25308 -477.75364) (xy 38.249194 -477.699286)
			(xy 36.237641 -477.699286) (xy 36.204933 -477.735165) (xy 36.140713 -477.793709) (xy 36.071366 -477.846078)
			(xy 35.997482 -477.891825) (xy 35.919693 -477.930559) (xy 35.838661 -477.961951) (xy 35.755079 -477.985732)
			(xy 35.669659 -478.0017) (xy 35.58313 -478.009718) (xy 35.49623 -478.009718) (xy 35.409701 -478.0017)
			(xy 35.324281 -477.985732) (xy 35.240699 -477.961951) (xy 35.159667 -477.930559) (xy 35.081878 -477.891825)
			(xy 35.007994 -477.846078) (xy 34.938647 -477.793709) (xy 34.874427 -477.735165) (xy 34.815883 -477.670945)
			(xy 34.763514 -477.601598) (xy 34.717767 -477.527714) (xy 34.679033 -477.449925) (xy 34.647641 -477.368893)
			(xy 34.62386 -477.285311) (xy 34.607892 -477.199891) (xy 34.599874 -477.113362) (xy 31.399486 -477.113362)
			(xy 31.391468 -477.199891) (xy 31.3755 -477.285311) (xy 31.351719 -477.368893) (xy 31.320327 -477.449925)
			(xy 31.281593 -477.527714) (xy 31.235846 -477.601598) (xy 31.183477 -477.670945) (xy 31.124933 -477.735165)
			(xy 31.060713 -477.793709) (xy 30.991366 -477.846078) (xy 30.917482 -477.891825) (xy 30.839693 -477.930559)
			(xy 30.758661 -477.961951) (xy 30.675079 -477.985732) (xy 30.589659 -478.0017) (xy 30.50313 -478.009718)
			(xy 30.41623 -478.009718) (xy 30.329701 -478.0017) (xy 30.244281 -477.985732) (xy 30.160699 -477.961951)
			(xy 30.079667 -477.930559) (xy 30.001878 -477.891825) (xy 29.927994 -477.846078) (xy 29.858647 -477.793709)
			(xy 29.794427 -477.735165) (xy 29.735883 -477.670945) (xy 29.683514 -477.601598) (xy 29.637767 -477.527714)
			(xy 29.599033 -477.449925) (xy 29.567641 -477.368893) (xy 29.54386 -477.285311) (xy 29.527892 -477.199891)
			(xy 29.519874 -477.113362) (xy 23.837075 -477.113362) (xy 23.749184 -477.29528) (xy 23.632496 -477.51857)
			(xy 23.508837 -477.738076) (xy 23.378329 -477.95358) (xy 23.241101 -478.164869) (xy 23.09729 -478.371734)
			(xy 22.947038 -478.573969) (xy 22.790494 -478.771373) (xy 22.627814 -478.963752) (xy 22.459158 -479.150914)
			(xy 22.284693 -479.332673) (xy 22.104593 -479.508851) (xy 21.947248 -479.653362) (xy 29.519874 -479.653362)
			(xy 29.519874 -479.566462) (xy 29.527892 -479.479933) (xy 29.54386 -479.394513) (xy 29.567641 -479.310931)
			(xy 29.599033 -479.229899) (xy 29.637767 -479.15211) (xy 29.683514 -479.078226) (xy 29.735883 -479.008879)
			(xy 29.794427 -478.944659) (xy 29.858647 -478.886115) (xy 29.927994 -478.833746) (xy 30.001878 -478.787999)
			(xy 30.079667 -478.749265) (xy 30.160699 -478.717873) (xy 30.244281 -478.694092) (xy 30.329701 -478.678124)
			(xy 30.41623 -478.670106) (xy 30.50313 -478.670106) (xy 30.589659 -478.678124) (xy 30.675079 -478.694092)
			(xy 30.758661 -478.717873) (xy 30.839693 -478.749265) (xy 30.917482 -478.787999) (xy 30.991366 -478.833746)
			(xy 31.060713 -478.886115) (xy 31.124933 -478.944659) (xy 31.183477 -479.008879) (xy 31.235846 -479.078226)
			(xy 31.281593 -479.15211) (xy 31.320327 -479.229899) (xy 31.351719 -479.310931) (xy 31.3755 -479.394513)
			(xy 31.391468 -479.479933) (xy 31.399486 -479.566462) (xy 31.399988 -479.609912) (xy 31.399486 -479.653362)
			(xy 34.599874 -479.653362) (xy 34.599874 -479.566462) (xy 34.607892 -479.479933) (xy 34.62386 -479.394513)
			(xy 34.647641 -479.310931) (xy 34.679033 -479.229899) (xy 34.717767 -479.15211) (xy 34.763514 -479.078226)
			(xy 34.815883 -479.008879) (xy 34.874427 -478.944659) (xy 34.938647 -478.886115) (xy 35.007994 -478.833746)
			(xy 35.081878 -478.787999) (xy 35.159667 -478.749265) (xy 35.240699 -478.717873) (xy 35.324281 -478.694092)
			(xy 35.409701 -478.678124) (xy 35.49623 -478.670106) (xy 35.58313 -478.670106) (xy 35.669659 -478.678124)
			(xy 35.755079 -478.694092) (xy 35.838661 -478.717873) (xy 35.919693 -478.749265) (xy 35.997482 -478.787999)
			(xy 36.016712 -478.799906) (xy 74.39914 -478.799906) (xy 74.39914 -477.799908) (xy 74.399635 -477.715487)
			(xy 74.407549 -477.546829) (xy 74.423359 -477.378729) (xy 74.447032 -477.211554) (xy 74.478514 -477.045672)
			(xy 74.517737 -476.881448) (xy 74.564615 -476.719244) (xy 74.619044 -476.559414) (xy 74.680904 -476.402312)
			(xy 74.750061 -476.248282) (xy 74.826361 -476.097663) (xy 74.909637 -475.950785) (xy 74.999706 -475.807973)
			(xy 75.09637 -475.669539) (xy 75.199416 -475.535788) (xy 75.308619 -475.407014) (xy 75.423737 -475.2835)
			(xy 75.544518 -475.165518) (xy 75.670697 -475.053327) (xy 75.801995 -474.947173) (xy 75.938125 -474.847291)
			(xy 76.078787 -474.753898) (xy 76.223672 -474.667202) (xy 76.372461 -474.587392) (xy 76.524828 -474.514644)
			(xy 76.680437 -474.449117) (xy 76.838946 -474.390957) (xy 77.000007 -474.340289) (xy 77.163266 -474.297227)
			(xy 77.328364 -474.261865) (xy 77.494938 -474.23428) (xy 77.662622 -474.214533) (xy 77.831048 -474.202667)
			(xy 77.999844 -474.198709) (xy 78.16864 -474.202667) (xy 78.337066 -474.214533) (xy 78.50475 -474.23428)
			(xy 78.671324 -474.261865) (xy 78.836422 -474.297227) (xy 78.999681 -474.340289) (xy 79.160742 -474.390957)
			(xy 79.319251 -474.449117) (xy 79.47486 -474.514644) (xy 79.627227 -474.587392) (xy 79.776016 -474.667202)
			(xy 79.920901 -474.753898) (xy 80.061563 -474.847291) (xy 80.197693 -474.947173) (xy 80.328991 -475.053327)
			(xy 80.45517 -475.165518) (xy 80.575951 -475.2835) (xy 80.691069 -475.407014) (xy 80.800272 -475.535788)
			(xy 80.903318 -475.669539) (xy 80.999982 -475.807973) (xy 81.090051 -475.950785) (xy 81.173327 -476.097663)
			(xy 81.249627 -476.248282) (xy 81.318784 -476.402312) (xy 81.380644 -476.559414) (xy 81.435073 -476.719244)
			(xy 81.481951 -476.881448) (xy 81.521174 -477.045672) (xy 81.552656 -477.211554) (xy 81.576329 -477.378729)
			(xy 81.592139 -477.546829) (xy 81.600053 -477.715487) (xy 81.600548 -477.799908) (xy 81.600548 -478.799906)
			(xy 81.600053 -478.884327) (xy 81.592139 -479.052985) (xy 81.576329 -479.221085) (xy 81.555187 -479.37039)
			(xy 89.11158 -479.37039) (xy 89.115651 -479.314768) (xy 89.127777 -479.260331) (xy 89.1477 -479.20824)
			(xy 89.174996 -479.159605) (xy 89.209082 -479.115462) (xy 89.249231 -479.076753) (xy 89.294589 -479.044302)
			(xy 89.344189 -479.018801) (xy 89.396973 -479.000794) (xy 89.451816 -478.990664) (xy 89.50755 -478.988627)
			(xy 89.562987 -478.994727) (xy 89.616944 -479.008833) (xy 89.668273 -479.030645) (xy 89.715879 -479.059699)
			(xy 89.758747 -479.095374) (xy 89.795964 -479.136911) (xy 89.826737 -479.183424) (xy 89.850409 -479.233921)
			(xy 89.866477 -479.287328) (xy 89.874597 -479.342504) (xy 89.875106 -479.37039) (xy 89.874597 -479.398276)
			(xy 89.866477 -479.453452) (xy 89.850409 -479.506859) (xy 89.826737 -479.557356) (xy 89.795964 -479.603869)
			(xy 89.758747 -479.645406) (xy 89.715879 -479.681081) (xy 89.668273 -479.710135) (xy 89.616944 -479.731947)
			(xy 89.562987 -479.746053) (xy 89.50755 -479.752153) (xy 89.451816 -479.750116) (xy 89.396973 -479.739986)
			(xy 89.344189 -479.721979) (xy 89.294589 -479.696478) (xy 89.249231 -479.664027) (xy 89.209082 -479.625318)
			(xy 89.174996 -479.581175) (xy 89.1477 -479.53254) (xy 89.127777 -479.480449) (xy 89.115651 -479.426012)
			(xy 89.11158 -479.37039) (xy 81.555187 -479.37039) (xy 81.552656 -479.38826) (xy 81.521174 -479.554142)
			(xy 81.481951 -479.718366) (xy 81.435073 -479.88057) (xy 81.380644 -480.0404) (xy 81.318784 -480.197502)
			(xy 81.249627 -480.351532) (xy 81.173327 -480.502151) (xy 81.090051 -480.649029) (xy 80.999982 -480.791841)
			(xy 80.903318 -480.930275) (xy 80.800272 -481.064026) (xy 80.691069 -481.1928) (xy 80.575951 -481.316314)
			(xy 80.45517 -481.434296) (xy 80.328991 -481.546487) (xy 80.197693 -481.652641) (xy 80.061563 -481.752523)
			(xy 79.920901 -481.845916) (xy 79.776016 -481.932612) (xy 79.627227 -482.012422) (xy 79.47486 -482.08517)
			(xy 79.319251 -482.150697) (xy 79.160742 -482.208857) (xy 78.999681 -482.259525) (xy 78.836422 -482.302587)
			(xy 78.671324 -482.337949) (xy 78.50475 -482.365534) (xy 78.337066 -482.385281) (xy 78.16864 -482.397147)
			(xy 77.999844 -482.401105) (xy 77.831048 -482.397147) (xy 77.662622 -482.385281) (xy 77.494938 -482.365534)
			(xy 77.328364 -482.337949) (xy 77.163266 -482.302587) (xy 77.000007 -482.259525) (xy 76.838946 -482.208857)
			(xy 76.680437 -482.150697) (xy 76.524828 -482.08517) (xy 76.372461 -482.012422) (xy 76.223672 -481.932612)
			(xy 76.078787 -481.845916) (xy 75.938125 -481.752523) (xy 75.801995 -481.652641) (xy 75.670697 -481.546487)
			(xy 75.544518 -481.434296) (xy 75.423737 -481.316314) (xy 75.308619 -481.1928) (xy 75.199416 -481.064026)
			(xy 75.09637 -480.930275) (xy 74.999706 -480.791841) (xy 74.909637 -480.649029) (xy 74.826361 -480.502151)
			(xy 74.750061 -480.351532) (xy 74.680904 -480.197502) (xy 74.619044 -480.0404) (xy 74.564615 -479.88057)
			(xy 74.517737 -479.718366) (xy 74.478514 -479.554142) (xy 74.447032 -479.38826) (xy 74.423359 -479.221085)
			(xy 74.407549 -479.052985) (xy 74.399635 -478.884327) (xy 74.39914 -478.799906) (xy 36.016712 -478.799906)
			(xy 36.071366 -478.833746) (xy 36.140713 -478.886115) (xy 36.204933 -478.944659) (xy 36.263477 -479.008879)
			(xy 36.315846 -479.078226) (xy 36.361593 -479.15211) (xy 36.400327 -479.229899) (xy 36.431719 -479.310931)
			(xy 36.449814 -479.374528) (xy 38.249138 -479.374528) (xy 38.253023 -479.320165) (xy 38.264604 -479.266909)
			(xy 38.283648 -479.215844) (xy 38.309765 -479.168008) (xy 38.342425 -479.124377) (xy 38.380962 -479.085838)
			(xy 38.424592 -479.053176) (xy 38.472426 -479.027056) (xy 38.523491 -479.00801) (xy 38.576746 -478.996425)
			(xy 38.631108 -478.992538) (xy 38.68547 -478.996428) (xy 38.738725 -479.008015) (xy 38.789789 -479.027063)
			(xy 38.837622 -479.053185) (xy 38.859714 -479.069146) (xy 38.878726 -479.082742) (xy 38.920609 -479.103474)
			(xy 38.965577 -479.1162) (xy 39.012114 -479.12049) (xy 39.058651 -479.1162) (xy 39.103619 -479.103474)
			(xy 39.145502 -479.082742) (xy 39.164514 -479.069146) (xy 39.186645 -479.053249) (xy 39.234467 -479.027137)
			(xy 39.285518 -479.008096) (xy 39.33876 -478.996515) (xy 39.393108 -478.992629) (xy 39.447455 -478.996517)
			(xy 39.500696 -479.0081) (xy 39.551747 -479.027143) (xy 39.599568 -479.053257) (xy 39.643185 -479.085912)
			(xy 39.681711 -479.124441) (xy 39.714362 -479.168062) (xy 39.740472 -479.215885) (xy 39.75951 -479.266937)
			(xy 39.771088 -479.32018) (xy 39.774971 -479.374528) (xy 40.135831 -479.374528) (xy 40.139716 -479.320164)
			(xy 40.151298 -479.266906) (xy 40.170342 -479.215839) (xy 40.196461 -479.168002) (xy 40.229122 -479.12437)
			(xy 40.26766 -479.08583) (xy 40.311292 -479.053167) (xy 40.359128 -479.027047) (xy 40.410194 -479.008001)
			(xy 40.463451 -478.996417) (xy 40.517815 -478.992531) (xy 40.572179 -478.996422) (xy 40.625435 -479.00801)
			(xy 40.6765 -479.02706) (xy 40.724334 -479.053184) (xy 40.746426 -479.069146) (xy 40.765438 -479.082742)
			(xy 40.807321 -479.103474) (xy 40.852289 -479.1162) (xy 40.898826 -479.12049) (xy 40.945363 -479.1162)
			(xy 40.990331 -479.103474) (xy 41.032214 -479.082742) (xy 41.051226 -479.069146) (xy 41.073357 -479.05325)
			(xy 41.121178 -479.02714) (xy 41.172228 -479.008101) (xy 41.225468 -478.996521) (xy 41.279814 -478.992636)
			(xy 41.33416 -478.996525) (xy 41.3874 -479.008109) (xy 41.438448 -479.027152) (xy 41.486267 -479.053266)
			(xy 41.529883 -479.08592) (xy 41.568408 -479.124448) (xy 41.601057 -479.168068) (xy 41.627166 -479.21589)
			(xy 41.646203 -479.266941) (xy 41.657781 -479.320181) (xy 41.661664 -479.374528) (xy 42.376966 -479.374528)
			(xy 42.38085 -479.320172) (xy 42.39243 -479.266921) (xy 42.41147 -479.215861) (xy 42.437584 -479.168031)
			(xy 42.470238 -479.124404) (xy 42.50877 -479.085868) (xy 42.552393 -479.053208) (xy 42.60022 -479.027089)
			(xy 42.651278 -479.008042) (xy 42.704527 -478.996456) (xy 42.758882 -478.992566) (xy 42.813238 -478.996451)
			(xy 42.866488 -479.008032) (xy 42.917547 -479.027074) (xy 42.965377 -479.053189) (xy 42.987468 -479.069146)
			(xy 43.00648 -479.082742) (xy 43.048363 -479.103474) (xy 43.093331 -479.1162) (xy 43.139868 -479.12049)
			(xy 43.186405 -479.1162) (xy 43.231373 -479.103474) (xy 43.273256 -479.082742) (xy 43.292268 -479.069146)
			(xy 43.3144 -479.053245) (xy 43.362225 -479.027126) (xy 43.413281 -479.008078) (xy 43.466528 -478.996492)
			(xy 43.520881 -478.992601) (xy 43.575236 -478.996486) (xy 43.628484 -479.008068) (xy 43.679541 -479.02711)
			(xy 43.727369 -479.053225) (xy 43.770992 -479.085882) (xy 43.809524 -479.124414) (xy 43.84218 -479.168039)
			(xy 43.868294 -479.215867) (xy 43.887335 -479.266925) (xy 43.898915 -479.320173) (xy 43.902799 -479.374528)
			(xy 44.280975 -479.374528) (xy 44.284859 -479.320174) (xy 44.296438 -479.266926) (xy 44.315478 -479.215868)
			(xy 44.34159 -479.168039) (xy 44.374243 -479.124413) (xy 44.412772 -479.085878) (xy 44.456393 -479.053219)
			(xy 44.504218 -479.0271) (xy 44.555274 -479.008054) (xy 44.60852 -478.996467) (xy 44.662873 -478.992575)
			(xy 44.717227 -478.996459) (xy 44.770475 -479.008039) (xy 44.821533 -479.027078) (xy 44.869362 -479.05319)
			(xy 44.891452 -479.069146) (xy 44.910464 -479.082742) (xy 44.952347 -479.103474) (xy 44.997315 -479.1162)
			(xy 45.043852 -479.12049) (xy 45.090389 -479.1162) (xy 45.135357 -479.103474) (xy 45.17724 -479.082742)
			(xy 45.196252 -479.069146) (xy 45.218384 -479.053244) (xy 45.266211 -479.027122) (xy 45.317268 -479.008072)
			(xy 45.370516 -478.996483) (xy 45.424872 -478.992592) (xy 45.479229 -478.996476) (xy 45.532479 -479.008057)
			(xy 45.583539 -479.027099) (xy 45.631369 -479.053214) (xy 45.674995 -479.085871) (xy 45.713529 -479.124405)
			(xy 45.746186 -479.168031) (xy 45.772301 -479.215861) (xy 45.791343 -479.266921) (xy 45.802924 -479.320171)
			(xy 45.806808 -479.374528) (xy 45.802917 -479.428884) (xy 45.791328 -479.482132) (xy 45.772278 -479.533189)
			(xy 45.746156 -479.581015) (xy 45.713493 -479.624637) (xy 45.674953 -479.663165) (xy 45.631322 -479.695816)
			(xy 45.583489 -479.721924) (xy 45.532426 -479.740959) (xy 45.479174 -479.752532) (xy 45.424817 -479.756408)
			(xy 45.370462 -479.752509) (xy 45.317215 -479.740912) (xy 45.26616 -479.721855) (xy 45.218338 -479.695726)
			(xy 45.196252 -479.679762) (xy 45.17724 -479.666166) (xy 45.135357 -479.645434) (xy 45.090389 -479.632708)
			(xy 45.043852 -479.628418) (xy 44.997315 -479.632708) (xy 44.952347 -479.645434) (xy 44.910464 -479.666166)
			(xy 44.891452 -479.679762) (xy 44.869408 -479.69578) (xy 44.821583 -479.721899) (xy 44.770528 -479.740946)
			(xy 44.717282 -479.752533) (xy 44.662928 -479.756425) (xy 44.608574 -479.752541) (xy 44.555326 -479.740962)
			(xy 44.504268 -479.721923) (xy 44.45644 -479.695811) (xy 44.412814 -479.663158) (xy 44.374279 -479.624629)
			(xy 44.34162 -479.581007) (xy 44.315501 -479.533182) (xy 44.296454 -479.482127) (xy 44.284867 -479.428881)
			(xy 44.280975 -479.374528) (xy 43.902799 -479.374528) (xy 43.898907 -479.428881) (xy 43.887319 -479.482128)
			(xy 43.868271 -479.533183) (xy 43.84215 -479.581007) (xy 43.809488 -479.624627) (xy 43.770951 -479.663155)
			(xy 43.727322 -479.695805) (xy 43.679491 -479.721913) (xy 43.628431 -479.740948) (xy 43.575181 -479.752522)
			(xy 43.520826 -479.756399) (xy 43.466473 -479.752501) (xy 43.413228 -479.740906) (xy 43.362175 -479.721852)
			(xy 43.314354 -479.695725) (xy 43.292268 -479.679762) (xy 43.273256 -479.666166) (xy 43.231373 -479.645434)
			(xy 43.186405 -479.632708) (xy 43.139868 -479.628418) (xy 43.093331 -479.632708) (xy 43.048363 -479.645434)
			(xy 43.00648 -479.666166) (xy 42.987468 -479.679762) (xy 42.965424 -479.695781) (xy 42.917598 -479.721903)
			(xy 42.866541 -479.740952) (xy 42.813293 -479.752541) (xy 42.758937 -479.756434) (xy 42.704581 -479.752552)
			(xy 42.651331 -479.740973) (xy 42.60027 -479.721934) (xy 42.552439 -479.695822) (xy 42.508811 -479.663168)
			(xy 42.470274 -479.624638) (xy 42.437613 -479.581015) (xy 42.411493 -479.533189) (xy 42.392445 -479.482131)
			(xy 42.380857 -479.428883) (xy 42.376966 -479.374528) (xy 41.661664 -479.374528) (xy 41.657773 -479.428873)
			(xy 41.646187 -479.482112) (xy 41.627143 -479.53316) (xy 41.601027 -479.580979) (xy 41.568372 -479.624593)
			(xy 41.529841 -479.663116) (xy 41.486221 -479.695764) (xy 41.438398 -479.721871) (xy 41.387347 -479.740907)
			(xy 41.334106 -479.752483) (xy 41.279759 -479.756364) (xy 41.225413 -479.752471) (xy 41.172175 -479.740884)
			(xy 41.121127 -479.721837) (xy 41.07331 -479.69572) (xy 41.051226 -479.679762) (xy 41.032214 -479.666166)
			(xy 40.990331 -479.645434) (xy 40.945363 -479.632708) (xy 40.898826 -479.628418) (xy 40.852289 -479.632708)
			(xy 40.807321 -479.645434) (xy 40.765438 -479.666166) (xy 40.746426 -479.679762) (xy 40.72438 -479.695786)
			(xy 40.67655 -479.721917) (xy 40.625488 -479.740974) (xy 40.572233 -479.75257) (xy 40.51787 -479.756469)
			(xy 40.463506 -479.752591) (xy 40.410247 -479.741014) (xy 40.359178 -479.721976) (xy 40.311338 -479.695862)
			(xy 40.267702 -479.663206) (xy 40.229158 -479.624672) (xy 40.196491 -479.581044) (xy 40.170365 -479.533211)
			(xy 40.151313 -479.482147) (xy 40.139723 -479.428891) (xy 40.135831 -479.374528) (xy 39.774971 -479.374528)
			(xy 39.77108 -479.428875) (xy 39.759494 -479.482116) (xy 39.740449 -479.533165) (xy 39.714332 -479.580985)
			(xy 39.681675 -479.6246) (xy 39.643143 -479.663124) (xy 39.599521 -479.695772) (xy 39.551697 -479.72188)
			(xy 39.500643 -479.740915) (xy 39.447401 -479.752491) (xy 39.393052 -479.756371) (xy 39.338705 -479.752477)
			(xy 39.285465 -479.740888) (xy 39.234417 -479.72184) (xy 39.186599 -479.695721) (xy 39.164514 -479.679762)
			(xy 39.145502 -479.666166) (xy 39.103619 -479.645434) (xy 39.058651 -479.632708) (xy 39.012114 -479.628418)
			(xy 38.965577 -479.632708) (xy 38.920609 -479.645434) (xy 38.878726 -479.666166) (xy 38.859714 -479.679762)
			(xy 38.837669 -479.695785) (xy 38.789839 -479.721914) (xy 38.738778 -479.74097) (xy 38.685525 -479.752564)
			(xy 38.631164 -479.756462) (xy 38.576801 -479.752582) (xy 38.523544 -479.741006) (xy 38.472476 -479.721967)
			(xy 38.424638 -479.695854) (xy 38.381004 -479.663198) (xy 38.342461 -479.624665) (xy 38.309795 -479.581038)
			(xy 38.283671 -479.533207) (xy 38.26462 -479.482144) (xy 38.25303 -479.428889) (xy 38.249138 -479.374528)
			(xy 36.449814 -479.374528) (xy 36.4555 -479.394513) (xy 36.471468 -479.479933) (xy 36.479486 -479.566462)
			(xy 36.479988 -479.609912) (xy 36.479486 -479.653362) (xy 36.471468 -479.739891) (xy 36.4555 -479.825311)
			(xy 36.431719 -479.908893) (xy 36.400327 -479.989925) (xy 36.361593 -480.067714) (xy 36.315846 -480.141598)
			(xy 36.263477 -480.210945) (xy 36.204933 -480.275165) (xy 36.140713 -480.333709) (xy 36.071366 -480.386078)
			(xy 35.997482 -480.431825) (xy 35.919693 -480.470559) (xy 35.838661 -480.501951) (xy 35.755079 -480.525732)
			(xy 35.669659 -480.5417) (xy 35.58313 -480.549718) (xy 35.49623 -480.549718) (xy 35.409701 -480.5417)
			(xy 35.324281 -480.525732) (xy 35.240699 -480.501951) (xy 35.159667 -480.470559) (xy 35.081878 -480.431825)
			(xy 35.007994 -480.386078) (xy 34.938647 -480.333709) (xy 34.874427 -480.275165) (xy 34.815883 -480.210945)
			(xy 34.763514 -480.141598) (xy 34.717767 -480.067714) (xy 34.679033 -479.989925) (xy 34.647641 -479.908893)
			(xy 34.62386 -479.825311) (xy 34.607892 -479.739891) (xy 34.599874 -479.653362) (xy 31.399486 -479.653362)
			(xy 31.391468 -479.739891) (xy 31.3755 -479.825311) (xy 31.351719 -479.908893) (xy 31.320327 -479.989925)
			(xy 31.281593 -480.067714) (xy 31.235846 -480.141598) (xy 31.183477 -480.210945) (xy 31.124933 -480.275165)
			(xy 31.060713 -480.333709) (xy 30.991366 -480.386078) (xy 30.917482 -480.431825) (xy 30.839693 -480.470559)
			(xy 30.758661 -480.501951) (xy 30.675079 -480.525732) (xy 30.589659 -480.5417) (xy 30.50313 -480.549718)
			(xy 30.41623 -480.549718) (xy 30.329701 -480.5417) (xy 30.244281 -480.525732) (xy 30.160699 -480.501951)
			(xy 30.079667 -480.470559) (xy 30.001878 -480.431825) (xy 29.927994 -480.386078) (xy 29.858647 -480.333709)
			(xy 29.794427 -480.275165) (xy 29.735883 -480.210945) (xy 29.683514 -480.141598) (xy 29.637767 -480.067714)
			(xy 29.599033 -479.989925) (xy 29.567641 -479.908893) (xy 29.54386 -479.825311) (xy 29.527892 -479.739891)
			(xy 29.519874 -479.653362) (xy 21.947248 -479.653362) (xy 21.919037 -479.679272) (xy 21.728207 -479.843767)
			(xy 21.532294 -480.002172) (xy 21.331491 -480.154332) (xy 21.125997 -480.300096) (xy 20.916017 -480.439318)
			(xy 20.701758 -480.57186) (xy 20.483433 -480.697593) (xy 20.261258 -480.816389) (xy 20.035453 -480.928133)
			(xy 19.806242 -481.032713) (xy 19.573853 -481.130026) (xy 19.338515 -481.219974) (xy 19.100463 -481.30247)
			(xy 18.859931 -481.377431) (xy 18.617159 -481.444782) (xy 18.372387 -481.504458) (xy 18.125858 -481.556398)
			(xy 17.877816 -481.600552) (xy 17.628507 -481.636876) (xy 17.378178 -481.665333) (xy 17.127077 -481.685896)
			(xy 16.875453 -481.698544) (xy 16.623556 -481.703264) (xy 16.371635 -481.700052) (xy 16.11994 -481.688911)
			(xy 15.86872 -481.669853) (xy 15.618225 -481.642895) (xy 15.368703 -481.608065) (xy 15.120401 -481.565397)
			(xy 14.873565 -481.514934) (xy 14.62844 -481.456725) (xy 14.385269 -481.390829) (xy 14.144293 -481.31731)
			(xy 13.905751 -481.236241) (xy 13.669879 -481.147703) (xy 13.436911 -481.051784) (xy 13.207078 -480.948579)
			(xy 12.980608 -480.838189) (xy 12.757726 -480.720725) (xy 12.538652 -480.596302) (xy 12.323603 -480.465045)
			(xy 12.112792 -480.327083) (xy 11.90643 -480.182553) (xy 11.704719 -480.031598) (xy 11.507861 -479.874368)
			(xy 11.316049 -479.711019) (xy 11.129476 -479.541713) (xy 10.948324 -479.366617) (xy 10.772774 -479.185905)
			(xy 10.603 -478.999756) (xy 10.439171 -478.808355) (xy 10.281448 -478.611892) (xy 10.129987 -478.41056)
			(xy 9.98494 -478.204561) (xy 9.84645 -477.994097) (xy 9.714654 -477.779378) (xy 9.589682 -477.560617)
			(xy 9.471659 -477.338029) (xy 9.360702 -477.111837) (xy 9.25692 -476.882264) (xy 9.160417 -476.649537)
			(xy 9.071288 -476.413888) (xy 8.989621 -476.17555) (xy 8.915498 -475.934759) (xy 8.848992 -475.691754)
			(xy 8.790169 -475.446776) (xy 8.739087 -475.200068) (xy 8.695796 -474.951873) (xy 8.66034 -474.702439)
			(xy 8.632754 -474.452013) (xy 8.613066 -474.200842) (xy 8.601294 -473.949175) (xy 8.59745 -473.697263)
			(xy 8.601539 -473.445355) (xy 8.613555 -473.1937) (xy 8.633488 -472.942549) (xy 8.661318 -472.692149)
			(xy 8.697016 -472.442749) (xy 8.718296 -472.318588) (xy 8.72174 -472.296089) (xy 8.721477 -472.250579)
			(xy 8.713113 -472.205843) (xy 8.696916 -472.163312) (xy 8.673404 -472.124345) (xy 8.643328 -472.090188)
			(xy 8.60765 -472.061934) (xy 8.567511 -472.040484) (xy 8.524193 -472.026526) (xy 8.479082 -472.020505)
			(xy 8.43362 -472.022615) (xy 8.38926 -472.032786) (xy 8.347421 -472.050695) (xy 8.328152 -472.06281)
			(xy 8.289177 -472.087947) (xy 8.207637 -472.13215) (xy 8.122569 -472.169112) (xy 8.034615 -472.198554)
			(xy 7.944439 -472.220253) (xy 7.85272 -472.234047) (xy 7.76015 -472.239832) (xy 7.667427 -472.237563)
			(xy 7.57525 -472.227258) (xy 7.484316 -472.208994) (xy 7.395308 -472.18291) (xy 7.3089 -472.149202)
			(xy 7.225742 -472.108123) (xy 7.146461 -472.059985) (xy 7.071656 -472.00515) (xy 7.001891 -471.944032)
			(xy 6.937691 -471.877091) (xy 6.879542 -471.804832) (xy 6.827881 -471.727801) (xy 6.783098 -471.646578)
			(xy 6.745531 -471.561776) (xy 6.715463 -471.474034) (xy 6.693121 -471.384014) (xy 6.678674 -471.292396)
			(xy 6.67223 -471.199869) (xy 2.46126 -471.199869) (xy 2.46126 -473.385642) (xy 3.290507 -474.214889)
			(xy 4.852911 -474.214889) (xy 4.852911 -474.129163) (xy 4.860821 -474.043803) (xy 4.876573 -473.959536)
			(xy 4.900033 -473.877083) (xy 4.931001 -473.797146) (xy 4.969212 -473.720407) (xy 5.014341 -473.647521)
			(xy 5.066002 -473.57911) (xy 5.123756 -473.515758) (xy 5.187108 -473.458004) (xy 5.255519 -473.406343)
			(xy 5.328405 -473.361214) (xy 5.405144 -473.323003) (xy 5.485081 -473.292035) (xy 5.567534 -473.268575)
			(xy 5.651801 -473.252823) (xy 5.737161 -473.244913) (xy 5.822887 -473.244913) (xy 5.908247 -473.252823)
			(xy 5.992514 -473.268575) (xy 6.074967 -473.292035) (xy 6.154904 -473.323003) (xy 6.231643 -473.361214)
			(xy 6.304529 -473.406343) (xy 6.37294 -473.458004) (xy 6.436292 -473.515758) (xy 6.494046 -473.57911)
			(xy 6.545707 -473.647521) (xy 6.590836 -473.720407) (xy 6.629047 -473.797146) (xy 6.660015 -473.877083)
			(xy 6.683475 -473.959536) (xy 6.699227 -474.043803) (xy 6.707137 -474.129163) (xy 6.707632 -474.172026)
			(xy 6.707137 -474.214889) (xy 6.699227 -474.300249) (xy 6.683475 -474.384516) (xy 6.660015 -474.466969)
			(xy 6.629047 -474.546906) (xy 6.590836 -474.623645) (xy 6.545707 -474.696531) (xy 6.494046 -474.764942)
			(xy 6.436292 -474.828294) (xy 6.37294 -474.886048) (xy 6.304529 -474.937709) (xy 6.231643 -474.982838)
			(xy 6.154904 -475.021049) (xy 6.074967 -475.052017) (xy 5.992514 -475.075477) (xy 5.908247 -475.091229)
			(xy 5.822887 -475.099139) (xy 5.737161 -475.099139) (xy 5.651801 -475.091229) (xy 5.567534 -475.075477)
			(xy 5.485081 -475.052017) (xy 5.405144 -475.021049) (xy 5.328405 -474.982838) (xy 5.255519 -474.937709)
			(xy 5.187108 -474.886048) (xy 5.123756 -474.828294) (xy 5.066002 -474.764942) (xy 5.014341 -474.696531)
			(xy 4.969212 -474.623645) (xy 4.931001 -474.546906) (xy 4.900033 -474.466969) (xy 4.876573 -474.384516)
			(xy 4.860821 -474.300249) (xy 4.852911 -474.214889) (xy 3.290507 -474.214889) (xy 5.32003 -476.244412)
			(xy 6.707632 -476.244412) (xy 6.707632 -478.099628) (xy 4.852416 -478.099628) (xy 4.852416 -476.712026)
			(xy 2.506472 -474.366082) (xy 2.489947 -474.351471) (xy 2.452862 -474.327596) (xy 2.412214 -474.310475)
			(xy 2.369223 -474.300621) (xy 2.325176 -474.298331) (xy 2.281395 -474.303672) (xy 2.239191 -474.316485)
			(xy 2.199829 -474.336385) (xy 2.16449 -474.362776) (xy 2.134232 -474.394867) (xy 2.109964 -474.431696)
			(xy 2.092411 -474.472159) (xy 2.0821 -474.515043) (xy 2.08026 -474.537024) (xy 2.08026 -480.172014)
			(xy 6.671831 -480.172014) (xy 6.675786 -480.080177) (xy 6.687621 -479.98902) (xy 6.707248 -479.899217)
			(xy 6.734522 -479.811435) (xy 6.769242 -479.726321) (xy 6.81115 -479.644508) (xy 6.859936 -479.5666)
			(xy 6.915239 -479.493175) (xy 6.976649 -479.424775) (xy 7.043711 -479.361908) (xy 7.11593 -479.305038)
			(xy 7.19277 -479.254587) (xy 7.273663 -479.210928) (xy 7.358009 -479.174385) (xy 7.445185 -479.145228)
			(xy 7.534544 -479.123674) (xy 7.625425 -479.10988) (xy 7.717156 -479.10395) (xy 7.809057 -479.105928)
			(xy 7.900448 -479.115799) (xy 7.990652 -479.133489) (xy 8.079001 -479.158869) (xy 8.164841 -479.191749)
			(xy 8.247537 -479.231887) (xy 8.326477 -479.278986) (xy 8.401075 -479.332696) (xy 8.470781 -479.39262)
			(xy 8.535076 -479.458314) (xy 8.593487 -479.529292) (xy 8.645579 -479.605029) (xy 8.690968 -479.684964)
			(xy 8.729318 -479.768504) (xy 8.760343 -479.855032) (xy 8.783816 -479.943907) (xy 8.799562 -480.034471)
			(xy 8.807464 -480.126053) (xy 8.807958 -480.172014) (xy 8.807464 -480.217975) (xy 8.799562 -480.309557)
			(xy 8.783816 -480.400121) (xy 8.760343 -480.488996) (xy 8.729318 -480.575524) (xy 8.690968 -480.659064)
			(xy 8.645579 -480.738999) (xy 8.593487 -480.814736) (xy 8.535076 -480.885714) (xy 8.470781 -480.951408)
			(xy 8.401075 -481.011332) (xy 8.326477 -481.065042) (xy 8.247537 -481.112141) (xy 8.164841 -481.152279)
			(xy 8.079001 -481.185159) (xy 7.990652 -481.210539) (xy 7.900448 -481.228229) (xy 7.809057 -481.2381)
			(xy 7.717156 -481.240078) (xy 7.625425 -481.234148) (xy 7.534544 -481.220354) (xy 7.445185 -481.1988)
			(xy 7.358009 -481.169643) (xy 7.273663 -481.1331) (xy 7.19277 -481.089441) (xy 7.11593 -481.03899)
			(xy 7.043711 -480.98212) (xy 6.976649 -480.919253) (xy 6.915239 -480.850853) (xy 6.859936 -480.777428)
			(xy 6.81115 -480.69952) (xy 6.769242 -480.617707) (xy 6.734522 -480.532593) (xy 6.707248 -480.444811)
			(xy 6.687621 -480.355008) (xy 6.675786 -480.263851) (xy 6.671831 -480.172014) (xy 2.08026 -480.172014)
			(xy 2.08026 -482.193362) (xy 29.519874 -482.193362) (xy 29.519874 -482.106462) (xy 29.527892 -482.019933)
			(xy 29.54386 -481.934513) (xy 29.567641 -481.850931) (xy 29.599033 -481.769899) (xy 29.637767 -481.69211)
			(xy 29.683514 -481.618226) (xy 29.735883 -481.548879) (xy 29.794427 -481.484659) (xy 29.858647 -481.426115)
			(xy 29.927994 -481.373746) (xy 30.001878 -481.327999) (xy 30.079667 -481.289265) (xy 30.160699 -481.257873)
			(xy 30.244281 -481.234092) (xy 30.329701 -481.218124) (xy 30.41623 -481.210106) (xy 30.50313 -481.210106)
			(xy 30.589659 -481.218124) (xy 30.675079 -481.234092) (xy 30.758661 -481.257873) (xy 30.839693 -481.289265)
			(xy 30.917482 -481.327999) (xy 30.991366 -481.373746) (xy 31.060713 -481.426115) (xy 31.124933 -481.484659)
			(xy 31.183477 -481.548879) (xy 31.235846 -481.618226) (xy 31.281593 -481.69211) (xy 31.320327 -481.769899)
			(xy 31.351719 -481.850931) (xy 31.3755 -481.934513) (xy 31.391468 -482.019933) (xy 31.399486 -482.106462)
			(xy 31.399988 -482.149912) (xy 31.399486 -482.193362) (xy 34.599874 -482.193362) (xy 34.599874 -482.106462)
			(xy 34.607892 -482.019933) (xy 34.62386 -481.934513) (xy 34.647641 -481.850931) (xy 34.679033 -481.769899)
			(xy 34.717767 -481.69211) (xy 34.763514 -481.618226) (xy 34.815883 -481.548879) (xy 34.874427 -481.484659)
			(xy 34.938647 -481.426115) (xy 35.007994 -481.373746) (xy 35.081878 -481.327999) (xy 35.159667 -481.289265)
			(xy 35.240699 -481.257873) (xy 35.324281 -481.234092) (xy 35.409701 -481.218124) (xy 35.49623 -481.210106)
			(xy 35.58313 -481.210106) (xy 35.669659 -481.218124) (xy 35.755079 -481.234092) (xy 35.838661 -481.257873)
			(xy 35.919693 -481.289265) (xy 35.997482 -481.327999) (xy 36.071366 -481.373746) (xy 36.087042 -481.385584)
			(xy 38.205816 -481.385584) (xy 38.209706 -481.331235) (xy 38.221291 -481.277993) (xy 38.240335 -481.226941)
			(xy 38.266451 -481.17912) (xy 38.299107 -481.135502) (xy 38.337638 -481.096975) (xy 38.38126 -481.064325)
			(xy 38.429085 -481.038215) (xy 38.480139 -481.019177) (xy 38.533383 -481.007599) (xy 38.587732 -481.003716)
			(xy 38.642081 -481.007608) (xy 38.695323 -481.019195) (xy 38.746374 -481.038242) (xy 38.794194 -481.06436)
			(xy 38.81628 -481.080318) (xy 38.835292 -481.093914) (xy 38.877175 -481.114646) (xy 38.922143 -481.127372)
			(xy 38.96868 -481.131662) (xy 39.015217 -481.127372) (xy 39.060185 -481.114646) (xy 39.102068 -481.093914)
			(xy 39.12108 -481.080318) (xy 39.143144 -481.064321) (xy 39.190973 -481.038194) (xy 39.242033 -481.01914)
			(xy 39.295285 -481.007547) (xy 39.349645 -481.003651) (xy 39.404006 -481.007531) (xy 39.457262 -481.019109)
			(xy 39.508327 -481.038148) (xy 39.556163 -481.064262) (xy 39.599796 -481.096918) (xy 39.638336 -481.135451)
			(xy 39.671 -481.179077) (xy 39.697122 -481.226909) (xy 39.716171 -481.277971) (xy 39.727759 -481.331224)
			(xy 39.731649 -481.385584) (xy 40.092509 -481.385584) (xy 40.096399 -481.331234) (xy 40.107984 -481.27799)
			(xy 40.127029 -481.226937) (xy 40.153146 -481.179114) (xy 40.185803 -481.135495) (xy 40.224336 -481.096967)
			(xy 40.26796 -481.064316) (xy 40.315787 -481.038206) (xy 40.366842 -481.019169) (xy 40.420088 -481.007591)
			(xy 40.474439 -481.003709) (xy 40.52879 -481.007602) (xy 40.582033 -481.019191) (xy 40.633085 -481.038239)
			(xy 40.680906 -481.064359) (xy 40.702992 -481.080318) (xy 40.722004 -481.093914) (xy 40.763887 -481.114646)
			(xy 40.808855 -481.127372) (xy 40.855392 -481.131662) (xy 40.901929 -481.127372) (xy 40.946897 -481.114646)
			(xy 40.98878 -481.093914) (xy 41.007792 -481.080318) (xy 41.029856 -481.064322) (xy 41.077684 -481.038197)
			(xy 41.128743 -481.019144) (xy 41.181993 -481.007553) (xy 41.236352 -481.003658) (xy 41.290711 -481.007539)
			(xy 41.343965 -481.019117) (xy 41.395029 -481.038157) (xy 41.442863 -481.06427) (xy 41.486494 -481.096926)
			(xy 41.525033 -481.135458) (xy 41.557695 -481.179083) (xy 41.583817 -481.226913) (xy 41.602865 -481.277974)
			(xy 41.614452 -481.331226) (xy 41.618342 -481.385584) (xy 42.333484 -481.385584) (xy 42.337374 -481.331228)
			(xy 42.348961 -481.277979) (xy 42.368009 -481.22692) (xy 42.394129 -481.179093) (xy 42.426791 -481.13547)
			(xy 42.465329 -481.09694) (xy 42.508959 -481.064287) (xy 42.556792 -481.038176) (xy 42.607854 -481.019139)
			(xy 42.661106 -481.007563) (xy 42.715463 -481.003684) (xy 42.769819 -481.007581) (xy 42.823067 -481.019174)
			(xy 42.874123 -481.038228) (xy 42.921947 -481.064355) (xy 42.944034 -481.080318) (xy 42.963046 -481.093914)
			(xy 43.004929 -481.114646) (xy 43.049897 -481.127372) (xy 43.096434 -481.131662) (xy 43.142971 -481.127372)
			(xy 43.187939 -481.114646) (xy 43.229822 -481.093914) (xy 43.248834 -481.080318) (xy 43.270897 -481.064326)
			(xy 43.318722 -481.038207) (xy 43.369777 -481.019161) (xy 43.423023 -481.007574) (xy 43.477376 -481.003683)
			(xy 43.531729 -481.007567) (xy 43.584977 -481.019147) (xy 43.636034 -481.038187) (xy 43.683862 -481.0643)
			(xy 43.727487 -481.096953) (xy 43.766021 -481.135483) (xy 43.798679 -481.179104) (xy 43.824796 -481.22693)
			(xy 43.843842 -481.277985) (xy 43.855427 -481.331231) (xy 43.859317 -481.385584) (xy 44.237494 -481.385584)
			(xy 44.241383 -481.33123) (xy 44.25297 -481.277983) (xy 44.272016 -481.226927) (xy 44.298136 -481.179101)
			(xy 44.330796 -481.135479) (xy 44.369332 -481.09695) (xy 44.412959 -481.064298) (xy 44.46079 -481.038188)
			(xy 44.51185 -481.01915) (xy 44.565099 -481.007574) (xy 44.619454 -481.003694) (xy 44.673808 -481.007589)
			(xy 44.727054 -481.019181) (xy 44.778108 -481.038232) (xy 44.825931 -481.064356) (xy 44.848018 -481.080318)
			(xy 44.86703 -481.093914) (xy 44.908913 -481.114646) (xy 44.953881 -481.127372) (xy 45.000418 -481.131662)
			(xy 45.046955 -481.127372) (xy 45.091923 -481.114646) (xy 45.133806 -481.093914) (xy 45.152818 -481.080318)
			(xy 45.174881 -481.064325) (xy 45.222707 -481.038203) (xy 45.273764 -481.019154) (xy 45.327012 -481.007566)
			(xy 45.381367 -481.003673) (xy 45.435722 -481.007556) (xy 45.488972 -481.019136) (xy 45.540032 -481.038176)
			(xy 45.587862 -481.064288) (xy 45.63149 -481.096943) (xy 45.670025 -481.135473) (xy 45.702685 -481.179096)
			(xy 45.728804 -481.226923) (xy 45.747851 -481.277981) (xy 45.759437 -481.331229) (xy 45.763327 -481.385584)
			(xy 45.759441 -481.43994) (xy 45.747859 -481.493189) (xy 45.728817 -481.544248) (xy 45.702702 -481.592077)
			(xy 45.670046 -481.635703) (xy 45.631513 -481.674237) (xy 45.587889 -481.706895) (xy 45.54006 -481.733012)
			(xy 45.489002 -481.752056) (xy 45.435753 -481.763639) (xy 45.381398 -481.767527) (xy 45.327042 -481.763639)
			(xy 45.273794 -481.752054) (xy 45.222736 -481.73301) (xy 45.174908 -481.706892) (xy 45.152818 -481.690934)
			(xy 45.133806 -481.677338) (xy 45.091923 -481.656606) (xy 45.046955 -481.64388) (xy 45.000418 -481.63959)
			(xy 44.953881 -481.64388) (xy 44.908913 -481.656606) (xy 44.86703 -481.677338) (xy 44.848018 -481.690934)
			(xy 44.825905 -481.70686) (xy 44.77808 -481.732981) (xy 44.727024 -481.752028) (xy 44.673777 -481.763616)
			(xy 44.619423 -481.767506) (xy 44.565068 -481.763622) (xy 44.51182 -481.752041) (xy 44.460761 -481.732999)
			(xy 44.412933 -481.706885) (xy 44.369308 -481.674229) (xy 44.330776 -481.635697) (xy 44.298119 -481.592073)
			(xy 44.272003 -481.544245) (xy 44.252961 -481.493187) (xy 44.241379 -481.439939) (xy 44.237494 -481.385584)
			(xy 43.859317 -481.385584) (xy 43.855432 -481.439938) (xy 43.843851 -481.493185) (xy 43.824809 -481.544242)
			(xy 43.798696 -481.592069) (xy 43.766041 -481.635694) (xy 43.727511 -481.674226) (xy 43.683888 -481.706884)
			(xy 43.636062 -481.733) (xy 43.585007 -481.752044) (xy 43.53176 -481.763628) (xy 43.477407 -481.767517)
			(xy 43.423054 -481.76363) (xy 43.369807 -481.752048) (xy 43.31875 -481.733006) (xy 43.270923 -481.706891)
			(xy 43.248834 -481.690934) (xy 43.229822 -481.677338) (xy 43.187939 -481.656606) (xy 43.142971 -481.64388)
			(xy 43.096434 -481.63959) (xy 43.049897 -481.64388) (xy 43.004929 -481.656606) (xy 42.963046 -481.677338)
			(xy 42.944034 -481.690934) (xy 42.921921 -481.706862) (xy 42.874094 -481.732985) (xy 42.823037 -481.752034)
			(xy 42.769788 -481.763624) (xy 42.715432 -481.767516) (xy 42.661075 -481.763633) (xy 42.607824 -481.752052)
			(xy 42.556763 -481.733011) (xy 42.508933 -481.706896) (xy 42.465306 -481.67424) (xy 42.426771 -481.635706)
			(xy 42.394113 -481.592081) (xy 42.367996 -481.544251) (xy 42.348952 -481.493191) (xy 42.33737 -481.439941)
			(xy 42.333484 -481.385584) (xy 41.618342 -481.385584) (xy 41.614456 -481.439944) (xy 41.602874 -481.493196)
			(xy 41.58383 -481.544258) (xy 41.557712 -481.59209) (xy 41.525053 -481.635718) (xy 41.486517 -481.674254)
			(xy 41.442889 -481.706913) (xy 41.395057 -481.73303) (xy 41.343995 -481.752074) (xy 41.290742 -481.763657)
			(xy 41.236383 -481.767542) (xy 41.182024 -481.763652) (xy 41.128772 -481.752064) (xy 41.077712 -481.733016)
			(xy 41.029882 -481.706895) (xy 41.007792 -481.690934) (xy 40.98878 -481.677338) (xy 40.946897 -481.656606)
			(xy 40.901929 -481.64388) (xy 40.855392 -481.63959) (xy 40.808855 -481.64388) (xy 40.763887 -481.656606)
			(xy 40.722004 -481.677338) (xy 40.702992 -481.690934) (xy 40.68088 -481.706858) (xy 40.633056 -481.732974)
			(xy 40.582003 -481.752018) (xy 40.528759 -481.763602) (xy 40.474408 -481.767491) (xy 40.420057 -481.763605)
			(xy 40.366812 -481.752023) (xy 40.315758 -481.732981) (xy 40.267934 -481.706867) (xy 40.224313 -481.674212)
			(xy 40.185783 -481.635682) (xy 40.153129 -481.59206) (xy 40.127016 -481.544235) (xy 40.107975 -481.49318)
			(xy 40.096394 -481.439935) (xy 40.092509 -481.385584) (xy 39.731649 -481.385584) (xy 39.727763 -481.439945)
			(xy 39.71618 -481.493199) (xy 39.697135 -481.544263) (xy 39.671017 -481.592096) (xy 39.638357 -481.635725)
			(xy 39.599819 -481.674262) (xy 39.556189 -481.706921) (xy 39.508356 -481.733039) (xy 39.457292 -481.752082)
			(xy 39.404037 -481.763665) (xy 39.349676 -481.767549) (xy 39.295316 -481.763658) (xy 39.242063 -481.752069)
			(xy 39.191001 -481.733019) (xy 39.143171 -481.706896) (xy 39.12108 -481.690934) (xy 39.102068 -481.677338)
			(xy 39.060185 -481.656606) (xy 39.015217 -481.64388) (xy 38.96868 -481.63959) (xy 38.922143 -481.64388)
			(xy 38.877175 -481.656606) (xy 38.835292 -481.677338) (xy 38.81628 -481.690934) (xy 38.794168 -481.706857)
			(xy 38.746345 -481.732971) (xy 38.695293 -481.752014) (xy 38.64205 -481.763596) (xy 38.587701 -481.767484)
			(xy 38.533352 -481.763597) (xy 38.480109 -481.752014) (xy 38.429057 -481.732972) (xy 38.381234 -481.706858)
			(xy 38.337614 -481.674204) (xy 38.299086 -481.635675) (xy 38.266434 -481.592054) (xy 38.240322 -481.54423)
			(xy 38.221282 -481.493177) (xy 38.209701 -481.439934) (xy 38.205816 -481.385584) (xy 36.087042 -481.385584)
			(xy 36.140713 -481.426115) (xy 36.204933 -481.484659) (xy 36.263477 -481.548879) (xy 36.315846 -481.618226)
			(xy 36.361593 -481.69211) (xy 36.400327 -481.769899) (xy 36.431719 -481.850931) (xy 36.440181 -481.880672)
			(xy 51.007772 -481.880672) (xy 52.65928 -481.880672) (xy 52.65928 -483.08133) (xy 69.041264 -483.08133)
			(xy 69.041264 -482.175058) (xy 69.041678 -482.142878) (xy 69.049795 -482.079031) (xy 69.065907 -482.016719)
			(xy 69.089755 -481.95694) (xy 69.120959 -481.900649) (xy 69.159019 -481.848748) (xy 69.203327 -481.802066)
			(xy 69.253172 -481.761351) (xy 69.307759 -481.727254) (xy 69.366213 -481.70032) (xy 69.427599 -481.68098)
			(xy 69.490936 -481.669544) (xy 69.55521 -481.666195) (xy 69.619392 -481.670986) (xy 69.682456 -481.68384)
			(xy 69.743393 -481.704552) (xy 69.801228 -481.732791) (xy 69.855036 -481.768105) (xy 69.903955 -481.809929)
			(xy 69.925946 -481.833428) (xy 69.942164 -481.850507) (xy 69.979713 -481.878928) (xy 70.021853 -481.899952)
			(xy 70.067142 -481.912861) (xy 70.114033 -481.917214) (xy 70.160924 -481.912861) (xy 70.206213 -481.899952)
			(xy 70.248353 -481.878928) (xy 70.285902 -481.850507) (xy 70.30212 -481.833428) (xy 70.324457 -481.809594)
			(xy 70.374184 -481.767237) (xy 70.428928 -481.7316) (xy 70.487786 -481.70327) (xy 70.549788 -481.682713)
			(xy 70.613913 -481.670267) (xy 70.679104 -481.666139) (xy 70.744286 -481.670396) (xy 70.808386 -481.682969)
			(xy 70.870348 -481.703649) (xy 70.92915 -481.732096) (xy 70.983823 -481.767841) (xy 71.033466 -481.810296)
			(xy 71.055738 -481.83419) (xy 71.071968 -481.851371) (xy 71.109587 -481.879975) (xy 71.151842 -481.90114)
			(xy 71.197278 -481.914137) (xy 71.244333 -481.91852) (xy 71.291388 -481.914137) (xy 71.336824 -481.90114)
			(xy 71.379079 -481.879975) (xy 71.416698 -481.851371) (xy 71.432928 -481.83419) (xy 71.455126 -481.810509)
			(xy 71.50443 -481.768295) (xy 71.558705 -481.732699) (xy 71.61707 -481.704301) (xy 71.678574 -481.683563)
			(xy 71.742217 -481.670821) (xy 71.806965 -481.666283) (xy 71.871764 -481.670023) (xy 71.93556 -481.68198)
			(xy 71.997315 -481.701959) (xy 72.056025 -481.729636) (xy 72.110735 -481.76456) (xy 72.160554 -481.806163)
			(xy 72.18299 -481.829618) (xy 72.199189 -481.846337) (xy 72.236509 -481.874156) (xy 72.278269 -481.894718)
			(xy 72.323073 -481.907336) (xy 72.369426 -481.91159) (xy 72.415779 -481.907336) (xy 72.460583 -481.894718)
			(xy 72.502343 -481.874156) (xy 72.539663 -481.846337) (xy 72.555862 -481.829618) (xy 72.578 -481.806456)
			(xy 72.62711 -481.765304) (xy 72.681003 -481.730651) (xy 72.738824 -481.703045) (xy 72.799655 -481.682925)
			(xy 72.862533 -481.67061) (xy 72.92646 -481.666294) (xy 72.990422 -481.670047) (xy 73.053406 -481.681808)
			(xy 73.114412 -481.701392) (xy 73.172474 -481.728487) (xy 73.22667 -481.762665) (xy 73.27614 -481.803383)
			(xy 73.320102 -481.849995) (xy 73.357856 -481.901762) (xy 73.388806 -481.957864) (xy 73.412459 -482.017411)
			(xy 73.428441 -482.079458) (xy 73.436499 -482.143022) (xy 73.436988 -482.175058) (xy 73.436988 -482.565456)
			(xy 92.659706 -482.565456) (xy 92.663777 -482.509834) (xy 92.675903 -482.455397) (xy 92.695826 -482.403306)
			(xy 92.723122 -482.354671) (xy 92.757208 -482.310528) (xy 92.797357 -482.271819) (xy 92.842715 -482.239368)
			(xy 92.892315 -482.213867) (xy 92.945099 -482.19586) (xy 92.999942 -482.18573) (xy 93.055676 -482.183693)
			(xy 93.111113 -482.189793) (xy 93.16507 -482.203899) (xy 93.216399 -482.225711) (xy 93.264005 -482.254765)
			(xy 93.306873 -482.29044) (xy 93.34409 -482.331977) (xy 93.374863 -482.37849) (xy 93.398535 -482.428987)
			(xy 93.414603 -482.482394) (xy 93.422723 -482.53757) (xy 93.423232 -482.565456) (xy 93.422723 -482.593342)
			(xy 93.414603 -482.648518) (xy 93.398535 -482.701925) (xy 93.374863 -482.752422) (xy 93.34409 -482.798935)
			(xy 93.306873 -482.840472) (xy 93.264005 -482.876147) (xy 93.216399 -482.905201) (xy 93.16507 -482.927013)
			(xy 93.111113 -482.941119) (xy 93.055676 -482.947219) (xy 92.999942 -482.945182) (xy 92.945099 -482.935052)
			(xy 92.892315 -482.917045) (xy 92.842715 -482.891544) (xy 92.797357 -482.859093) (xy 92.757208 -482.820384)
			(xy 92.723122 -482.776241) (xy 92.695826 -482.727606) (xy 92.675903 -482.675515) (xy 92.663777 -482.621078)
			(xy 92.659706 -482.565456) (xy 73.436988 -482.565456) (xy 73.436988 -482.954838) (xy 94.723456 -482.954838)
			(xy 94.727527 -482.899216) (xy 94.739653 -482.844779) (xy 94.759576 -482.792688) (xy 94.786872 -482.744053)
			(xy 94.820958 -482.69991) (xy 94.861107 -482.661201) (xy 94.906465 -482.62875) (xy 94.956065 -482.603249)
			(xy 95.008849 -482.585242) (xy 95.063692 -482.575112) (xy 95.119426 -482.573075) (xy 95.174863 -482.579175)
			(xy 95.22882 -482.593281) (xy 95.280149 -482.615093) (xy 95.327755 -482.644147) (xy 95.370623 -482.679822)
			(xy 95.40784 -482.721359) (xy 95.438613 -482.767872) (xy 95.462285 -482.818369) (xy 95.478353 -482.871776)
			(xy 95.486473 -482.926952) (xy 95.486982 -482.954838) (xy 95.486473 -482.982724) (xy 95.478353 -483.0379)
			(xy 95.462285 -483.091307) (xy 95.438613 -483.141804) (xy 95.40784 -483.188317) (xy 95.370623 -483.229854)
			(xy 95.327755 -483.265529) (xy 95.280149 -483.294583) (xy 95.22882 -483.316395) (xy 95.174863 -483.330501)
			(xy 95.119426 -483.336601) (xy 95.063692 -483.334564) (xy 95.008849 -483.324434) (xy 94.956065 -483.306427)
			(xy 94.906465 -483.280926) (xy 94.861107 -483.248475) (xy 94.820958 -483.209766) (xy 94.786872 -483.165623)
			(xy 94.759576 -483.116988) (xy 94.739653 -483.064897) (xy 94.727527 -483.01046) (xy 94.723456 -482.954838)
			(xy 73.436988 -482.954838) (xy 73.436988 -483.08133) (xy 73.436458 -483.114055) (xy 73.428072 -483.178967)
			(xy 73.411429 -483.242266) (xy 73.386804 -483.302907) (xy 73.354604 -483.359889) (xy 73.335388 -483.386384)
			(xy 73.309988 -483.420166) (xy 73.309988 -483.437184) (xy 73.294748 -483.437184) (xy 73.258934 -483.467664)
			(xy 73.233757 -483.488517) (xy 73.179025 -483.524268) (xy 73.12016 -483.552707) (xy 73.058135 -483.573362)
			(xy 72.993973 -483.585893) (xy 72.928734 -483.590093) (xy 72.863495 -483.585893) (xy 72.799333 -483.573362)
			(xy 72.737308 -483.552707) (xy 72.678443 -483.524268) (xy 72.623711 -483.488517) (xy 72.598534 -483.467664)
			(xy 72.56272 -483.437184) (xy 72.54748 -483.437184) (xy 72.54748 -483.420166) (xy 72.52208 -483.386384)
			(xy 72.510818 -483.371136) (xy 72.49035 -483.339224) (xy 72.481186 -483.32263) (xy 72.473583 -483.309453)
			(xy 72.453227 -483.286859) (xy 72.428095 -483.269733) (xy 72.399621 -483.259051) (xy 72.369426 -483.255421)
			(xy 72.339231 -483.259051) (xy 72.310757 -483.269733) (xy 72.285625 -483.286859) (xy 72.265269 -483.309453)
			(xy 72.257666 -483.32263) (xy 72.248495 -483.33922) (xy 72.228024 -483.371129) (xy 72.216772 -483.386384)
			(xy 72.191372 -483.420166) (xy 72.191372 -483.437184) (xy 72.176132 -483.437184) (xy 72.140318 -483.467664)
			(xy 72.115141 -483.488517) (xy 72.060409 -483.524268) (xy 72.001544 -483.552707) (xy 71.939519 -483.573362)
			(xy 71.875357 -483.585893) (xy 71.810118 -483.590093) (xy 71.744879 -483.585893) (xy 71.680717 -483.573362)
			(xy 71.618692 -483.552707) (xy 71.559827 -483.524268) (xy 71.505095 -483.488517) (xy 71.479918 -483.467664)
			(xy 71.444104 -483.437184) (xy 71.428864 -483.437184) (xy 71.428864 -483.420166) (xy 71.403464 -483.386384)
			(xy 71.390613 -483.368851) (xy 71.367591 -483.331973) (xy 71.35749 -483.312724) (xy 71.350052 -483.299063)
			(xy 71.329678 -483.275573) (xy 71.304221 -483.257717) (xy 71.275196 -483.246559) (xy 71.244333 -483.242765)
			(xy 71.21347 -483.246559) (xy 71.184445 -483.257717) (xy 71.158988 -483.275573) (xy 71.138614 -483.299063)
			(xy 71.131176 -483.312724) (xy 71.121084 -483.331978) (xy 71.098064 -483.368859) (xy 71.085202 -483.386384)
			(xy 71.060056 -483.420166) (xy 71.060056 -483.437184) (xy 71.044562 -483.437184) (xy 71.008748 -483.467664)
			(xy 70.983571 -483.488517) (xy 70.928839 -483.524268) (xy 70.869974 -483.552707) (xy 70.807949 -483.573362)
			(xy 70.743787 -483.585893) (xy 70.678548 -483.590093) (xy 70.613309 -483.585893) (xy 70.549147 -483.573362)
			(xy 70.487122 -483.552707) (xy 70.428257 -483.524268) (xy 70.373525 -483.488517) (xy 70.348348 -483.467664)
			(xy 70.312534 -483.437184) (xy 70.29704 -483.437184) (xy 70.29704 -483.420166) (xy 70.271894 -483.386384)
			(xy 70.259356 -483.369325) (xy 70.236849 -483.333463) (xy 70.226936 -483.314756) (xy 70.219473 -483.301181)
			(xy 70.199099 -483.277855) (xy 70.173699 -483.260133) (xy 70.144774 -483.249063) (xy 70.114033 -483.245299)
			(xy 70.083292 -483.249063) (xy 70.054367 -483.260133) (xy 70.028967 -483.277855) (xy 70.008593 -483.301181)
			(xy 70.00113 -483.314756) (xy 69.99121 -483.333459) (xy 69.968701 -483.369319) (xy 69.956172 -483.386384)
			(xy 69.930772 -483.420166) (xy 69.930772 -483.437184) (xy 69.915532 -483.437184) (xy 69.879718 -483.467664)
			(xy 69.854541 -483.488517) (xy 69.799809 -483.524268) (xy 69.740944 -483.552707) (xy 69.678919 -483.573362)
			(xy 69.614757 -483.585893) (xy 69.549518 -483.590093) (xy 69.484279 -483.585893) (xy 69.420117 -483.573362)
			(xy 69.358092 -483.552707) (xy 69.299227 -483.524268) (xy 69.244495 -483.488517) (xy 69.219318 -483.467664)
			(xy 69.183504 -483.437184) (xy 69.168264 -483.437184) (xy 69.168264 -483.420166) (xy 69.142864 -483.386384)
			(xy 69.123618 -483.359907) (xy 69.091392 -483.302932) (xy 69.066754 -483.242288) (xy 69.050115 -483.17898)
			(xy 69.04175 -483.114059) (xy 69.041264 -483.08133) (xy 52.65928 -483.08133) (xy 52.65928 -483.532688)
			(xy 51.007772 -483.532688) (xy 51.007772 -481.880672) (xy 36.440181 -481.880672) (xy 36.4555 -481.934513)
			(xy 36.471468 -482.019933) (xy 36.479486 -482.106462) (xy 36.479988 -482.149912) (xy 36.479486 -482.193362)
			(xy 36.471468 -482.279891) (xy 36.4555 -482.365311) (xy 36.431719 -482.448893) (xy 36.400327 -482.529925)
			(xy 36.361593 -482.607714) (xy 36.315846 -482.681598) (xy 36.266279 -482.747235) (xy 47.507896 -482.747235)
			(xy 47.507896 -482.666125) (xy 47.515846 -482.585406) (xy 47.531669 -482.505855) (xy 47.555214 -482.428239)
			(xy 47.586253 -482.353303) (xy 47.624488 -482.281771) (xy 47.66955 -482.214331) (xy 47.721005 -482.151632)
			(xy 47.778358 -482.094279) (xy 47.841057 -482.042824) (xy 47.908497 -481.997762) (xy 47.980029 -481.959527)
			(xy 48.054965 -481.928488) (xy 48.132581 -481.904943) (xy 48.212132 -481.88912) (xy 48.292851 -481.88117)
			(xy 48.373961 -481.88117) (xy 48.45468 -481.88912) (xy 48.534231 -481.904943) (xy 48.611847 -481.928488)
			(xy 48.686783 -481.959527) (xy 48.758315 -481.997762) (xy 48.825755 -482.042824) (xy 48.888454 -482.094279)
			(xy 48.945807 -482.151632) (xy 48.997262 -482.214331) (xy 49.042324 -482.281771) (xy 49.080559 -482.353303)
			(xy 49.111598 -482.428239) (xy 49.135143 -482.505855) (xy 49.150966 -482.585406) (xy 49.158916 -482.666125)
			(xy 49.159414 -482.70668) (xy 49.158916 -482.747235) (xy 49.150966 -482.827954) (xy 49.135143 -482.907505)
			(xy 49.111598 -482.985121) (xy 49.080559 -483.060057) (xy 49.042324 -483.131589) (xy 48.997262 -483.199029)
			(xy 48.945807 -483.261728) (xy 48.888454 -483.319081) (xy 48.825755 -483.370536) (xy 48.758315 -483.415598)
			(xy 48.686783 -483.453833) (xy 48.611847 -483.484872) (xy 48.534231 -483.508417) (xy 48.45468 -483.52424)
			(xy 48.373961 -483.53219) (xy 48.292851 -483.53219) (xy 48.212132 -483.52424) (xy 48.132581 -483.508417)
			(xy 48.054965 -483.484872) (xy 47.980029 -483.453833) (xy 47.908497 -483.415598) (xy 47.841057 -483.370536)
			(xy 47.778358 -483.319081) (xy 47.721005 -483.261728) (xy 47.66955 -483.199029) (xy 47.624488 -483.131589)
			(xy 47.586253 -483.060057) (xy 47.555214 -482.985121) (xy 47.531669 -482.907505) (xy 47.515846 -482.827954)
			(xy 47.507896 -482.747235) (xy 36.266279 -482.747235) (xy 36.263477 -482.750945) (xy 36.204933 -482.815165)
			(xy 36.140713 -482.873709) (xy 36.071366 -482.926078) (xy 35.997482 -482.971825) (xy 35.919693 -483.010559)
			(xy 35.838661 -483.041951) (xy 35.755079 -483.065732) (xy 35.669659 -483.0817) (xy 35.58313 -483.089718)
			(xy 35.49623 -483.089718) (xy 35.409701 -483.0817) (xy 35.324281 -483.065732) (xy 35.240699 -483.041951)
			(xy 35.159667 -483.010559) (xy 35.081878 -482.971825) (xy 35.007994 -482.926078) (xy 34.938647 -482.873709)
			(xy 34.874427 -482.815165) (xy 34.815883 -482.750945) (xy 34.763514 -482.681598) (xy 34.717767 -482.607714)
			(xy 34.679033 -482.529925) (xy 34.647641 -482.448893) (xy 34.62386 -482.365311) (xy 34.607892 -482.279891)
			(xy 34.599874 -482.193362) (xy 31.399486 -482.193362) (xy 31.391468 -482.279891) (xy 31.3755 -482.365311)
			(xy 31.351719 -482.448893) (xy 31.320327 -482.529925) (xy 31.281593 -482.607714) (xy 31.235846 -482.681598)
			(xy 31.183477 -482.750945) (xy 31.124933 -482.815165) (xy 31.060713 -482.873709) (xy 30.991366 -482.926078)
			(xy 30.917482 -482.971825) (xy 30.839693 -483.010559) (xy 30.758661 -483.041951) (xy 30.675079 -483.065732)
			(xy 30.589659 -483.0817) (xy 30.50313 -483.089718) (xy 30.41623 -483.089718) (xy 30.329701 -483.0817)
			(xy 30.244281 -483.065732) (xy 30.160699 -483.041951) (xy 30.079667 -483.010559) (xy 30.001878 -482.971825)
			(xy 29.927994 -482.926078) (xy 29.858647 -482.873709) (xy 29.794427 -482.815165) (xy 29.735883 -482.750945)
			(xy 29.683514 -482.681598) (xy 29.637767 -482.607714) (xy 29.599033 -482.529925) (xy 29.567641 -482.448893)
			(xy 29.54386 -482.365311) (xy 29.527892 -482.279891) (xy 29.519874 -482.193362) (xy 2.08026 -482.193362)
			(xy 2.08026 -483.276071) (xy 38.205834 -483.276071) (xy 38.209725 -483.221725) (xy 38.221311 -483.168485)
			(xy 38.240356 -483.117437) (xy 38.266473 -483.069618) (xy 38.299129 -483.026003) (xy 38.33766 -482.98748)
			(xy 38.381281 -482.954832) (xy 38.429104 -482.928725) (xy 38.480157 -482.90969) (xy 38.533398 -482.898114)
			(xy 38.587745 -482.894234) (xy 38.642092 -482.898127) (xy 38.695331 -482.909716) (xy 38.746378 -482.928763)
			(xy 38.794196 -482.954882) (xy 38.81628 -482.97084) (xy 38.835292 -482.984436) (xy 38.877175 -483.005168)
			(xy 38.922143 -483.017894) (xy 38.96868 -483.022184) (xy 39.015217 -483.017894) (xy 39.060185 -483.005168)
			(xy 39.102068 -482.984436) (xy 39.12108 -482.97084) (xy 39.143124 -482.954814) (xy 39.190953 -482.928683)
			(xy 39.242015 -482.909627) (xy 39.295269 -482.898031) (xy 39.349632 -482.894133) (xy 39.403996 -482.898012)
			(xy 39.457254 -482.909588) (xy 39.508323 -482.928627) (xy 39.556162 -482.95474) (xy 39.599797 -482.987396)
			(xy 39.638341 -483.02593) (xy 39.671008 -483.069557) (xy 39.697133 -483.117389) (xy 39.716184 -483.168453)
			(xy 39.727774 -483.221708) (xy 39.731667 -483.276071) (xy 40.092527 -483.276071) (xy 40.096418 -483.221723)
			(xy 40.108005 -483.168482) (xy 40.12705 -483.117432) (xy 40.153168 -483.069612) (xy 40.185825 -483.025996)
			(xy 40.224358 -482.987472) (xy 40.267981 -482.954824) (xy 40.315806 -482.928717) (xy 40.36686 -482.909682)
			(xy 40.420103 -482.898106) (xy 40.474452 -482.894227) (xy 40.5288 -482.898121) (xy 40.58204 -482.909711)
			(xy 40.633089 -482.92876) (xy 40.680907 -482.954881) (xy 40.702992 -482.97084) (xy 40.722004 -482.984436)
			(xy 40.763887 -483.005168) (xy 40.808855 -483.017894) (xy 40.855392 -483.022184) (xy 40.901929 -483.017894)
			(xy 40.946897 -483.005168) (xy 40.98878 -482.984436) (xy 41.007792 -482.97084) (xy 41.029835 -482.954815)
			(xy 41.077664 -482.928686) (xy 41.128725 -482.909631) (xy 41.181978 -482.898037) (xy 41.236339 -482.89414)
			(xy 41.290701 -482.89802) (xy 41.343957 -482.909597) (xy 41.395024 -482.928635) (xy 41.442861 -482.954748)
			(xy 41.486495 -482.987404) (xy 41.525037 -483.025937) (xy 41.557703 -483.069563) (xy 41.583827 -483.117394)
			(xy 41.602878 -483.168456) (xy 41.614467 -483.22171) (xy 41.61836 -483.276071) (xy 42.333502 -483.276071)
			(xy 42.337393 -483.221717) (xy 42.348982 -483.168471) (xy 42.36803 -483.117416) (xy 42.394151 -483.069591)
			(xy 42.426813 -483.025972) (xy 42.465351 -482.987445) (xy 42.50898 -482.954795) (xy 42.556811 -482.928687)
			(xy 42.607872 -482.909652) (xy 42.661121 -482.898078) (xy 42.715476 -482.894202) (xy 42.769829 -482.8981)
			(xy 42.823075 -482.909695) (xy 42.874127 -482.92875) (xy 42.921948 -482.954877) (xy 42.944034 -482.97084)
			(xy 42.963046 -482.984436) (xy 43.004929 -483.005168) (xy 43.049897 -483.017894) (xy 43.096434 -483.022184)
			(xy 43.142971 -483.017894) (xy 43.187939 -483.005168) (xy 43.229822 -482.984436) (xy 43.248834 -482.97084)
			(xy 43.270876 -482.954818) (xy 43.318702 -482.928697) (xy 43.369759 -482.909647) (xy 43.423007 -482.898058)
			(xy 43.477362 -482.894165) (xy 43.531719 -482.898048) (xy 43.584969 -482.909626) (xy 43.636029 -482.928665)
			(xy 43.683861 -482.954778) (xy 43.727489 -482.987431) (xy 43.766025 -483.025961) (xy 43.798687 -483.069584)
			(xy 43.824807 -483.11741) (xy 43.843855 -483.168467) (xy 43.855443 -483.221716) (xy 43.859335 -483.276071)
			(xy 44.237511 -483.276071) (xy 44.241403 -483.22172) (xy 44.25299 -483.168475) (xy 44.272038 -483.117422)
			(xy 44.298158 -483.069599) (xy 44.330818 -483.025981) (xy 44.369354 -482.987455) (xy 44.41298 -482.954806)
			(xy 44.460809 -482.928698) (xy 44.511867 -482.909663) (xy 44.565115 -482.898089) (xy 44.619467 -482.894211)
			(xy 44.673818 -482.898108) (xy 44.727062 -482.909701) (xy 44.778113 -482.928754) (xy 44.825933 -482.954878)
			(xy 44.848018 -482.97084) (xy 44.86703 -482.984436) (xy 44.908913 -483.005168) (xy 44.953881 -483.017894)
			(xy 45.000418 -483.022184) (xy 45.046955 -483.017894) (xy 45.091923 -483.005168) (xy 45.133806 -482.984436)
			(xy 45.152818 -482.97084) (xy 45.174861 -482.954817) (xy 45.222688 -482.928693) (xy 45.273746 -482.909641)
			(xy 45.326996 -482.89805) (xy 45.381353 -482.894156) (xy 45.435712 -482.898037) (xy 45.488964 -482.909615)
			(xy 45.540027 -482.928654) (xy 45.587861 -482.954766) (xy 45.631491 -482.987421) (xy 45.67003 -483.025952)
			(xy 45.702693 -483.069576) (xy 45.728815 -483.117404) (xy 45.747864 -483.168463) (xy 45.759452 -483.221714)
			(xy 45.763344 -483.276071) (xy 45.75946 -483.330429) (xy 45.74788 -483.383682) (xy 45.728839 -483.434744)
			(xy 45.702724 -483.482576) (xy 45.670068 -483.526205) (xy 45.631535 -483.564742) (xy 45.587909 -483.597402)
			(xy 45.54008 -483.623522) (xy 45.48902 -483.642569) (xy 45.435769 -483.654155) (xy 45.381411 -483.658044)
			(xy 45.327053 -483.654158) (xy 45.273801 -483.642575) (xy 45.22274 -483.623531) (xy 45.174909 -483.597414)
			(xy 45.152818 -483.581456) (xy 45.133806 -483.56786) (xy 45.091923 -483.547128) (xy 45.046955 -483.534402)
			(xy 45.000418 -483.530112) (xy 44.953881 -483.534402) (xy 44.908913 -483.547128) (xy 44.86703 -483.56786)
			(xy 44.848018 -483.581456) (xy 44.825884 -483.597353) (xy 44.77806 -483.62347) (xy 44.727006 -483.642515)
			(xy 44.673761 -483.6541) (xy 44.619409 -483.657989) (xy 44.565057 -483.654103) (xy 44.511812 -483.64252)
			(xy 44.460757 -483.623478) (xy 44.412932 -483.597363) (xy 44.36931 -483.564707) (xy 44.33078 -483.526175)
			(xy 44.298127 -483.482552) (xy 44.272014 -483.434726) (xy 44.252974 -483.38367) (xy 44.241395 -483.330423)
			(xy 44.237511 -483.276071) (xy 43.859335 -483.276071) (xy 43.855451 -483.330427) (xy 43.843871 -483.383677)
			(xy 43.824831 -483.434737) (xy 43.798718 -483.482568) (xy 43.766063 -483.526195) (xy 43.727532 -483.564731)
			(xy 43.683909 -483.597391) (xy 43.636082 -483.623511) (xy 43.585024 -483.642557) (xy 43.531776 -483.654144)
			(xy 43.47742 -483.658035) (xy 43.423064 -483.65415) (xy 43.369814 -483.642569) (xy 43.318755 -483.623527)
			(xy 43.270925 -483.597413) (xy 43.248834 -483.581456) (xy 43.229822 -483.56786) (xy 43.187939 -483.547128)
			(xy 43.142971 -483.534402) (xy 43.096434 -483.530112) (xy 43.049897 -483.534402) (xy 43.004929 -483.547128)
			(xy 42.963046 -483.56786) (xy 42.944034 -483.581456) (xy 42.9219 -483.597354) (xy 42.874075 -483.623474)
			(xy 42.823019 -483.642521) (xy 42.769772 -483.654108) (xy 42.715419 -483.657998) (xy 42.661064 -483.654113)
			(xy 42.607816 -483.642532) (xy 42.556759 -483.623489) (xy 42.508931 -483.597374) (xy 42.465307 -483.564718)
			(xy 42.426776 -483.526185) (xy 42.39412 -483.48256) (xy 42.368006 -483.434732) (xy 42.348965 -483.383674)
			(xy 42.337385 -483.330426) (xy 42.333502 -483.276071) (xy 41.61836 -483.276071) (xy 41.614476 -483.330433)
			(xy 41.602894 -483.383689) (xy 41.583851 -483.434754) (xy 41.557734 -483.482589) (xy 41.525075 -483.52622)
			(xy 41.486539 -483.564759) (xy 41.44291 -483.597421) (xy 41.395076 -483.623541) (xy 41.344013 -483.642587)
			(xy 41.290758 -483.654172) (xy 41.236396 -483.65806) (xy 41.182035 -483.654171) (xy 41.12878 -483.642585)
			(xy 41.077717 -483.623538) (xy 41.029884 -483.597417) (xy 41.007792 -483.581456) (xy 40.98878 -483.56786)
			(xy 40.946897 -483.547128) (xy 40.901929 -483.534402) (xy 40.855392 -483.530112) (xy 40.808855 -483.534402)
			(xy 40.763887 -483.547128) (xy 40.722004 -483.56786) (xy 40.702992 -483.581456) (xy 40.680859 -483.597351)
			(xy 40.633037 -483.623464) (xy 40.581985 -483.642505) (xy 40.528743 -483.654087) (xy 40.474395 -483.657973)
			(xy 40.420046 -483.654085) (xy 40.366805 -483.642502) (xy 40.315753 -483.623459) (xy 40.267932 -483.597345)
			(xy 40.224314 -483.56469) (xy 40.185788 -483.52616) (xy 40.153137 -483.482539) (xy 40.127027 -483.434716)
			(xy 40.107988 -483.383663) (xy 40.09641 -483.33042) (xy 40.092527 -483.276071) (xy 39.731667 -483.276071)
			(xy 39.727783 -483.330435) (xy 39.716201 -483.383692) (xy 39.697157 -483.434758) (xy 39.671039 -483.482595)
			(xy 39.638378 -483.526227) (xy 39.599841 -483.564767) (xy 39.55621 -483.597429) (xy 39.508375 -483.623549)
			(xy 39.457309 -483.642596) (xy 39.404053 -483.65418) (xy 39.349689 -483.658067) (xy 39.295326 -483.654177)
			(xy 39.24207 -483.64259) (xy 39.191006 -483.62354) (xy 39.143172 -483.597418) (xy 39.12108 -483.581456)
			(xy 39.102068 -483.56786) (xy 39.060185 -483.547128) (xy 39.015217 -483.534402) (xy 38.96868 -483.530112)
			(xy 38.922143 -483.534402) (xy 38.877175 -483.547128) (xy 38.835292 -483.56786) (xy 38.81628 -483.581456)
			(xy 38.794147 -483.59735) (xy 38.746326 -483.623461) (xy 38.695275 -483.6425) (xy 38.642035 -483.654081)
			(xy 38.587688 -483.657966) (xy 38.533341 -483.654077) (xy 38.480101 -483.642494) (xy 38.429052 -483.623451)
			(xy 38.381232 -483.597336) (xy 38.337616 -483.564682) (xy 38.299091 -483.526153) (xy 38.266441 -483.482533)
			(xy 38.240332 -483.434711) (xy 38.221295 -483.383659) (xy 38.209717 -483.330418) (xy 38.205834 -483.276071)
			(xy 2.08026 -483.276071) (xy 2.08026 -484.733362) (xy 29.519874 -484.733362) (xy 29.519874 -484.646462)
			(xy 29.527892 -484.559933) (xy 29.54386 -484.474513) (xy 29.567641 -484.390931) (xy 29.599033 -484.309899)
			(xy 29.637767 -484.23211) (xy 29.683514 -484.158226) (xy 29.735883 -484.088879) (xy 29.794427 -484.024659)
			(xy 29.858647 -483.966115) (xy 29.927994 -483.913746) (xy 30.001878 -483.867999) (xy 30.079667 -483.829265)
			(xy 30.160699 -483.797873) (xy 30.244281 -483.774092) (xy 30.329701 -483.758124) (xy 30.41623 -483.750106)
			(xy 30.50313 -483.750106) (xy 30.589659 -483.758124) (xy 30.675079 -483.774092) (xy 30.758661 -483.797873)
			(xy 30.839693 -483.829265) (xy 30.917482 -483.867999) (xy 30.991366 -483.913746) (xy 31.060713 -483.966115)
			(xy 31.124933 -484.024659) (xy 31.183477 -484.088879) (xy 31.235846 -484.158226) (xy 31.281593 -484.23211)
			(xy 31.320327 -484.309899) (xy 31.351719 -484.390931) (xy 31.3755 -484.474513) (xy 31.391468 -484.559933)
			(xy 31.399486 -484.646462) (xy 31.399988 -484.689912) (xy 31.399486 -484.733362) (xy 34.599874 -484.733362)
			(xy 34.599874 -484.646462) (xy 34.607892 -484.559933) (xy 34.62386 -484.474513) (xy 34.647641 -484.390931)
			(xy 34.679033 -484.309899) (xy 34.717767 -484.23211) (xy 34.763514 -484.158226) (xy 34.815883 -484.088879)
			(xy 34.874427 -484.024659) (xy 34.938647 -483.966115) (xy 35.007994 -483.913746) (xy 35.081878 -483.867999)
			(xy 35.159667 -483.829265) (xy 35.240699 -483.797873) (xy 35.324281 -483.774092) (xy 35.409701 -483.758124)
			(xy 35.49623 -483.750106) (xy 35.58313 -483.750106) (xy 35.669659 -483.758124) (xy 35.755079 -483.774092)
			(xy 35.838661 -483.797873) (xy 35.919693 -483.829265) (xy 35.997482 -483.867999) (xy 36.071366 -483.913746)
			(xy 36.140713 -483.966115) (xy 36.204933 -484.024659) (xy 36.263477 -484.088879) (xy 36.315846 -484.158226)
			(xy 36.361593 -484.23211) (xy 36.400327 -484.309899) (xy 36.431719 -484.390931) (xy 36.4555 -484.474513)
			(xy 36.471468 -484.559933) (xy 36.479486 -484.646462) (xy 36.479988 -484.689912) (xy 36.479486 -484.733362)
			(xy 36.471468 -484.819891) (xy 36.4555 -484.905311) (xy 36.431719 -484.988893) (xy 36.400327 -485.069925)
			(xy 36.361593 -485.147714) (xy 36.315846 -485.221598) (xy 36.263477 -485.290945) (xy 36.239447 -485.317305)
			(xy 38.205789 -485.317305) (xy 38.209676 -485.262952) (xy 38.221259 -485.209705) (xy 38.240301 -485.158649)
			(xy 38.266417 -485.110822) (xy 38.299073 -485.067199) (xy 38.337605 -485.028668) (xy 38.381228 -484.996013)
			(xy 38.429055 -484.969899) (xy 38.480112 -484.950857) (xy 38.533359 -484.939275) (xy 38.587712 -484.935389)
			(xy 38.642065 -484.939278) (xy 38.695311 -484.950863) (xy 38.746366 -484.969908) (xy 38.794192 -484.996026)
			(xy 38.81628 -485.011984) (xy 38.835292 -485.02558) (xy 38.877175 -485.046312) (xy 38.922143 -485.059038)
			(xy 38.96868 -485.063328) (xy 39.015217 -485.059038) (xy 39.060185 -485.046312) (xy 39.102068 -485.02558)
			(xy 39.12108 -485.011984) (xy 39.143176 -484.996033) (xy 39.191003 -484.96991) (xy 39.24206 -484.95086)
			(xy 39.295309 -484.939271) (xy 39.349665 -484.935378) (xy 39.404022 -484.939261) (xy 39.457274 -484.950841)
			(xy 39.508334 -484.969882) (xy 39.556166 -484.995996) (xy 39.599793 -485.028652) (xy 39.638329 -485.067184)
			(xy 39.670988 -485.110809) (xy 39.697106 -485.158638) (xy 39.716151 -485.209698) (xy 39.727735 -485.262948)
			(xy 39.731622 -485.317305) (xy 40.092482 -485.317305) (xy 40.096369 -485.26295) (xy 40.107952 -485.209702)
			(xy 40.126996 -485.158644) (xy 40.153112 -485.110816) (xy 40.185769 -485.067192) (xy 40.224303 -485.02866)
			(xy 40.267928 -484.996005) (xy 40.315757 -484.96989) (xy 40.366815 -484.950848) (xy 40.420064 -484.939267)
			(xy 40.474419 -484.935382) (xy 40.528773 -484.939272) (xy 40.582021 -484.950859) (xy 40.633077 -484.969905)
			(xy 40.680903 -484.996025) (xy 40.702992 -485.011984) (xy 40.722004 -485.02558) (xy 40.763887 -485.046312)
			(xy 40.808855 -485.059038) (xy 40.855392 -485.063328) (xy 40.901929 -485.059038) (xy 40.946897 -485.046312)
			(xy 40.98878 -485.02558) (xy 41.007792 -485.011984) (xy 41.029888 -484.996034) (xy 41.077713 -484.969913)
			(xy 41.12877 -484.950865) (xy 41.182017 -484.939277) (xy 41.236372 -484.935385) (xy 41.290728 -484.939269)
			(xy 41.343977 -484.950849) (xy 41.395036 -484.96989) (xy 41.442865 -484.996004) (xy 41.486491 -485.028659)
			(xy 41.525025 -485.067191) (xy 41.557683 -485.110815) (xy 41.5838 -485.158643) (xy 41.602844 -485.209701)
			(xy 41.614428 -485.26295) (xy 41.618315 -485.317305) (xy 42.333457 -485.317305) (xy 42.337344 -485.262944)
			(xy 42.348929 -485.20969) (xy 42.367976 -485.158628) (xy 42.394096 -485.110795) (xy 42.426757 -485.067168)
			(xy 42.465296 -485.028633) (xy 42.508927 -484.995975) (xy 42.556762 -484.96986) (xy 42.607827 -484.950819)
			(xy 42.661082 -484.939239) (xy 42.715443 -484.935357) (xy 42.769803 -484.939251) (xy 42.823055 -484.950843)
			(xy 42.874115 -484.969895) (xy 42.921944 -484.996021) (xy 42.944034 -485.011984) (xy 42.963046 -485.02558)
			(xy 43.004929 -485.046312) (xy 43.049897 -485.059038) (xy 43.096434 -485.063328) (xy 43.142971 -485.059038)
			(xy 43.187939 -485.046312) (xy 43.229822 -485.02558) (xy 43.248834 -485.011984) (xy 43.270929 -484.996038)
			(xy 43.318752 -484.969923) (xy 43.369804 -484.950881) (xy 43.423047 -484.939298) (xy 43.477396 -484.93541)
			(xy 43.531745 -484.939297) (xy 43.584989 -484.950879) (xy 43.636041 -484.96992) (xy 43.683865 -484.996034)
			(xy 43.727485 -485.028687) (xy 43.766014 -485.067216) (xy 43.798667 -485.110836) (xy 43.82478 -485.158659)
			(xy 43.843821 -485.209712) (xy 43.855403 -485.262955) (xy 43.85929 -485.317305) (xy 44.237466 -485.317305)
			(xy 44.241354 -485.262946) (xy 44.252938 -485.209695) (xy 44.271983 -485.158634) (xy 44.298102 -485.110803)
			(xy 44.330762 -485.067177) (xy 44.369299 -485.028643) (xy 44.412928 -484.995986) (xy 44.46076 -484.969871)
			(xy 44.511822 -484.95083) (xy 44.565075 -484.93925) (xy 44.619433 -484.935366) (xy 44.673791 -484.939259)
			(xy 44.727042 -484.950849) (xy 44.778101 -484.969899) (xy 44.825929 -484.996023) (xy 44.848018 -485.011984)
			(xy 44.86703 -485.02558) (xy 44.908913 -485.046312) (xy 44.953881 -485.059038) (xy 45.000418 -485.063328)
			(xy 45.046955 -485.059038) (xy 45.091923 -485.046312) (xy 45.133806 -485.02558) (xy 45.152818 -485.011984)
			(xy 45.174913 -484.996036) (xy 45.222737 -484.96992) (xy 45.273791 -484.950875) (xy 45.327036 -484.93929)
			(xy 45.381387 -484.935401) (xy 45.435739 -484.939286) (xy 45.488984 -484.950868) (xy 45.540039 -484.969909)
			(xy 45.587865 -484.996022) (xy 45.631487 -485.028677) (xy 45.670018 -485.067207) (xy 45.702673 -485.110828)
			(xy 45.728788 -485.158653) (xy 45.74783 -485.209708) (xy 45.759413 -485.262953) (xy 45.763299 -485.317305)
			(xy 45.759411 -485.371656) (xy 45.747827 -485.424901) (xy 45.7477 -485.425242) (xy 87.09609 -485.425242)
			(xy 87.100161 -485.36962) (xy 87.112287 -485.315183) (xy 87.13221 -485.263092) (xy 87.159506 -485.214457)
			(xy 87.193592 -485.170314) (xy 87.233741 -485.131605) (xy 87.279099 -485.099154) (xy 87.328699 -485.073653)
			(xy 87.381483 -485.055646) (xy 87.436326 -485.045516) (xy 87.49206 -485.043479) (xy 87.547497 -485.049579)
			(xy 87.601454 -485.063685) (xy 87.652783 -485.085497) (xy 87.700389 -485.114551) (xy 87.743257 -485.150226)
			(xy 87.780474 -485.191763) (xy 87.811247 -485.238276) (xy 87.834919 -485.288773) (xy 87.850987 -485.34218)
			(xy 87.859107 -485.397356) (xy 87.859616 -485.425242) (xy 87.859107 -485.453128) (xy 87.850987 -485.508304)
			(xy 87.834919 -485.561711) (xy 87.811247 -485.612208) (xy 87.780474 -485.658721) (xy 87.743257 -485.700258)
			(xy 87.700389 -485.735933) (xy 87.652783 -485.764987) (xy 87.601454 -485.786799) (xy 87.547497 -485.800905)
			(xy 87.49206 -485.807005) (xy 87.436326 -485.804968) (xy 87.381483 -485.794838) (xy 87.328699 -485.776831)
			(xy 87.279099 -485.75133) (xy 87.233741 -485.718879) (xy 87.193592 -485.68017) (xy 87.159506 -485.636027)
			(xy 87.13221 -485.587392) (xy 87.112287 -485.535301) (xy 87.100161 -485.480864) (xy 87.09609 -485.425242)
			(xy 45.7477 -485.425242) (xy 45.728784 -485.475955) (xy 45.702668 -485.52378) (xy 45.670012 -485.567401)
			(xy 45.63148 -485.60593) (xy 45.587857 -485.638583) (xy 45.540031 -485.664695) (xy 45.488975 -485.683735)
			(xy 45.435729 -485.695315) (xy 45.381377 -485.699199) (xy 45.327026 -485.695309) (xy 45.273782 -485.683722)
			(xy 45.222728 -485.664676) (xy 45.174905 -485.638558) (xy 45.152818 -485.6226) (xy 45.133806 -485.609004)
			(xy 45.091923 -485.588272) (xy 45.046955 -485.575546) (xy 45.000418 -485.571256) (xy 44.953881 -485.575546)
			(xy 44.908913 -485.588272) (xy 44.86703 -485.609004) (xy 44.848018 -485.6226) (xy 44.825937 -485.638572)
			(xy 44.77811 -485.664697) (xy 44.727051 -485.683749) (xy 44.673801 -485.69534) (xy 44.619443 -485.699234)
			(xy 44.565084 -485.695352) (xy 44.511831 -485.683773) (xy 44.460769 -485.664733) (xy 44.412936 -485.638619)
			(xy 44.369306 -485.605963) (xy 44.330768 -485.56743) (xy 44.298107 -485.523805) (xy 44.271987 -485.475975)
			(xy 44.252941 -485.424914) (xy 44.241355 -485.371663) (xy 44.237466 -485.317305) (xy 43.85929 -485.317305)
			(xy 43.855402 -485.371654) (xy 43.843819 -485.424897) (xy 43.824776 -485.475949) (xy 43.798662 -485.523772)
			(xy 43.766007 -485.567391) (xy 43.727477 -485.605919) (xy 43.683856 -485.638572) (xy 43.636033 -485.664684)
			(xy 43.584979 -485.683724) (xy 43.531736 -485.695304) (xy 43.477386 -485.69919) (xy 43.423037 -485.695301)
			(xy 43.369795 -485.683716) (xy 43.318743 -485.664673) (xy 43.270921 -485.638557) (xy 43.248834 -485.6226)
			(xy 43.229822 -485.609004) (xy 43.187939 -485.588272) (xy 43.142971 -485.575546) (xy 43.096434 -485.571256)
			(xy 43.049897 -485.575546) (xy 43.004929 -485.588272) (xy 42.963046 -485.609004) (xy 42.944034 -485.6226)
			(xy 42.921953 -485.638574) (xy 42.874124 -485.664701) (xy 42.823064 -485.683755) (xy 42.769812 -485.695348)
			(xy 42.715452 -485.699243) (xy 42.661091 -485.695362) (xy 42.607836 -485.683784) (xy 42.556771 -485.664744)
			(xy 42.508935 -485.63863) (xy 42.465303 -485.605974) (xy 42.426764 -485.56744) (xy 42.394101 -485.523813)
			(xy 42.36798 -485.475981) (xy 42.348932 -485.424919) (xy 42.337346 -485.371665) (xy 42.333457 -485.317305)
			(xy 41.618315 -485.317305) (xy 41.614426 -485.37166) (xy 41.602842 -485.424908) (xy 41.583796 -485.475966)
			(xy 41.557678 -485.523793) (xy 41.525019 -485.567416) (xy 41.486484 -485.605947) (xy 41.442857 -485.638601)
			(xy 41.395027 -485.664714) (xy 41.343968 -485.683754) (xy 41.290718 -485.695332) (xy 41.236363 -485.699215)
			(xy 41.182008 -485.695322) (xy 41.128761 -485.683732) (xy 41.077705 -485.664683) (xy 41.02988 -485.638561)
			(xy 41.007792 -485.6226) (xy 40.98878 -485.609004) (xy 40.946897 -485.588272) (xy 40.901929 -485.575546)
			(xy 40.855392 -485.571256) (xy 40.808855 -485.575546) (xy 40.763887 -485.588272) (xy 40.722004 -485.609004)
			(xy 40.702992 -485.6226) (xy 40.680912 -485.63857) (xy 40.633086 -485.664691) (xy 40.58203 -485.683739)
			(xy 40.528783 -485.695326) (xy 40.474428 -485.699218) (xy 40.420073 -485.695334) (xy 40.366824 -485.683755)
			(xy 40.315765 -485.664714) (xy 40.267936 -485.638601) (xy 40.22431 -485.605946) (xy 40.185776 -485.567415)
			(xy 40.153117 -485.523792) (xy 40.127 -485.475965) (xy 40.107955 -485.424907) (xy 40.09637 -485.371659)
			(xy 40.092482 -485.317305) (xy 39.731622 -485.317305) (xy 39.727733 -485.371661) (xy 39.716148 -485.424911)
			(xy 39.697102 -485.47597) (xy 39.670983 -485.523799) (xy 39.638323 -485.567423) (xy 39.599786 -485.605955)
			(xy 39.556158 -485.638609) (xy 39.508326 -485.664722) (xy 39.457264 -485.683762) (xy 39.404013 -485.69534)
			(xy 39.349656 -485.699222) (xy 39.295299 -485.695328) (xy 39.242051 -485.683737) (xy 39.190994 -485.664686)
			(xy 39.143168 -485.638562) (xy 39.12108 -485.6226) (xy 39.102068 -485.609004) (xy 39.060185 -485.588272)
			(xy 39.015217 -485.575546) (xy 38.96868 -485.571256) (xy 38.922143 -485.575546) (xy 38.877175 -485.588272)
			(xy 38.835292 -485.609004) (xy 38.81628 -485.6226) (xy 38.7942 -485.638569) (xy 38.746375 -485.664688)
			(xy 38.69532 -485.683734) (xy 38.642074 -485.69532) (xy 38.587721 -485.699211) (xy 38.533368 -485.695326)
			(xy 38.480121 -485.683746) (xy 38.429064 -485.664705) (xy 38.381236 -485.638592) (xy 38.337612 -485.605938)
			(xy 38.299079 -485.567408) (xy 38.266422 -485.523786) (xy 38.240305 -485.47596) (xy 38.221261 -485.424904)
			(xy 38.209677 -485.371658) (xy 38.205789 -485.317305) (xy 36.239447 -485.317305) (xy 36.204933 -485.355165)
			(xy 36.140713 -485.413709) (xy 36.071366 -485.466078) (xy 35.997482 -485.511825) (xy 35.919693 -485.550559)
			(xy 35.838661 -485.581951) (xy 35.755079 -485.605732) (xy 35.669659 -485.6217) (xy 35.58313 -485.629718)
			(xy 35.49623 -485.629718) (xy 35.409701 -485.6217) (xy 35.324281 -485.605732) (xy 35.240699 -485.581951)
			(xy 35.159667 -485.550559) (xy 35.081878 -485.511825) (xy 35.007994 -485.466078) (xy 34.938647 -485.413709)
			(xy 34.874427 -485.355165) (xy 34.815883 -485.290945) (xy 34.763514 -485.221598) (xy 34.717767 -485.147714)
			(xy 34.679033 -485.069925) (xy 34.647641 -484.988893) (xy 34.62386 -484.905311) (xy 34.607892 -484.819891)
			(xy 34.599874 -484.733362) (xy 31.399486 -484.733362) (xy 31.391468 -484.819891) (xy 31.3755 -484.905311)
			(xy 31.351719 -484.988893) (xy 31.320327 -485.069925) (xy 31.281593 -485.147714) (xy 31.235846 -485.221598)
			(xy 31.183477 -485.290945) (xy 31.124933 -485.355165) (xy 31.060713 -485.413709) (xy 30.991366 -485.466078)
			(xy 30.917482 -485.511825) (xy 30.839693 -485.550559) (xy 30.758661 -485.581951) (xy 30.675079 -485.605732)
			(xy 30.589659 -485.6217) (xy 30.50313 -485.629718) (xy 30.41623 -485.629718) (xy 30.329701 -485.6217)
			(xy 30.244281 -485.605732) (xy 30.160699 -485.581951) (xy 30.079667 -485.550559) (xy 30.001878 -485.511825)
			(xy 29.927994 -485.466078) (xy 29.858647 -485.413709) (xy 29.794427 -485.355165) (xy 29.735883 -485.290945)
			(xy 29.683514 -485.221598) (xy 29.637767 -485.147714) (xy 29.599033 -485.069925) (xy 29.567641 -484.988893)
			(xy 29.54386 -484.905311) (xy 29.527892 -484.819891) (xy 29.519874 -484.733362) (xy 2.08026 -484.733362)
			(xy 2.08026 -487.273362) (xy 29.519874 -487.273362) (xy 29.519874 -487.186462) (xy 29.527892 -487.099933)
			(xy 29.54386 -487.014513) (xy 29.567641 -486.930931) (xy 29.599033 -486.849899) (xy 29.637767 -486.77211)
			(xy 29.683514 -486.698226) (xy 29.735883 -486.628879) (xy 29.794427 -486.564659) (xy 29.858647 -486.506115)
			(xy 29.927994 -486.453746) (xy 30.001878 -486.407999) (xy 30.079667 -486.369265) (xy 30.160699 -486.337873)
			(xy 30.244281 -486.314092) (xy 30.329701 -486.298124) (xy 30.41623 -486.290106) (xy 30.50313 -486.290106)
			(xy 30.589659 -486.298124) (xy 30.675079 -486.314092) (xy 30.758661 -486.337873) (xy 30.839693 -486.369265)
			(xy 30.917482 -486.407999) (xy 30.991366 -486.453746) (xy 31.060713 -486.506115) (xy 31.124933 -486.564659)
			(xy 31.183477 -486.628879) (xy 31.235846 -486.698226) (xy 31.281593 -486.77211) (xy 31.320327 -486.849899)
			(xy 31.351719 -486.930931) (xy 31.3755 -487.014513) (xy 31.391468 -487.099933) (xy 31.399486 -487.186462)
			(xy 31.399988 -487.229912) (xy 31.399486 -487.273362) (xy 34.599874 -487.273362) (xy 34.599874 -487.186462)
			(xy 34.607892 -487.099933) (xy 34.62386 -487.014513) (xy 34.647641 -486.930931) (xy 34.679033 -486.849899)
			(xy 34.717767 -486.77211) (xy 34.763514 -486.698226) (xy 34.815883 -486.628879) (xy 34.874427 -486.564659)
			(xy 34.938647 -486.506115) (xy 35.007994 -486.453746) (xy 35.081878 -486.407999) (xy 35.159667 -486.369265)
			(xy 35.240699 -486.337873) (xy 35.324281 -486.314092) (xy 35.409701 -486.298124) (xy 35.49623 -486.290106)
			(xy 35.58313 -486.290106) (xy 35.669659 -486.298124) (xy 35.755079 -486.314092) (xy 35.838661 -486.337873)
			(xy 35.919693 -486.369265) (xy 35.997482 -486.407999) (xy 36.071366 -486.453746) (xy 36.140713 -486.506115)
			(xy 36.204933 -486.564659) (xy 36.263477 -486.628879) (xy 36.315846 -486.698226) (xy 36.361593 -486.77211)
			(xy 36.378335 -486.805732) (xy 87.38438 -486.805732) (xy 87.388451 -486.75011) (xy 87.400577 -486.695673)
			(xy 87.4205 -486.643582) (xy 87.447796 -486.594947) (xy 87.481882 -486.550804) (xy 87.522031 -486.512095)
			(xy 87.567389 -486.479644) (xy 87.616989 -486.454143) (xy 87.669773 -486.436136) (xy 87.724616 -486.426006)
			(xy 87.78035 -486.423969) (xy 87.835787 -486.430069) (xy 87.889744 -486.444175) (xy 87.941073 -486.465987)
			(xy 87.988679 -486.495041) (xy 88.031547 -486.530716) (xy 88.068764 -486.572253) (xy 88.099537 -486.618766)
			(xy 88.123209 -486.669263) (xy 88.139277 -486.72267) (xy 88.147397 -486.777846) (xy 88.147906 -486.805732)
			(xy 88.147397 -486.833618) (xy 88.139277 -486.888794) (xy 88.123209 -486.942201) (xy 88.099537 -486.992698)
			(xy 88.068764 -487.039211) (xy 88.031547 -487.080748) (xy 87.988679 -487.116423) (xy 87.941073 -487.145477)
			(xy 87.889744 -487.167289) (xy 87.835787 -487.181395) (xy 87.78035 -487.187495) (xy 87.724616 -487.185458)
			(xy 87.669773 -487.175328) (xy 87.616989 -487.157321) (xy 87.567389 -487.13182) (xy 87.522031 -487.099369)
			(xy 87.481882 -487.06066) (xy 87.447796 -487.016517) (xy 87.4205 -486.967882) (xy 87.400577 -486.915791)
			(xy 87.388451 -486.861354) (xy 87.38438 -486.805732) (xy 36.378335 -486.805732) (xy 36.400327 -486.849899)
			(xy 36.431719 -486.930931) (xy 36.4555 -487.014513) (xy 36.471468 -487.099933) (xy 36.479486 -487.186462)
			(xy 36.479955 -487.227089) (xy 38.20581 -487.227089) (xy 38.209699 -487.172739) (xy 38.221283 -487.119496)
			(xy 38.240327 -487.068443) (xy 38.266443 -487.02062) (xy 38.299099 -486.977001) (xy 38.33763 -486.938474)
			(xy 38.381253 -486.905822) (xy 38.429078 -486.879711) (xy 38.480133 -486.860672) (xy 38.533377 -486.849093)
			(xy 38.587727 -486.84521) (xy 38.642077 -486.849101) (xy 38.69532 -486.860688) (xy 38.746372 -486.879734)
			(xy 38.794194 -486.905852) (xy 38.81628 -486.92181) (xy 38.835292 -486.935406) (xy 38.877175 -486.956138)
			(xy 38.922143 -486.968864) (xy 38.96868 -486.973154) (xy 39.015217 -486.968864) (xy 39.060185 -486.956138)
			(xy 39.102068 -486.935406) (xy 39.12108 -486.92181) (xy 39.143152 -486.905824) (xy 39.19098 -486.879698)
			(xy 39.242039 -486.860645) (xy 39.295291 -486.849052) (xy 39.34965 -486.845157) (xy 39.40401 -486.849038)
			(xy 39.457264 -486.860616) (xy 39.508329 -486.879656) (xy 39.556164 -486.90577) (xy 39.599795 -486.938426)
			(xy 39.638334 -486.976959) (xy 39.670997 -487.020585) (xy 39.697119 -487.068416) (xy 39.716166 -487.119477)
			(xy 39.727753 -487.17273) (xy 39.731643 -487.227089) (xy 40.092503 -487.227089) (xy 40.096392 -487.172738)
			(xy 40.107976 -487.119493) (xy 40.127021 -487.068438) (xy 40.153138 -487.020614) (xy 40.185795 -486.976994)
			(xy 40.224328 -486.938466) (xy 40.267952 -486.905814) (xy 40.315779 -486.879702) (xy 40.366836 -486.860664)
			(xy 40.420082 -486.849085) (xy 40.474434 -486.845203) (xy 40.528786 -486.849095) (xy 40.58203 -486.860683)
			(xy 40.633083 -486.879731) (xy 40.680905 -486.905851) (xy 40.702992 -486.92181) (xy 40.722004 -486.935406)
			(xy 40.763887 -486.956138) (xy 40.808855 -486.968864) (xy 40.855392 -486.973154) (xy 40.901929 -486.968864)
			(xy 40.946897 -486.956138) (xy 40.98878 -486.935406) (xy 41.007792 -486.92181) (xy 41.029863 -486.905825)
			(xy 41.077691 -486.879701) (xy 41.128749 -486.860649) (xy 41.181999 -486.849058) (xy 41.236357 -486.845164)
			(xy 41.290715 -486.849046) (xy 41.343968 -486.860625) (xy 41.39503 -486.879665) (xy 41.442864 -486.905778)
			(xy 41.486493 -486.938434) (xy 41.525031 -486.976966) (xy 41.557693 -487.020591) (xy 41.583813 -487.06842)
			(xy 41.60286 -487.11948) (xy 41.614446 -487.172731) (xy 41.618336 -487.227089) (xy 42.333478 -487.227089)
			(xy 42.337367 -487.172732) (xy 42.348954 -487.119481) (xy 42.368001 -487.068422) (xy 42.394122 -487.020594)
			(xy 42.426783 -486.97697) (xy 42.465322 -486.938438) (xy 42.508952 -486.905784) (xy 42.556785 -486.879672)
			(xy 42.607848 -486.860634) (xy 42.6611 -486.849057) (xy 42.715458 -486.845178) (xy 42.769815 -486.849074)
			(xy 42.823064 -486.860667) (xy 42.874121 -486.879721) (xy 42.921946 -486.905847) (xy 42.944034 -486.92181)
			(xy 42.963046 -486.935406) (xy 43.004929 -486.956138) (xy 43.049897 -486.968864) (xy 43.096434 -486.973154)
			(xy 43.142971 -486.968864) (xy 43.187939 -486.956138) (xy 43.229822 -486.935406) (xy 43.248834 -486.92181)
			(xy 43.270904 -486.905829) (xy 43.318729 -486.879711) (xy 43.369783 -486.860665) (xy 43.423028 -486.84908)
			(xy 43.47738 -486.845189) (xy 43.531733 -486.849074) (xy 43.584979 -486.860654) (xy 43.636036 -486.879695)
			(xy 43.683863 -486.905808) (xy 43.727486 -486.938461) (xy 43.766019 -486.976991) (xy 43.798676 -487.020612)
			(xy 43.824793 -487.068437) (xy 43.843837 -487.119491) (xy 43.855422 -487.172737) (xy 43.859311 -487.227089)
			(xy 44.237487 -487.227089) (xy 44.241376 -487.172734) (xy 44.252962 -487.119486) (xy 44.272009 -487.068428)
			(xy 44.298128 -487.020601) (xy 44.330788 -486.976979) (xy 44.369324 -486.938449) (xy 44.412952 -486.905795)
			(xy 44.460783 -486.879684) (xy 44.511843 -486.860645) (xy 44.565093 -486.849068) (xy 44.619449 -486.845187)
			(xy 44.673804 -486.849082) (xy 44.727051 -486.860673) (xy 44.778106 -486.879725) (xy 44.825931 -486.905848)
			(xy 44.848018 -486.92181) (xy 44.86703 -486.935406) (xy 44.908913 -486.956138) (xy 44.953881 -486.968864)
			(xy 45.000418 -486.973154) (xy 45.046955 -486.968864) (xy 45.091923 -486.956138) (xy 45.133806 -486.935406)
			(xy 45.152818 -486.92181) (xy 45.174889 -486.905827) (xy 45.222714 -486.879707) (xy 45.27377 -486.860659)
			(xy 45.327017 -486.849072) (xy 45.381371 -486.84518) (xy 45.435726 -486.849063) (xy 45.488975 -486.860643)
			(xy 45.540034 -486.879683) (xy 45.587863 -486.905796) (xy 45.631489 -486.938451) (xy 45.670024 -486.976981)
			(xy 45.702682 -487.020604) (xy 45.7288 -487.06843) (xy 45.747846 -487.119487) (xy 45.759431 -487.172735)
			(xy 45.76332 -487.227089) (xy 45.761575 -487.251502) (xy 91.911676 -487.251502) (xy 91.915747 -487.19588)
			(xy 91.927873 -487.141443) (xy 91.947796 -487.089352) (xy 91.975092 -487.040717) (xy 92.009178 -486.996574)
			(xy 92.049327 -486.957865) (xy 92.094685 -486.925414) (xy 92.144285 -486.899913) (xy 92.197069 -486.881906)
			(xy 92.251912 -486.871776) (xy 92.307646 -486.869739) (xy 92.363083 -486.875839) (xy 92.41704 -486.889945)
			(xy 92.468369 -486.911757) (xy 92.515975 -486.940811) (xy 92.558843 -486.976486) (xy 92.565839 -486.984294)
			(xy 95.986344 -486.984294) (xy 95.990415 -486.928672) (xy 96.002541 -486.874235) (xy 96.022464 -486.822144)
			(xy 96.04976 -486.773509) (xy 96.083846 -486.729366) (xy 96.123995 -486.690657) (xy 96.169353 -486.658206)
			(xy 96.218953 -486.632705) (xy 96.271737 -486.614698) (xy 96.32658 -486.604568) (xy 96.382314 -486.602531)
			(xy 96.437751 -486.608631) (xy 96.491708 -486.622737) (xy 96.543037 -486.644549) (xy 96.590643 -486.673603)
			(xy 96.633511 -486.709278) (xy 96.670728 -486.750815) (xy 96.701501 -486.797328) (xy 96.725173 -486.847825)
			(xy 96.741241 -486.901232) (xy 96.749361 -486.956408) (xy 96.74987 -486.984294) (xy 96.749361 -487.01218)
			(xy 96.741241 -487.067356) (xy 96.725173 -487.120763) (xy 96.701501 -487.17126) (xy 96.670728 -487.217773)
			(xy 96.633511 -487.25931) (xy 96.590643 -487.294985) (xy 96.543037 -487.324039) (xy 96.491708 -487.345851)
			(xy 96.437751 -487.359957) (xy 96.382314 -487.366057) (xy 96.32658 -487.36402) (xy 96.271737 -487.35389)
			(xy 96.218953 -487.335883) (xy 96.169353 -487.310382) (xy 96.123995 -487.277931) (xy 96.083846 -487.239222)
			(xy 96.04976 -487.195079) (xy 96.022464 -487.146444) (xy 96.002541 -487.094353) (xy 95.990415 -487.039916)
			(xy 95.986344 -486.984294) (xy 92.565839 -486.984294) (xy 92.59606 -487.018023) (xy 92.626833 -487.064536)
			(xy 92.650505 -487.115033) (xy 92.666573 -487.16844) (xy 92.674693 -487.223616) (xy 92.675202 -487.251502)
			(xy 92.674693 -487.279388) (xy 92.666573 -487.334564) (xy 92.650505 -487.387971) (xy 92.626833 -487.438468)
			(xy 92.59606 -487.484981) (xy 92.593604 -487.487722) (xy 94.810832 -487.487722) (xy 94.814903 -487.4321)
			(xy 94.827029 -487.377663) (xy 94.846952 -487.325572) (xy 94.874248 -487.276937) (xy 94.908334 -487.232794)
			(xy 94.948483 -487.194085) (xy 94.993841 -487.161634) (xy 95.043441 -487.136133) (xy 95.096225 -487.118126)
			(xy 95.151068 -487.107996) (xy 95.206802 -487.105959) (xy 95.262239 -487.112059) (xy 95.316196 -487.126165)
			(xy 95.367525 -487.147977) (xy 95.415131 -487.177031) (xy 95.457999 -487.212706) (xy 95.495216 -487.254243)
			(xy 95.525989 -487.300756) (xy 95.549661 -487.351253) (xy 95.565729 -487.40466) (xy 95.573849 -487.459836)
			(xy 95.574358 -487.487722) (xy 95.573849 -487.515608) (xy 95.565729 -487.570784) (xy 95.549661 -487.624191)
			(xy 95.525989 -487.674688) (xy 95.495216 -487.721201) (xy 95.457999 -487.762738) (xy 95.415131 -487.798413)
			(xy 95.367525 -487.827467) (xy 95.316196 -487.849279) (xy 95.262239 -487.863385) (xy 95.206802 -487.869485)
			(xy 95.151068 -487.867448) (xy 95.096225 -487.857318) (xy 95.043441 -487.839311) (xy 94.993841 -487.81381)
			(xy 94.948483 -487.781359) (xy 94.908334 -487.74265) (xy 94.874248 -487.698507) (xy 94.846952 -487.649872)
			(xy 94.827029 -487.597781) (xy 94.814903 -487.543344) (xy 94.810832 -487.487722) (xy 92.593604 -487.487722)
			(xy 92.558843 -487.526518) (xy 92.515975 -487.562193) (xy 92.468369 -487.591247) (xy 92.41704 -487.613059)
			(xy 92.363083 -487.627165) (xy 92.307646 -487.633265) (xy 92.251912 -487.631228) (xy 92.197069 -487.621098)
			(xy 92.144285 -487.603091) (xy 92.094685 -487.57759) (xy 92.049327 -487.545139) (xy 92.009178 -487.50643)
			(xy 91.975092 -487.462287) (xy 91.947796 -487.413652) (xy 91.927873 -487.361561) (xy 91.915747 -487.307124)
			(xy 91.911676 -487.251502) (xy 45.761575 -487.251502) (xy 45.759434 -487.281444) (xy 45.747852 -487.334692)
			(xy 45.728809 -487.38575) (xy 45.702694 -487.433578) (xy 45.670038 -487.477202) (xy 45.631505 -487.515735)
			(xy 45.587881 -487.548392) (xy 45.540053 -487.574508) (xy 45.488996 -487.593551) (xy 45.435748 -487.605134)
			(xy 45.381393 -487.60902) (xy 45.327039 -487.605132) (xy 45.273791 -487.593547) (xy 45.222734 -487.574502)
			(xy 45.174907 -487.548384) (xy 45.152818 -487.532426) (xy 45.133806 -487.51883) (xy 45.091923 -487.498098)
			(xy 45.046955 -487.485372) (xy 45.000418 -487.481082) (xy 44.953881 -487.485372) (xy 44.908913 -487.498098)
			(xy 44.86703 -487.51883) (xy 44.848018 -487.532426) (xy 44.825913 -487.548363) (xy 44.778087 -487.574484)
			(xy 44.72703 -487.593533) (xy 44.673783 -487.605121) (xy 44.619427 -487.609013) (xy 44.565072 -487.605129)
			(xy 44.511822 -487.593549) (xy 44.460763 -487.574507) (xy 44.412934 -487.548393) (xy 44.369308 -487.515737)
			(xy 44.330774 -487.477205) (xy 44.298116 -487.43358) (xy 44.272 -487.385752) (xy 44.252956 -487.334694)
			(xy 44.241373 -487.281445) (xy 44.237487 -487.227089) (xy 43.859311 -487.227089) (xy 43.855425 -487.281442)
			(xy 43.843843 -487.334688) (xy 43.824802 -487.385744) (xy 43.798688 -487.43357) (xy 43.766033 -487.477193)
			(xy 43.727503 -487.515725) (xy 43.683881 -487.548381) (xy 43.636055 -487.574496) (xy 43.585 -487.593539)
			(xy 43.531754 -487.605123) (xy 43.477402 -487.609011) (xy 43.42305 -487.605123) (xy 43.369804 -487.593541)
			(xy 43.318748 -487.574498) (xy 43.270923 -487.548383) (xy 43.248834 -487.532426) (xy 43.229822 -487.51883)
			(xy 43.187939 -487.498098) (xy 43.142971 -487.485372) (xy 43.096434 -487.481082) (xy 43.049897 -487.485372)
			(xy 43.004929 -487.498098) (xy 42.963046 -487.51883) (xy 42.944034 -487.532426) (xy 42.921928 -487.548365)
			(xy 42.874101 -487.574488) (xy 42.823043 -487.593539) (xy 42.769794 -487.605129) (xy 42.715437 -487.609022)
			(xy 42.661079 -487.60514) (xy 42.607827 -487.59356) (xy 42.556765 -487.574519) (xy 42.508933 -487.548404)
			(xy 42.465305 -487.515748) (xy 42.426769 -487.477214) (xy 42.39411 -487.433588) (xy 42.367992 -487.385758)
			(xy 42.348947 -487.334698) (xy 42.337364 -487.281447) (xy 42.333478 -487.227089) (xy 41.618336 -487.227089)
			(xy 41.614449 -487.281447) (xy 41.602866 -487.334699) (xy 41.583822 -487.38576) (xy 41.557704 -487.433591)
			(xy 41.525045 -487.477218) (xy 41.486509 -487.515752) (xy 41.442882 -487.54841) (xy 41.39505 -487.574526)
			(xy 41.343989 -487.593569) (xy 41.290736 -487.605151) (xy 41.236378 -487.609036) (xy 41.18202 -487.605145)
			(xy 41.12877 -487.593557) (xy 41.07771 -487.574508) (xy 41.029882 -487.548387) (xy 41.007792 -487.532426)
			(xy 40.98878 -487.51883) (xy 40.946897 -487.498098) (xy 40.901929 -487.485372) (xy 40.855392 -487.481082)
			(xy 40.808855 -487.485372) (xy 40.763887 -487.498098) (xy 40.722004 -487.51883) (xy 40.702992 -487.532426)
			(xy 40.680887 -487.548361) (xy 40.633063 -487.574478) (xy 40.582009 -487.593523) (xy 40.528764 -487.605108)
			(xy 40.474413 -487.608997) (xy 40.420061 -487.605112) (xy 40.366815 -487.59353) (xy 40.31576 -487.574489)
			(xy 40.267934 -487.548375) (xy 40.224312 -487.51572) (xy 40.185781 -487.477189) (xy 40.153126 -487.433567)
			(xy 40.127012 -487.385742) (xy 40.10797 -487.334687) (xy 40.096389 -487.281441) (xy 40.092503 -487.227089)
			(xy 39.731643 -487.227089) (xy 39.727756 -487.281449) (xy 39.716173 -487.334702) (xy 39.697128 -487.385765)
			(xy 39.671009 -487.433597) (xy 39.638349 -487.477225) (xy 39.599811 -487.51576) (xy 39.556182 -487.548419)
			(xy 39.508349 -487.574535) (xy 39.457285 -487.593578) (xy 39.404031 -487.605159) (xy 39.349671 -487.609043)
			(xy 39.295312 -487.605151) (xy 39.24206 -487.593561) (xy 39.190999 -487.574511) (xy 39.14317 -487.548388)
			(xy 39.12108 -487.532426) (xy 39.102068 -487.51883) (xy 39.060185 -487.498098) (xy 39.015217 -487.485372)
			(xy 38.96868 -487.481082) (xy 38.922143 -487.485372) (xy 38.877175 -487.498098) (xy 38.835292 -487.51883)
			(xy 38.81628 -487.532426) (xy 38.794175 -487.54836) (xy 38.746352 -487.574475) (xy 38.695299 -487.593518)
			(xy 38.642056 -487.605102) (xy 38.587706 -487.60899) (xy 38.533356 -487.605104) (xy 38.480112 -487.593522)
			(xy 38.429058 -487.57448) (xy 38.381234 -487.548366) (xy 38.337614 -487.515712) (xy 38.299085 -487.477182)
			(xy 38.266431 -487.433561) (xy 38.240318 -487.385737) (xy 38.221277 -487.334683) (xy 38.209696 -487.281439)
			(xy 38.20581 -487.227089) (xy 36.479955 -487.227089) (xy 36.479988 -487.229912) (xy 36.479486 -487.273362)
			(xy 36.471468 -487.359891) (xy 36.4555 -487.445311) (xy 36.431719 -487.528893) (xy 36.400327 -487.609925)
			(xy 36.361593 -487.687714) (xy 36.315846 -487.761598) (xy 36.263477 -487.830945) (xy 36.243627 -487.85272)
			(xy 90.630754 -487.85272) (xy 90.634825 -487.797098) (xy 90.646951 -487.742661) (xy 90.666874 -487.69057)
			(xy 90.69417 -487.641935) (xy 90.728256 -487.597792) (xy 90.768405 -487.559083) (xy 90.813763 -487.526632)
			(xy 90.863363 -487.501131) (xy 90.916147 -487.483124) (xy 90.97099 -487.472994) (xy 91.026724 -487.470957)
			(xy 91.082161 -487.477057) (xy 91.136118 -487.491163) (xy 91.187447 -487.512975) (xy 91.235053 -487.542029)
			(xy 91.277921 -487.577704) (xy 91.315138 -487.619241) (xy 91.345911 -487.665754) (xy 91.369583 -487.716251)
			(xy 91.385651 -487.769658) (xy 91.393771 -487.824834) (xy 91.39428 -487.85272) (xy 91.393771 -487.880606)
			(xy 91.385651 -487.935782) (xy 91.369583 -487.989189) (xy 91.345911 -488.039686) (xy 91.315138 -488.086199)
			(xy 91.277921 -488.127736) (xy 91.268075 -488.13593) (xy 93.533974 -488.13593) (xy 93.538045 -488.080308)
			(xy 93.550171 -488.025871) (xy 93.570094 -487.97378) (xy 93.59739 -487.925145) (xy 93.631476 -487.881002)
			(xy 93.671625 -487.842293) (xy 93.716983 -487.809842) (xy 93.766583 -487.784341) (xy 93.819367 -487.766334)
			(xy 93.87421 -487.756204) (xy 93.929944 -487.754167) (xy 93.985381 -487.760267) (xy 94.039338 -487.774373)
			(xy 94.090667 -487.796185) (xy 94.138273 -487.825239) (xy 94.181141 -487.860914) (xy 94.218358 -487.902451)
			(xy 94.249131 -487.948964) (xy 94.272803 -487.999461) (xy 94.288871 -488.052868) (xy 94.296991 -488.108044)
			(xy 94.2975 -488.13593) (xy 94.296991 -488.163816) (xy 94.288871 -488.218992) (xy 94.272803 -488.272399)
			(xy 94.249131 -488.322896) (xy 94.218358 -488.369409) (xy 94.181141 -488.410946) (xy 94.138273 -488.446621)
			(xy 94.090667 -488.475675) (xy 94.039338 -488.497487) (xy 93.985381 -488.511593) (xy 93.929944 -488.517693)
			(xy 93.87421 -488.515656) (xy 93.819367 -488.505526) (xy 93.766583 -488.487519) (xy 93.716983 -488.462018)
			(xy 93.671625 -488.429567) (xy 93.631476 -488.390858) (xy 93.59739 -488.346715) (xy 93.570094 -488.29808)
			(xy 93.550171 -488.245989) (xy 93.538045 -488.191552) (xy 93.533974 -488.13593) (xy 91.268075 -488.13593)
			(xy 91.235053 -488.163411) (xy 91.187447 -488.192465) (xy 91.136118 -488.214277) (xy 91.082161 -488.228383)
			(xy 91.026724 -488.234483) (xy 90.97099 -488.232446) (xy 90.916147 -488.222316) (xy 90.863363 -488.204309)
			(xy 90.813763 -488.178808) (xy 90.768405 -488.146357) (xy 90.728256 -488.107648) (xy 90.69417 -488.063505)
			(xy 90.666874 -488.01487) (xy 90.646951 -487.962779) (xy 90.634825 -487.908342) (xy 90.630754 -487.85272)
			(xy 36.243627 -487.85272) (xy 36.204933 -487.895165) (xy 36.140713 -487.953709) (xy 36.071366 -488.006078)
			(xy 35.997482 -488.051825) (xy 35.919693 -488.090559) (xy 35.838661 -488.121951) (xy 35.755079 -488.145732)
			(xy 35.669659 -488.1617) (xy 35.58313 -488.169718) (xy 35.49623 -488.169718) (xy 35.409701 -488.1617)
			(xy 35.324281 -488.145732) (xy 35.240699 -488.121951) (xy 35.159667 -488.090559) (xy 35.081878 -488.051825)
			(xy 35.007994 -488.006078) (xy 34.938647 -487.953709) (xy 34.874427 -487.895165) (xy 34.815883 -487.830945)
			(xy 34.763514 -487.761598) (xy 34.717767 -487.687714) (xy 34.679033 -487.609925) (xy 34.647641 -487.528893)
			(xy 34.62386 -487.445311) (xy 34.607892 -487.359891) (xy 34.599874 -487.273362) (xy 31.399486 -487.273362)
			(xy 31.391468 -487.359891) (xy 31.3755 -487.445311) (xy 31.351719 -487.528893) (xy 31.320327 -487.609925)
			(xy 31.281593 -487.687714) (xy 31.235846 -487.761598) (xy 31.183477 -487.830945) (xy 31.124933 -487.895165)
			(xy 31.060713 -487.953709) (xy 30.991366 -488.006078) (xy 30.917482 -488.051825) (xy 30.839693 -488.090559)
			(xy 30.758661 -488.121951) (xy 30.675079 -488.145732) (xy 30.589659 -488.1617) (xy 30.50313 -488.169718)
			(xy 30.41623 -488.169718) (xy 30.329701 -488.1617) (xy 30.244281 -488.145732) (xy 30.160699 -488.121951)
			(xy 30.079667 -488.090559) (xy 30.001878 -488.051825) (xy 29.927994 -488.006078) (xy 29.858647 -487.953709)
			(xy 29.794427 -487.895165) (xy 29.735883 -487.830945) (xy 29.683514 -487.761598) (xy 29.637767 -487.687714)
			(xy 29.599033 -487.609925) (xy 29.567641 -487.528893) (xy 29.54386 -487.445311) (xy 29.527892 -487.359891)
			(xy 29.519874 -487.273362) (xy 2.08026 -487.273362) (xy 2.08026 -488.291886) (xy 86.063326 -488.291886)
			(xy 86.067397 -488.236264) (xy 86.079523 -488.181827) (xy 86.099446 -488.129736) (xy 86.126742 -488.081101)
			(xy 86.160828 -488.036958) (xy 86.200977 -487.998249) (xy 86.246335 -487.965798) (xy 86.295935 -487.940297)
			(xy 86.348719 -487.92229) (xy 86.403562 -487.91216) (xy 86.459296 -487.910123) (xy 86.514733 -487.916223)
			(xy 86.56869 -487.930329) (xy 86.620019 -487.952141) (xy 86.667625 -487.981195) (xy 86.710493 -488.01687)
			(xy 86.74771 -488.058407) (xy 86.778483 -488.10492) (xy 86.802155 -488.155417) (xy 86.818223 -488.208824)
			(xy 86.826343 -488.264) (xy 86.826852 -488.291886) (xy 86.826343 -488.319772) (xy 86.818223 -488.374948)
			(xy 86.802155 -488.428355) (xy 86.778483 -488.478852) (xy 86.74771 -488.525365) (xy 86.717944 -488.558586)
			(xy 91.924376 -488.558586) (xy 91.928447 -488.502964) (xy 91.940573 -488.448527) (xy 91.960496 -488.396436)
			(xy 91.987792 -488.347801) (xy 92.021878 -488.303658) (xy 92.062027 -488.264949) (xy 92.107385 -488.232498)
			(xy 92.156985 -488.206997) (xy 92.209769 -488.18899) (xy 92.264612 -488.17886) (xy 92.320346 -488.176823)
			(xy 92.375783 -488.182923) (xy 92.42974 -488.197029) (xy 92.481069 -488.218841) (xy 92.528675 -488.247895)
			(xy 92.571543 -488.28357) (xy 92.60876 -488.325107) (xy 92.639533 -488.37162) (xy 92.663205 -488.422117)
			(xy 92.679273 -488.475524) (xy 92.687393 -488.5307) (xy 92.687902 -488.558586) (xy 92.687393 -488.586472)
			(xy 92.679273 -488.641648) (xy 92.663205 -488.695055) (xy 92.639533 -488.745552) (xy 92.60876 -488.792065)
			(xy 92.571543 -488.833602) (xy 92.528675 -488.869277) (xy 92.481069 -488.898331) (xy 92.42974 -488.920143)
			(xy 92.375783 -488.934249) (xy 92.320346 -488.940349) (xy 92.264612 -488.938312) (xy 92.209769 -488.928182)
			(xy 92.156985 -488.910175) (xy 92.107385 -488.884674) (xy 92.062027 -488.852223) (xy 92.021878 -488.813514)
			(xy 91.987792 -488.769371) (xy 91.960496 -488.720736) (xy 91.940573 -488.668645) (xy 91.928447 -488.614208)
			(xy 91.924376 -488.558586) (xy 86.717944 -488.558586) (xy 86.710493 -488.566902) (xy 86.667625 -488.602577)
			(xy 86.620019 -488.631631) (xy 86.56869 -488.653443) (xy 86.514733 -488.667549) (xy 86.459296 -488.673649)
			(xy 86.403562 -488.671612) (xy 86.348719 -488.661482) (xy 86.295935 -488.643475) (xy 86.246335 -488.617974)
			(xy 86.200977 -488.585523) (xy 86.160828 -488.546814) (xy 86.126742 -488.502671) (xy 86.099446 -488.454036)
			(xy 86.079523 -488.401945) (xy 86.067397 -488.347508) (xy 86.063326 -488.291886) (xy 2.08026 -488.291886)
			(xy 2.08026 -489.813362) (xy 29.519874 -489.813362) (xy 29.519874 -489.726462) (xy 29.527892 -489.639933)
			(xy 29.54386 -489.554513) (xy 29.567641 -489.470931) (xy 29.599033 -489.389899) (xy 29.637767 -489.31211)
			(xy 29.683514 -489.238226) (xy 29.735883 -489.168879) (xy 29.794427 -489.104659) (xy 29.858647 -489.046115)
			(xy 29.927994 -488.993746) (xy 30.001878 -488.947999) (xy 30.079667 -488.909265) (xy 30.160699 -488.877873)
			(xy 30.244281 -488.854092) (xy 30.329701 -488.838124) (xy 30.41623 -488.830106) (xy 30.50313 -488.830106)
			(xy 30.589659 -488.838124) (xy 30.675079 -488.854092) (xy 30.758661 -488.877873) (xy 30.839693 -488.909265)
			(xy 30.917482 -488.947999) (xy 30.991366 -488.993746) (xy 31.060713 -489.046115) (xy 31.124933 -489.104659)
			(xy 31.183477 -489.168879) (xy 31.235846 -489.238226) (xy 31.281593 -489.31211) (xy 31.320327 -489.389899)
			(xy 31.351719 -489.470931) (xy 31.3755 -489.554513) (xy 31.391468 -489.639933) (xy 31.399486 -489.726462)
			(xy 31.399988 -489.769912) (xy 31.399486 -489.813362) (xy 34.599874 -489.813362) (xy 34.599874 -489.726462)
			(xy 34.607892 -489.639933) (xy 34.62386 -489.554513) (xy 34.647641 -489.470931) (xy 34.679033 -489.389899)
			(xy 34.717767 -489.31211) (xy 34.763514 -489.238226) (xy 34.815883 -489.168879) (xy 34.874427 -489.104659)
			(xy 34.938647 -489.046115) (xy 35.007994 -488.993746) (xy 35.081878 -488.947999) (xy 35.159667 -488.909265)
			(xy 35.240699 -488.877873) (xy 35.324281 -488.854092) (xy 35.409701 -488.838124) (xy 35.49623 -488.830106)
			(xy 35.58313 -488.830106) (xy 35.669659 -488.838124) (xy 35.755079 -488.854092) (xy 35.838661 -488.877873)
			(xy 35.919693 -488.909265) (xy 35.997482 -488.947999) (xy 36.071366 -488.993746) (xy 36.140713 -489.046115)
			(xy 36.204933 -489.104659) (xy 36.263477 -489.168879) (xy 36.315846 -489.238226) (xy 36.361593 -489.31211)
			(xy 36.400327 -489.389899) (xy 36.40575 -489.403898) (xy 84.047328 -489.403898) (xy 84.051399 -489.348276)
			(xy 84.063525 -489.293839) (xy 84.083448 -489.241748) (xy 84.110744 -489.193113) (xy 84.14483 -489.14897)
			(xy 84.184979 -489.110261) (xy 84.230337 -489.07781) (xy 84.279937 -489.052309) (xy 84.332721 -489.034302)
			(xy 84.387564 -489.024172) (xy 84.443298 -489.022135) (xy 84.498735 -489.028235) (xy 84.552692 -489.042341)
			(xy 84.604021 -489.064153) (xy 84.651627 -489.093207) (xy 84.694495 -489.128882) (xy 84.731712 -489.170419)
			(xy 84.762485 -489.216932) (xy 84.786157 -489.267429) (xy 84.802225 -489.320836) (xy 84.810345 -489.376012)
			(xy 84.810854 -489.403898) (xy 84.810345 -489.431784) (xy 84.802225 -489.48696) (xy 84.786157 -489.540367)
			(xy 84.762485 -489.590864) (xy 84.731712 -489.637377) (xy 84.694495 -489.678914) (xy 84.651627 -489.714589)
			(xy 84.604021 -489.743643) (xy 84.552692 -489.765455) (xy 84.498735 -489.779561) (xy 84.443298 -489.785661)
			(xy 84.387564 -489.783624) (xy 84.332721 -489.773494) (xy 84.279937 -489.755487) (xy 84.230337 -489.729986)
			(xy 84.184979 -489.697535) (xy 84.14483 -489.658826) (xy 84.110744 -489.614683) (xy 84.083448 -489.566048)
			(xy 84.063525 -489.513957) (xy 84.051399 -489.45952) (xy 84.047328 -489.403898) (xy 36.40575 -489.403898)
			(xy 36.431719 -489.470931) (xy 36.4555 -489.554513) (xy 36.471468 -489.639933) (xy 36.479486 -489.726462)
			(xy 36.479988 -489.769912) (xy 36.479486 -489.813362) (xy 36.471468 -489.899891) (xy 36.4555 -489.985311)
			(xy 36.431719 -490.068893) (xy 36.400327 -490.149925) (xy 36.361593 -490.227714) (xy 36.315846 -490.301598)
			(xy 36.263477 -490.370945) (xy 36.204933 -490.435165) (xy 36.140713 -490.493709) (xy 36.071366 -490.546078)
			(xy 35.997482 -490.591825) (xy 35.919693 -490.630559) (xy 35.838661 -490.661951) (xy 35.755079 -490.685732)
			(xy 35.669659 -490.7017) (xy 35.58313 -490.709718) (xy 35.49623 -490.709718) (xy 35.409701 -490.7017)
			(xy 35.324281 -490.685732) (xy 35.240699 -490.661951) (xy 35.159667 -490.630559) (xy 35.081878 -490.591825)
			(xy 35.007994 -490.546078) (xy 34.938647 -490.493709) (xy 34.874427 -490.435165) (xy 34.815883 -490.370945)
			(xy 34.763514 -490.301598) (xy 34.717767 -490.227714) (xy 34.679033 -490.149925) (xy 34.647641 -490.068893)
			(xy 34.62386 -489.985311) (xy 34.607892 -489.899891) (xy 34.599874 -489.813362) (xy 31.399486 -489.813362)
			(xy 31.391468 -489.899891) (xy 31.3755 -489.985311) (xy 31.351719 -490.068893) (xy 31.320327 -490.149925)
			(xy 31.281593 -490.227714) (xy 31.235846 -490.301598) (xy 31.183477 -490.370945) (xy 31.124933 -490.435165)
			(xy 31.060713 -490.493709) (xy 30.991366 -490.546078) (xy 30.917482 -490.591825) (xy 30.839693 -490.630559)
			(xy 30.758661 -490.661951) (xy 30.675079 -490.685732) (xy 30.589659 -490.7017) (xy 30.50313 -490.709718)
			(xy 30.41623 -490.709718) (xy 30.329701 -490.7017) (xy 30.244281 -490.685732) (xy 30.160699 -490.661951)
			(xy 30.079667 -490.630559) (xy 30.001878 -490.591825) (xy 29.927994 -490.546078) (xy 29.858647 -490.493709)
			(xy 29.794427 -490.435165) (xy 29.735883 -490.370945) (xy 29.683514 -490.301598) (xy 29.637767 -490.227714)
			(xy 29.599033 -490.149925) (xy 29.567641 -490.068893) (xy 29.54386 -489.985311) (xy 29.527892 -489.899891)
			(xy 29.519874 -489.813362) (xy 2.08026 -489.813362) (xy 2.08026 -491.999778) (xy 6.671831 -491.999778)
			(xy 6.675786 -491.907941) (xy 6.687621 -491.816784) (xy 6.707248 -491.726981) (xy 6.734522 -491.639199)
			(xy 6.769242 -491.554085) (xy 6.81115 -491.472272) (xy 6.859936 -491.394364) (xy 6.915239 -491.320939)
			(xy 6.976649 -491.252539) (xy 7.043711 -491.189672) (xy 7.11593 -491.132802) (xy 7.19277 -491.082351)
			(xy 7.273663 -491.038692) (xy 7.358009 -491.002149) (xy 7.445185 -490.972992) (xy 7.534544 -490.951438)
			(xy 7.625425 -490.937644) (xy 7.717156 -490.931714) (xy 7.809057 -490.933692) (xy 7.900448 -490.943563)
			(xy 7.990652 -490.961253) (xy 8.079001 -490.986633) (xy 8.164841 -491.019513) (xy 8.247537 -491.059651)
			(xy 8.326477 -491.10675) (xy 8.401075 -491.16046) (xy 8.470781 -491.220384) (xy 8.535076 -491.286078)
			(xy 8.593487 -491.357056) (xy 8.645579 -491.432793) (xy 8.690968 -491.512728) (xy 8.729318 -491.596268)
			(xy 8.760343 -491.682796) (xy 8.783816 -491.771671) (xy 8.799562 -491.862235) (xy 8.807464 -491.953817)
			(xy 8.807958 -491.999778) (xy 8.807464 -492.045739) (xy 8.799562 -492.137321) (xy 8.783816 -492.227885)
			(xy 8.760343 -492.31676) (xy 8.747219 -492.353362) (xy 29.519874 -492.353362) (xy 29.519874 -492.266462)
			(xy 29.527892 -492.179933) (xy 29.54386 -492.094513) (xy 29.567641 -492.010931) (xy 29.599033 -491.929899)
			(xy 29.637767 -491.85211) (xy 29.683514 -491.778226) (xy 29.735883 -491.708879) (xy 29.794427 -491.644659)
			(xy 29.858647 -491.586115) (xy 29.927994 -491.533746) (xy 30.001878 -491.487999) (xy 30.079667 -491.449265)
			(xy 30.160699 -491.417873) (xy 30.244281 -491.394092) (xy 30.329701 -491.378124) (xy 30.41623 -491.370106)
			(xy 30.50313 -491.370106) (xy 30.589659 -491.378124) (xy 30.675079 -491.394092) (xy 30.758661 -491.417873)
			(xy 30.839693 -491.449265) (xy 30.917482 -491.487999) (xy 30.991366 -491.533746) (xy 31.060713 -491.586115)
			(xy 31.124933 -491.644659) (xy 31.183477 -491.708879) (xy 31.235846 -491.778226) (xy 31.281593 -491.85211)
			(xy 31.320327 -491.929899) (xy 31.351719 -492.010931) (xy 31.3755 -492.094513) (xy 31.391468 -492.179933)
			(xy 31.399486 -492.266462) (xy 31.399988 -492.309912) (xy 31.399486 -492.353362) (xy 34.599874 -492.353362)
			(xy 34.599874 -492.266462) (xy 34.607892 -492.179933) (xy 34.62386 -492.094513) (xy 34.647641 -492.010931)
			(xy 34.679033 -491.929899) (xy 34.717767 -491.85211) (xy 34.763514 -491.778226) (xy 34.815883 -491.708879)
			(xy 34.874427 -491.644659) (xy 34.938647 -491.586115) (xy 35.007994 -491.533746) (xy 35.081878 -491.487999)
			(xy 35.159667 -491.449265) (xy 35.240699 -491.417873) (xy 35.324281 -491.394092) (xy 35.409701 -491.378124)
			(xy 35.49623 -491.370106) (xy 35.58313 -491.370106) (xy 35.669659 -491.378124) (xy 35.755079 -491.394092)
			(xy 35.838661 -491.417873) (xy 35.919693 -491.449265) (xy 35.997482 -491.487999) (xy 36.071366 -491.533746)
			(xy 36.140713 -491.586115) (xy 36.204933 -491.644659) (xy 36.263477 -491.708879) (xy 36.315846 -491.778226)
			(xy 36.361593 -491.85211) (xy 36.400327 -491.929899) (xy 36.431719 -492.010931) (xy 36.4555 -492.094513)
			(xy 36.471468 -492.179933) (xy 36.479486 -492.266462) (xy 36.479988 -492.309912) (xy 36.479486 -492.353362)
			(xy 36.471468 -492.439891) (xy 36.4555 -492.525311) (xy 36.431719 -492.608893) (xy 36.400327 -492.689925)
			(xy 36.361593 -492.767714) (xy 36.315846 -492.841598) (xy 36.263477 -492.910945) (xy 36.204933 -492.975165)
			(xy 36.140713 -493.033709) (xy 36.071366 -493.086078) (xy 35.997482 -493.131825) (xy 35.919693 -493.170559)
			(xy 35.838661 -493.201951) (xy 35.755079 -493.225732) (xy 35.669659 -493.2417) (xy 35.58313 -493.249718)
			(xy 35.49623 -493.249718) (xy 35.409701 -493.2417) (xy 35.324281 -493.225732) (xy 35.240699 -493.201951)
			(xy 35.159667 -493.170559) (xy 35.081878 -493.131825) (xy 35.007994 -493.086078) (xy 34.938647 -493.033709)
			(xy 34.874427 -492.975165) (xy 34.815883 -492.910945) (xy 34.763514 -492.841598) (xy 34.717767 -492.767714)
			(xy 34.679033 -492.689925) (xy 34.647641 -492.608893) (xy 34.62386 -492.525311) (xy 34.607892 -492.439891)
			(xy 34.599874 -492.353362) (xy 31.399486 -492.353362) (xy 31.391468 -492.439891) (xy 31.3755 -492.525311)
			(xy 31.351719 -492.608893) (xy 31.320327 -492.689925) (xy 31.281593 -492.767714) (xy 31.235846 -492.841598)
			(xy 31.183477 -492.910945) (xy 31.124933 -492.975165) (xy 31.060713 -493.033709) (xy 30.991366 -493.086078)
			(xy 30.917482 -493.131825) (xy 30.839693 -493.170559) (xy 30.758661 -493.201951) (xy 30.675079 -493.225732)
			(xy 30.589659 -493.2417) (xy 30.50313 -493.249718) (xy 30.41623 -493.249718) (xy 30.329701 -493.2417)
			(xy 30.244281 -493.225732) (xy 30.160699 -493.201951) (xy 30.079667 -493.170559) (xy 30.001878 -493.131825)
			(xy 29.927994 -493.086078) (xy 29.858647 -493.033709) (xy 29.794427 -492.975165) (xy 29.735883 -492.910945)
			(xy 29.683514 -492.841598) (xy 29.637767 -492.767714) (xy 29.599033 -492.689925) (xy 29.567641 -492.608893)
			(xy 29.54386 -492.525311) (xy 29.527892 -492.439891) (xy 29.519874 -492.353362) (xy 8.747219 -492.353362)
			(xy 8.729318 -492.403288) (xy 8.690968 -492.486828) (xy 8.645579 -492.566763) (xy 8.593487 -492.6425)
			(xy 8.535076 -492.713478) (xy 8.470781 -492.779172) (xy 8.401075 -492.839096) (xy 8.326477 -492.892806)
			(xy 8.247537 -492.939905) (xy 8.164841 -492.980043) (xy 8.079001 -493.012923) (xy 7.990652 -493.038303)
			(xy 7.900448 -493.055993) (xy 7.809057 -493.065864) (xy 7.717156 -493.067842) (xy 7.625425 -493.061912)
			(xy 7.534544 -493.048118) (xy 7.445185 -493.026564) (xy 7.358009 -492.997407) (xy 7.273663 -492.960864)
			(xy 7.19277 -492.917205) (xy 7.11593 -492.866754) (xy 7.043711 -492.809884) (xy 6.976649 -492.747017)
			(xy 6.915239 -492.678617) (xy 6.859936 -492.605192) (xy 6.81115 -492.527284) (xy 6.769242 -492.445471)
			(xy 6.734522 -492.360357) (xy 6.707248 -492.272575) (xy 6.687621 -492.182772) (xy 6.675786 -492.091615)
			(xy 6.671831 -491.999778) (xy 2.08026 -491.999778) (xy 2.08026 -493.832642) (xy 3.290253 -495.042635)
			(xy 4.852911 -495.042635) (xy 4.852911 -494.956909) (xy 4.860821 -494.871549) (xy 4.876573 -494.787282)
			(xy 4.900033 -494.704829) (xy 4.931001 -494.624892) (xy 4.969212 -494.548153) (xy 5.014341 -494.475267)
			(xy 5.066002 -494.406856) (xy 5.123756 -494.343504) (xy 5.187108 -494.28575) (xy 5.255519 -494.234089)
			(xy 5.328405 -494.18896) (xy 5.405144 -494.150749) (xy 5.485081 -494.119781) (xy 5.567534 -494.096321)
			(xy 5.651801 -494.080569) (xy 5.737161 -494.072659) (xy 5.822887 -494.072659) (xy 5.908247 -494.080569)
			(xy 5.992514 -494.096321) (xy 6.074967 -494.119781) (xy 6.154904 -494.150749) (xy 6.231643 -494.18896)
			(xy 6.304529 -494.234089) (xy 6.37294 -494.28575) (xy 6.436292 -494.343504) (xy 6.494046 -494.406856)
			(xy 6.545707 -494.475267) (xy 6.590836 -494.548153) (xy 6.629047 -494.624892) (xy 6.660015 -494.704829)
			(xy 6.683475 -494.787282) (xy 6.699227 -494.871549) (xy 6.701248 -494.893362) (xy 29.519874 -494.893362)
			(xy 29.519874 -494.806462) (xy 29.527892 -494.719933) (xy 29.54386 -494.634513) (xy 29.567641 -494.550931)
			(xy 29.599033 -494.469899) (xy 29.637767 -494.39211) (xy 29.683514 -494.318226) (xy 29.735883 -494.248879)
			(xy 29.794427 -494.184659) (xy 29.858647 -494.126115) (xy 29.927994 -494.073746) (xy 30.001878 -494.027999)
			(xy 30.079667 -493.989265) (xy 30.160699 -493.957873) (xy 30.244281 -493.934092) (xy 30.329701 -493.918124)
			(xy 30.41623 -493.910106) (xy 30.50313 -493.910106) (xy 30.589659 -493.918124) (xy 30.675079 -493.934092)
			(xy 30.758661 -493.957873) (xy 30.839693 -493.989265) (xy 30.917482 -494.027999) (xy 30.991366 -494.073746)
			(xy 31.060713 -494.126115) (xy 31.124933 -494.184659) (xy 31.183477 -494.248879) (xy 31.235846 -494.318226)
			(xy 31.281593 -494.39211) (xy 31.320327 -494.469899) (xy 31.351719 -494.550931) (xy 31.3755 -494.634513)
			(xy 31.391468 -494.719933) (xy 31.399486 -494.806462) (xy 31.399988 -494.849912) (xy 31.399486 -494.893362)
			(xy 34.599874 -494.893362) (xy 34.599874 -494.806462) (xy 34.607892 -494.719933) (xy 34.62386 -494.634513)
			(xy 34.647641 -494.550931) (xy 34.679033 -494.469899) (xy 34.717767 -494.39211) (xy 34.763514 -494.318226)
			(xy 34.815883 -494.248879) (xy 34.874427 -494.184659) (xy 34.938647 -494.126115) (xy 35.007994 -494.073746)
			(xy 35.081878 -494.027999) (xy 35.159667 -493.989265) (xy 35.240699 -493.957873) (xy 35.324281 -493.934092)
			(xy 35.409701 -493.918124) (xy 35.49623 -493.910106) (xy 35.58313 -493.910106) (xy 35.669659 -493.918124)
			(xy 35.755079 -493.934092) (xy 35.838661 -493.957873) (xy 35.919693 -493.989265) (xy 35.997482 -494.027999)
			(xy 36.071366 -494.073746) (xy 36.140713 -494.126115) (xy 36.204933 -494.184659) (xy 36.263477 -494.248879)
			(xy 36.315846 -494.318226) (xy 36.361593 -494.39211) (xy 36.400327 -494.469899) (xy 36.431719 -494.550931)
			(xy 36.4555 -494.634513) (xy 36.471468 -494.719933) (xy 36.479486 -494.806462) (xy 36.479988 -494.849912)
			(xy 36.479486 -494.893362) (xy 36.471468 -494.979891) (xy 36.4555 -495.065311) (xy 36.431719 -495.148893)
			(xy 36.400327 -495.229925) (xy 36.361593 -495.307714) (xy 36.315846 -495.381598) (xy 36.263477 -495.450945)
			(xy 36.204933 -495.515165) (xy 36.140713 -495.573709) (xy 36.071366 -495.626078) (xy 35.997482 -495.671825)
			(xy 35.919693 -495.710559) (xy 35.838661 -495.741951) (xy 35.755079 -495.765732) (xy 35.669659 -495.7817)
			(xy 35.58313 -495.789718) (xy 35.49623 -495.789718) (xy 35.409701 -495.7817) (xy 35.324281 -495.765732)
			(xy 35.240699 -495.741951) (xy 35.159667 -495.710559) (xy 35.081878 -495.671825) (xy 35.007994 -495.626078)
			(xy 34.938647 -495.573709) (xy 34.874427 -495.515165) (xy 34.815883 -495.450945) (xy 34.763514 -495.381598)
			(xy 34.717767 -495.307714) (xy 34.679033 -495.229925) (xy 34.647641 -495.148893) (xy 34.62386 -495.065311)
			(xy 34.607892 -494.979891) (xy 34.599874 -494.893362) (xy 31.399486 -494.893362) (xy 31.391468 -494.979891)
			(xy 31.3755 -495.065311) (xy 31.351719 -495.148893) (xy 31.320327 -495.229925) (xy 31.281593 -495.307714)
			(xy 31.235846 -495.381598) (xy 31.183477 -495.450945) (xy 31.124933 -495.515165) (xy 31.060713 -495.573709)
			(xy 30.991366 -495.626078) (xy 30.917482 -495.671825) (xy 30.839693 -495.710559) (xy 30.758661 -495.741951)
			(xy 30.675079 -495.765732) (xy 30.589659 -495.7817) (xy 30.50313 -495.789718) (xy 30.41623 -495.789718)
			(xy 30.329701 -495.7817) (xy 30.244281 -495.765732) (xy 30.160699 -495.741951) (xy 30.079667 -495.710559)
			(xy 30.001878 -495.671825) (xy 29.927994 -495.626078) (xy 29.858647 -495.573709) (xy 29.794427 -495.515165)
			(xy 29.735883 -495.450945) (xy 29.683514 -495.381598) (xy 29.637767 -495.307714) (xy 29.599033 -495.229925)
			(xy 29.567641 -495.148893) (xy 29.54386 -495.065311) (xy 29.527892 -494.979891) (xy 29.519874 -494.893362)
			(xy 6.701248 -494.893362) (xy 6.707137 -494.956909) (xy 6.707632 -494.999772) (xy 6.707137 -495.042635)
			(xy 6.699227 -495.127995) (xy 6.683475 -495.212262) (xy 6.660015 -495.294715) (xy 6.629047 -495.374652)
			(xy 6.590836 -495.451391) (xy 6.545707 -495.524277) (xy 6.494046 -495.592688) (xy 6.436292 -495.65604)
			(xy 6.37294 -495.713794) (xy 6.304529 -495.765455) (xy 6.231643 -495.810584) (xy 6.154904 -495.848795)
			(xy 6.1258 -495.86007) (xy 39.818564 -495.86007) (xy 39.819058 -495.802661) (xy 39.826902 -495.688113)
			(xy 39.842544 -495.574366) (xy 39.865911 -495.461952) (xy 39.896896 -495.351394) (xy 39.935352 -495.243209)
			(xy 39.981101 -495.1379) (xy 40.03393 -495.035958) (xy 40.093592 -494.937859) (xy 40.159809 -494.84406)
			(xy 40.232272 -494.754998) (xy 40.310645 -494.671089) (xy 40.39456 -494.592723) (xy 40.483627 -494.520266)
			(xy 40.577431 -494.454056) (xy 40.675535 -494.394402) (xy 40.777481 -494.341581) (xy 40.882793 -494.295839)
			(xy 40.990981 -494.257391) (xy 41.101541 -494.226415) (xy 41.213957 -494.203056) (xy 41.327705 -494.187423)
			(xy 41.442254 -494.179588) (xy 41.557072 -494.179588) (xy 41.671621 -494.187423) (xy 41.785369 -494.203056)
			(xy 41.897785 -494.226415) (xy 42.008345 -494.257391) (xy 42.116533 -494.295839) (xy 42.221845 -494.341581)
			(xy 42.323791 -494.394402) (xy 42.421895 -494.454056) (xy 42.501239 -494.51006) (xy 43.327577 -494.51006)
			(xy 43.331612 -494.434356) (xy 43.343671 -494.359511) (xy 43.363617 -494.28637) (xy 43.391224 -494.215765)
			(xy 43.42618 -494.148494) (xy 43.468088 -494.085319) (xy 43.516474 -494.026957) (xy 43.57079 -493.974069)
			(xy 43.630419 -493.927254) (xy 43.694687 -493.887042) (xy 43.762864 -493.85389) (xy 43.83418 -493.828172)
			(xy 43.907825 -493.81018) (xy 43.982965 -493.800118) (xy 44.058749 -493.798099) (xy 44.134319 -493.804148)
			(xy 44.208817 -493.818195) (xy 44.2814 -493.840081) (xy 44.351246 -493.869558) (xy 44.417563 -493.906293)
			(xy 44.479599 -493.949868) (xy 44.536652 -493.99979) (xy 44.588076 -494.055494) (xy 44.633287 -494.116349)
			(xy 44.671774 -494.181664) (xy 44.7031 -494.2507) (xy 44.72691 -494.322675) (xy 44.742935 -494.396773)
			(xy 44.750994 -494.472154) (xy 44.751498 -494.51006) (xy 45.867577 -494.51006) (xy 45.871612 -494.434356)
			(xy 45.883671 -494.359511) (xy 45.903617 -494.28637) (xy 45.931224 -494.215765) (xy 45.96618 -494.148494)
			(xy 46.008088 -494.085319) (xy 46.056474 -494.026957) (xy 46.11079 -493.974069) (xy 46.170419 -493.927254)
			(xy 46.234687 -493.887042) (xy 46.302864 -493.85389) (xy 46.37418 -493.828172) (xy 46.447825 -493.81018)
			(xy 46.522965 -493.800118) (xy 46.598749 -493.798099) (xy 46.674319 -493.804148) (xy 46.748817 -493.818195)
			(xy 46.8214 -493.840081) (xy 46.891246 -493.869558) (xy 46.957563 -493.906293) (xy 47.019599 -493.949868)
			(xy 47.076652 -493.99979) (xy 47.128076 -494.055494) (xy 47.173287 -494.116349) (xy 47.211774 -494.181664)
			(xy 47.2431 -494.2507) (xy 47.26691 -494.322675) (xy 47.282935 -494.396773) (xy 47.290994 -494.472154)
			(xy 47.291498 -494.51006) (xy 48.407577 -494.51006) (xy 48.411612 -494.434356) (xy 48.423671 -494.359511)
			(xy 48.443617 -494.28637) (xy 48.471224 -494.215765) (xy 48.50618 -494.148494) (xy 48.548088 -494.085319)
			(xy 48.596474 -494.026957) (xy 48.65079 -493.974069) (xy 48.710419 -493.927254) (xy 48.774687 -493.887042)
			(xy 48.842864 -493.85389) (xy 48.91418 -493.828172) (xy 48.987825 -493.81018) (xy 49.062965 -493.800118)
			(xy 49.138749 -493.798099) (xy 49.214319 -493.804148) (xy 49.288817 -493.818195) (xy 49.3614 -493.840081)
			(xy 49.431246 -493.869558) (xy 49.497563 -493.906293) (xy 49.559599 -493.949868) (xy 49.616652 -493.99979)
			(xy 49.668076 -494.055494) (xy 49.713287 -494.116349) (xy 49.751774 -494.181664) (xy 49.7831 -494.2507)
			(xy 49.80691 -494.322675) (xy 49.822935 -494.396773) (xy 49.830994 -494.472154) (xy 49.831498 -494.51006)
			(xy 50.947577 -494.51006) (xy 50.951612 -494.434356) (xy 50.963671 -494.359511) (xy 50.983617 -494.28637)
			(xy 51.011224 -494.215765) (xy 51.04618 -494.148494) (xy 51.088088 -494.085319) (xy 51.136474 -494.026957)
			(xy 51.19079 -493.974069) (xy 51.250419 -493.927254) (xy 51.314687 -493.887042) (xy 51.382864 -493.85389)
			(xy 51.45418 -493.828172) (xy 51.527825 -493.81018) (xy 51.602965 -493.800118) (xy 51.678749 -493.798099)
			(xy 51.754319 -493.804148) (xy 51.828817 -493.818195) (xy 51.9014 -493.840081) (xy 51.971246 -493.869558)
			(xy 52.037563 -493.906293) (xy 52.099599 -493.949868) (xy 52.156652 -493.99979) (xy 52.208076 -494.055494)
			(xy 52.253287 -494.116349) (xy 52.291774 -494.181664) (xy 52.3231 -494.2507) (xy 52.34691 -494.322675)
			(xy 52.362935 -494.396773) (xy 52.370994 -494.472154) (xy 52.371498 -494.51006) (xy 53.487577 -494.51006)
			(xy 53.491612 -494.434356) (xy 53.503671 -494.359511) (xy 53.523617 -494.28637) (xy 53.551224 -494.215765)
			(xy 53.58618 -494.148494) (xy 53.628088 -494.085319) (xy 53.676474 -494.026957) (xy 53.73079 -493.974069)
			(xy 53.790419 -493.927254) (xy 53.854687 -493.887042) (xy 53.922864 -493.85389) (xy 53.99418 -493.828172)
			(xy 54.067825 -493.81018) (xy 54.142965 -493.800118) (xy 54.218749 -493.798099) (xy 54.294319 -493.804148)
			(xy 54.368817 -493.818195) (xy 54.4414 -493.840081) (xy 54.511246 -493.869558) (xy 54.577563 -493.906293)
			(xy 54.639599 -493.949868) (xy 54.696652 -493.99979) (xy 54.748076 -494.055494) (xy 54.793287 -494.116349)
			(xy 54.831774 -494.181664) (xy 54.8631 -494.2507) (xy 54.88691 -494.322675) (xy 54.902935 -494.396773)
			(xy 54.910994 -494.472154) (xy 54.911498 -494.51006) (xy 56.027577 -494.51006) (xy 56.031612 -494.434356)
			(xy 56.043671 -494.359511) (xy 56.063617 -494.28637) (xy 56.091224 -494.215765) (xy 56.12618 -494.148494)
			(xy 56.168088 -494.085319) (xy 56.216474 -494.026957) (xy 56.27079 -493.974069) (xy 56.330419 -493.927254)
			(xy 56.394687 -493.887042) (xy 56.462864 -493.85389) (xy 56.53418 -493.828172) (xy 56.607825 -493.81018)
			(xy 56.682965 -493.800118) (xy 56.758749 -493.798099) (xy 56.834319 -493.804148) (xy 56.908817 -493.818195)
			(xy 56.9814 -493.840081) (xy 57.051246 -493.869558) (xy 57.117563 -493.906293) (xy 57.179599 -493.949868)
			(xy 57.236652 -493.99979) (xy 57.288076 -494.055494) (xy 57.333287 -494.116349) (xy 57.371774 -494.181664)
			(xy 57.4031 -494.2507) (xy 57.42691 -494.322675) (xy 57.442935 -494.396773) (xy 57.450994 -494.472154)
			(xy 57.451498 -494.51006) (xy 58.567577 -494.51006) (xy 58.571612 -494.434356) (xy 58.583671 -494.359511)
			(xy 58.603617 -494.28637) (xy 58.631224 -494.215765) (xy 58.66618 -494.148494) (xy 58.708088 -494.085319)
			(xy 58.756474 -494.026957) (xy 58.81079 -493.974069) (xy 58.870419 -493.927254) (xy 58.934687 -493.887042)
			(xy 59.002864 -493.85389) (xy 59.07418 -493.828172) (xy 59.147825 -493.81018) (xy 59.222965 -493.800118)
			(xy 59.298749 -493.798099) (xy 59.374319 -493.804148) (xy 59.448817 -493.818195) (xy 59.5214 -493.840081)
			(xy 59.591246 -493.869558) (xy 59.657563 -493.906293) (xy 59.719599 -493.949868) (xy 59.776652 -493.99979)
			(xy 59.828076 -494.055494) (xy 59.873287 -494.116349) (xy 59.911774 -494.181664) (xy 59.9431 -494.2507)
			(xy 59.96691 -494.322675) (xy 59.982935 -494.396773) (xy 59.990994 -494.472154) (xy 59.991498 -494.51006)
			(xy 61.107577 -494.51006) (xy 61.111612 -494.434356) (xy 61.123671 -494.359511) (xy 61.143617 -494.28637)
			(xy 61.171224 -494.215765) (xy 61.20618 -494.148494) (xy 61.248088 -494.085319) (xy 61.296474 -494.026957)
			(xy 61.35079 -493.974069) (xy 61.410419 -493.927254) (xy 61.474687 -493.887042) (xy 61.542864 -493.85389)
			(xy 61.61418 -493.828172) (xy 61.687825 -493.81018) (xy 61.762965 -493.800118) (xy 61.838749 -493.798099)
			(xy 61.914319 -493.804148) (xy 61.988817 -493.818195) (xy 62.0614 -493.840081) (xy 62.131246 -493.869558)
			(xy 62.197563 -493.906293) (xy 62.259599 -493.949868) (xy 62.265544 -493.95507) (xy 86.197697 -493.95507)
			(xy 86.201732 -493.879366) (xy 86.213791 -493.804521) (xy 86.233737 -493.73138) (xy 86.261344 -493.660775)
			(xy 86.2963 -493.593504) (xy 86.338208 -493.530329) (xy 86.386594 -493.471967) (xy 86.44091 -493.419079)
			(xy 86.500539 -493.372264) (xy 86.564807 -493.332052) (xy 86.632984 -493.2989) (xy 86.7043 -493.273182)
			(xy 86.777945 -493.25519) (xy 86.853085 -493.245128) (xy 86.928869 -493.243109) (xy 87.004439 -493.249158)
			(xy 87.078937 -493.263205) (xy 87.15152 -493.285091) (xy 87.221366 -493.314568) (xy 87.287683 -493.351303)
			(xy 87.349719 -493.394878) (xy 87.406772 -493.4448) (xy 87.458196 -493.500504) (xy 87.503407 -493.561359)
			(xy 87.541894 -493.626674) (xy 87.57322 -493.69571) (xy 87.59703 -493.767685) (xy 87.613055 -493.841783)
			(xy 87.621114 -493.917164) (xy 87.621618 -493.95507) (xy 88.737697 -493.95507) (xy 88.741732 -493.879366)
			(xy 88.753791 -493.804521) (xy 88.773737 -493.73138) (xy 88.801344 -493.660775) (xy 88.8363 -493.593504)
			(xy 88.878208 -493.530329) (xy 88.926594 -493.471967) (xy 88.98091 -493.419079) (xy 89.040539 -493.372264)
			(xy 89.104807 -493.332052) (xy 89.172984 -493.2989) (xy 89.2443 -493.273182) (xy 89.317945 -493.25519)
			(xy 89.393085 -493.245128) (xy 89.468869 -493.243109) (xy 89.544439 -493.249158) (xy 89.618937 -493.263205)
			(xy 89.69152 -493.285091) (xy 89.761366 -493.314568) (xy 89.827683 -493.351303) (xy 89.889719 -493.394878)
			(xy 89.946772 -493.4448) (xy 89.998196 -493.500504) (xy 90.043407 -493.561359) (xy 90.081894 -493.626674)
			(xy 90.11322 -493.69571) (xy 90.13703 -493.767685) (xy 90.153055 -493.841783) (xy 90.161114 -493.917164)
			(xy 90.161618 -493.95507) (xy 91.277697 -493.95507) (xy 91.281732 -493.879366) (xy 91.293791 -493.804521)
			(xy 91.313737 -493.73138) (xy 91.341344 -493.660775) (xy 91.3763 -493.593504) (xy 91.418208 -493.530329)
			(xy 91.466594 -493.471967) (xy 91.52091 -493.419079) (xy 91.580539 -493.372264) (xy 91.644807 -493.332052)
			(xy 91.712984 -493.2989) (xy 91.7843 -493.273182) (xy 91.857945 -493.25519) (xy 91.933085 -493.245128)
			(xy 92.008869 -493.243109) (xy 92.084439 -493.249158) (xy 92.158937 -493.263205) (xy 92.23152 -493.285091)
			(xy 92.301366 -493.314568) (xy 92.367683 -493.351303) (xy 92.429719 -493.394878) (xy 92.486772 -493.4448)
			(xy 92.538196 -493.500504) (xy 92.583407 -493.561359) (xy 92.621894 -493.626674) (xy 92.65322 -493.69571)
			(xy 92.67703 -493.767685) (xy 92.693055 -493.841783) (xy 92.701114 -493.917164) (xy 92.701618 -493.95507)
			(xy 92.701114 -493.992976) (xy 92.693055 -494.068357) (xy 92.67703 -494.142455) (xy 92.65322 -494.21443)
			(xy 92.621894 -494.283466) (xy 92.583407 -494.348781) (xy 92.538196 -494.409636) (xy 92.486772 -494.46534)
			(xy 92.429719 -494.515262) (xy 92.367683 -494.558837) (xy 92.301366 -494.595572) (xy 92.23152 -494.625049)
			(xy 92.158937 -494.646935) (xy 92.084439 -494.660982) (xy 92.008869 -494.667031) (xy 91.933085 -494.665012)
			(xy 91.857945 -494.65495) (xy 91.7843 -494.636958) (xy 91.712984 -494.61124) (xy 91.644807 -494.578088)
			(xy 91.580539 -494.537876) (xy 91.52091 -494.491061) (xy 91.466594 -494.438173) (xy 91.418208 -494.379811)
			(xy 91.3763 -494.316636) (xy 91.341344 -494.249365) (xy 91.313737 -494.17876) (xy 91.293791 -494.105619)
			(xy 91.281732 -494.030774) (xy 91.277697 -493.95507) (xy 90.161618 -493.95507) (xy 90.161114 -493.992976)
			(xy 90.153055 -494.068357) (xy 90.13703 -494.142455) (xy 90.11322 -494.21443) (xy 90.081894 -494.283466)
			(xy 90.043407 -494.348781) (xy 89.998196 -494.409636) (xy 89.946772 -494.46534) (xy 89.889719 -494.515262)
			(xy 89.827683 -494.558837) (xy 89.761366 -494.595572) (xy 89.69152 -494.625049) (xy 89.618937 -494.646935)
			(xy 89.544439 -494.660982) (xy 89.468869 -494.667031) (xy 89.393085 -494.665012) (xy 89.317945 -494.65495)
			(xy 89.2443 -494.636958) (xy 89.172984 -494.61124) (xy 89.104807 -494.578088) (xy 89.040539 -494.537876)
			(xy 88.98091 -494.491061) (xy 88.926594 -494.438173) (xy 88.878208 -494.379811) (xy 88.8363 -494.316636)
			(xy 88.801344 -494.249365) (xy 88.773737 -494.17876) (xy 88.753791 -494.105619) (xy 88.741732 -494.030774)
			(xy 88.737697 -493.95507) (xy 87.621618 -493.95507) (xy 87.621114 -493.992976) (xy 87.613055 -494.068357)
			(xy 87.59703 -494.142455) (xy 87.57322 -494.21443) (xy 87.541894 -494.283466) (xy 87.503407 -494.348781)
			(xy 87.458196 -494.409636) (xy 87.406772 -494.46534) (xy 87.349719 -494.515262) (xy 87.287683 -494.558837)
			(xy 87.221366 -494.595572) (xy 87.15152 -494.625049) (xy 87.078937 -494.646935) (xy 87.004439 -494.660982)
			(xy 86.928869 -494.667031) (xy 86.853085 -494.665012) (xy 86.777945 -494.65495) (xy 86.7043 -494.636958)
			(xy 86.632984 -494.61124) (xy 86.564807 -494.578088) (xy 86.500539 -494.537876) (xy 86.44091 -494.491061)
			(xy 86.386594 -494.438173) (xy 86.338208 -494.379811) (xy 86.2963 -494.316636) (xy 86.261344 -494.249365)
			(xy 86.233737 -494.17876) (xy 86.213791 -494.105619) (xy 86.201732 -494.030774) (xy 86.197697 -493.95507)
			(xy 62.265544 -493.95507) (xy 62.316652 -493.99979) (xy 62.368076 -494.055494) (xy 62.413287 -494.116349)
			(xy 62.451774 -494.181664) (xy 62.4831 -494.2507) (xy 62.50691 -494.322675) (xy 62.522935 -494.396773)
			(xy 62.530994 -494.472154) (xy 62.531498 -494.51006) (xy 62.530994 -494.547966) (xy 62.522935 -494.623347)
			(xy 62.50691 -494.697445) (xy 62.4831 -494.76942) (xy 62.451774 -494.838456) (xy 62.413287 -494.903771)
			(xy 62.368076 -494.964626) (xy 62.316652 -495.02033) (xy 62.259599 -495.070252) (xy 62.197563 -495.113827)
			(xy 62.131246 -495.150562) (xy 62.0614 -495.180039) (xy 61.988817 -495.201925) (xy 61.914319 -495.215972)
			(xy 61.838749 -495.222021) (xy 61.762965 -495.220002) (xy 61.687825 -495.20994) (xy 61.61418 -495.191948)
			(xy 61.542864 -495.16623) (xy 61.474687 -495.133078) (xy 61.410419 -495.092866) (xy 61.35079 -495.046051)
			(xy 61.296474 -494.993163) (xy 61.248088 -494.934801) (xy 61.20618 -494.871626) (xy 61.171224 -494.804355)
			(xy 61.143617 -494.73375) (xy 61.123671 -494.660609) (xy 61.111612 -494.585764) (xy 61.107577 -494.51006)
			(xy 59.991498 -494.51006) (xy 59.990994 -494.547966) (xy 59.982935 -494.623347) (xy 59.96691 -494.697445)
			(xy 59.9431 -494.76942) (xy 59.911774 -494.838456) (xy 59.873287 -494.903771) (xy 59.828076 -494.964626)
			(xy 59.776652 -495.02033) (xy 59.719599 -495.070252) (xy 59.657563 -495.113827) (xy 59.591246 -495.150562)
			(xy 59.5214 -495.180039) (xy 59.448817 -495.201925) (xy 59.374319 -495.215972) (xy 59.298749 -495.222021)
			(xy 59.222965 -495.220002) (xy 59.147825 -495.20994) (xy 59.07418 -495.191948) (xy 59.002864 -495.16623)
			(xy 58.934687 -495.133078) (xy 58.870419 -495.092866) (xy 58.81079 -495.046051) (xy 58.756474 -494.993163)
			(xy 58.708088 -494.934801) (xy 58.66618 -494.871626) (xy 58.631224 -494.804355) (xy 58.603617 -494.73375)
			(xy 58.583671 -494.660609) (xy 58.571612 -494.585764) (xy 58.567577 -494.51006) (xy 57.451498 -494.51006)
			(xy 57.450994 -494.547966) (xy 57.442935 -494.623347) (xy 57.42691 -494.697445) (xy 57.4031 -494.76942)
			(xy 57.371774 -494.838456) (xy 57.333287 -494.903771) (xy 57.288076 -494.964626) (xy 57.236652 -495.02033)
			(xy 57.179599 -495.070252) (xy 57.117563 -495.113827) (xy 57.051246 -495.150562) (xy 56.9814 -495.180039)
			(xy 56.908817 -495.201925) (xy 56.834319 -495.215972) (xy 56.758749 -495.222021) (xy 56.682965 -495.220002)
			(xy 56.607825 -495.20994) (xy 56.53418 -495.191948) (xy 56.462864 -495.16623) (xy 56.394687 -495.133078)
			(xy 56.330419 -495.092866) (xy 56.27079 -495.046051) (xy 56.216474 -494.993163) (xy 56.168088 -494.934801)
			(xy 56.12618 -494.871626) (xy 56.091224 -494.804355) (xy 56.063617 -494.73375) (xy 56.043671 -494.660609)
			(xy 56.031612 -494.585764) (xy 56.027577 -494.51006) (xy 54.911498 -494.51006) (xy 54.910994 -494.547966)
			(xy 54.902935 -494.623347) (xy 54.88691 -494.697445) (xy 54.8631 -494.76942) (xy 54.831774 -494.838456)
			(xy 54.793287 -494.903771) (xy 54.748076 -494.964626) (xy 54.696652 -495.02033) (xy 54.639599 -495.070252)
			(xy 54.577563 -495.113827) (xy 54.511246 -495.150562) (xy 54.4414 -495.180039) (xy 54.368817 -495.201925)
			(xy 54.294319 -495.215972) (xy 54.218749 -495.222021) (xy 54.142965 -495.220002) (xy 54.067825 -495.20994)
			(xy 53.99418 -495.191948) (xy 53.922864 -495.16623) (xy 53.854687 -495.133078) (xy 53.790419 -495.092866)
			(xy 53.73079 -495.046051) (xy 53.676474 -494.993163) (xy 53.628088 -494.934801) (xy 53.58618 -494.871626)
			(xy 53.551224 -494.804355) (xy 53.523617 -494.73375) (xy 53.503671 -494.660609) (xy 53.491612 -494.585764)
			(xy 53.487577 -494.51006) (xy 52.371498 -494.51006) (xy 52.370994 -494.547966) (xy 52.362935 -494.623347)
			(xy 52.34691 -494.697445) (xy 52.3231 -494.76942) (xy 52.291774 -494.838456) (xy 52.253287 -494.903771)
			(xy 52.208076 -494.964626) (xy 52.156652 -495.02033) (xy 52.099599 -495.070252) (xy 52.037563 -495.113827)
			(xy 51.971246 -495.150562) (xy 51.9014 -495.180039) (xy 51.828817 -495.201925) (xy 51.754319 -495.215972)
			(xy 51.678749 -495.222021) (xy 51.602965 -495.220002) (xy 51.527825 -495.20994) (xy 51.45418 -495.191948)
			(xy 51.382864 -495.16623) (xy 51.314687 -495.133078) (xy 51.250419 -495.092866) (xy 51.19079 -495.046051)
			(xy 51.136474 -494.993163) (xy 51.088088 -494.934801) (xy 51.04618 -494.871626) (xy 51.011224 -494.804355)
			(xy 50.983617 -494.73375) (xy 50.963671 -494.660609) (xy 50.951612 -494.585764) (xy 50.947577 -494.51006)
			(xy 49.831498 -494.51006) (xy 49.830994 -494.547966) (xy 49.822935 -494.623347) (xy 49.80691 -494.697445)
			(xy 49.7831 -494.76942) (xy 49.751774 -494.838456) (xy 49.713287 -494.903771) (xy 49.668076 -494.964626)
			(xy 49.616652 -495.02033) (xy 49.559599 -495.070252) (xy 49.497563 -495.113827) (xy 49.431246 -495.150562)
			(xy 49.3614 -495.180039) (xy 49.288817 -495.201925) (xy 49.214319 -495.215972) (xy 49.138749 -495.222021)
			(xy 49.062965 -495.220002) (xy 48.987825 -495.20994) (xy 48.91418 -495.191948) (xy 48.842864 -495.16623)
			(xy 48.774687 -495.133078) (xy 48.710419 -495.092866) (xy 48.65079 -495.046051) (xy 48.596474 -494.993163)
			(xy 48.548088 -494.934801) (xy 48.50618 -494.871626) (xy 48.471224 -494.804355) (xy 48.443617 -494.73375)
			(xy 48.423671 -494.660609) (xy 48.411612 -494.585764) (xy 48.407577 -494.51006) (xy 47.291498 -494.51006)
			(xy 47.290994 -494.547966) (xy 47.282935 -494.623347) (xy 47.26691 -494.697445) (xy 47.2431 -494.76942)
			(xy 47.211774 -494.838456) (xy 47.173287 -494.903771) (xy 47.128076 -494.964626) (xy 47.076652 -495.02033)
			(xy 47.019599 -495.070252) (xy 46.957563 -495.113827) (xy 46.891246 -495.150562) (xy 46.8214 -495.180039)
			(xy 46.748817 -495.201925) (xy 46.674319 -495.215972) (xy 46.598749 -495.222021) (xy 46.522965 -495.220002)
			(xy 46.447825 -495.20994) (xy 46.37418 -495.191948) (xy 46.302864 -495.16623) (xy 46.234687 -495.133078)
			(xy 46.170419 -495.092866) (xy 46.11079 -495.046051) (xy 46.056474 -494.993163) (xy 46.008088 -494.934801)
			(xy 45.96618 -494.871626) (xy 45.931224 -494.804355) (xy 45.903617 -494.73375) (xy 45.883671 -494.660609)
			(xy 45.871612 -494.585764) (xy 45.867577 -494.51006) (xy 44.751498 -494.51006) (xy 44.750994 -494.547966)
			(xy 44.742935 -494.623347) (xy 44.72691 -494.697445) (xy 44.7031 -494.76942) (xy 44.671774 -494.838456)
			(xy 44.633287 -494.903771) (xy 44.588076 -494.964626) (xy 44.536652 -495.02033) (xy 44.479599 -495.070252)
			(xy 44.417563 -495.113827) (xy 44.351246 -495.150562) (xy 44.2814 -495.180039) (xy 44.208817 -495.201925)
			(xy 44.134319 -495.215972) (xy 44.058749 -495.222021) (xy 43.982965 -495.220002) (xy 43.907825 -495.20994)
			(xy 43.83418 -495.191948) (xy 43.762864 -495.16623) (xy 43.694687 -495.133078) (xy 43.630419 -495.092866)
			(xy 43.57079 -495.046051) (xy 43.516474 -494.993163) (xy 43.468088 -494.934801) (xy 43.42618 -494.871626)
			(xy 43.391224 -494.804355) (xy 43.363617 -494.73375) (xy 43.343671 -494.660609) (xy 43.331612 -494.585764)
			(xy 43.327577 -494.51006) (xy 42.501239 -494.51006) (xy 42.515699 -494.520266) (xy 42.604766 -494.592723)
			(xy 42.688681 -494.671089) (xy 42.767054 -494.754998) (xy 42.839517 -494.84406) (xy 42.905734 -494.937859)
			(xy 42.965396 -495.035958) (xy 43.018225 -495.1379) (xy 43.056094 -495.22507) (xy 84.927697 -495.22507)
			(xy 84.931732 -495.149366) (xy 84.943791 -495.074521) (xy 84.963737 -495.00138) (xy 84.991344 -494.930775)
			(xy 85.0263 -494.863504) (xy 85.068208 -494.800329) (xy 85.116594 -494.741967) (xy 85.17091 -494.689079)
			(xy 85.230539 -494.642264) (xy 85.294807 -494.602052) (xy 85.362984 -494.5689) (xy 85.4343 -494.543182)
			(xy 85.507945 -494.52519) (xy 85.583085 -494.515128) (xy 85.658869 -494.513109) (xy 85.734439 -494.519158)
			(xy 85.808937 -494.533205) (xy 85.88152 -494.555091) (xy 85.951366 -494.584568) (xy 86.017683 -494.621303)
			(xy 86.079719 -494.664878) (xy 86.136772 -494.7148) (xy 86.188196 -494.770504) (xy 86.233407 -494.831359)
			(xy 86.271894 -494.896674) (xy 86.30322 -494.96571) (xy 86.32703 -495.037685) (xy 86.343055 -495.111783)
			(xy 86.351114 -495.187164) (xy 86.351618 -495.22507) (xy 87.467697 -495.22507) (xy 87.471732 -495.149366)
			(xy 87.483791 -495.074521) (xy 87.503737 -495.00138) (xy 87.531344 -494.930775) (xy 87.5663 -494.863504)
			(xy 87.608208 -494.800329) (xy 87.656594 -494.741967) (xy 87.71091 -494.689079) (xy 87.770539 -494.642264)
			(xy 87.834807 -494.602052) (xy 87.902984 -494.5689) (xy 87.9743 -494.543182) (xy 88.047945 -494.52519)
			(xy 88.123085 -494.515128) (xy 88.198869 -494.513109) (xy 88.274439 -494.519158) (xy 88.348937 -494.533205)
			(xy 88.42152 -494.555091) (xy 88.491366 -494.584568) (xy 88.557683 -494.621303) (xy 88.619719 -494.664878)
			(xy 88.676772 -494.7148) (xy 88.728196 -494.770504) (xy 88.773407 -494.831359) (xy 88.811894 -494.896674)
			(xy 88.84322 -494.96571) (xy 88.86703 -495.037685) (xy 88.883055 -495.111783) (xy 88.891114 -495.187164)
			(xy 88.891618 -495.22507) (xy 90.007697 -495.22507) (xy 90.011732 -495.149366) (xy 90.023791 -495.074521)
			(xy 90.043737 -495.00138) (xy 90.071344 -494.930775) (xy 90.1063 -494.863504) (xy 90.148208 -494.800329)
			(xy 90.196594 -494.741967) (xy 90.25091 -494.689079) (xy 90.310539 -494.642264) (xy 90.374807 -494.602052)
			(xy 90.442984 -494.5689) (xy 90.5143 -494.543182) (xy 90.587945 -494.52519) (xy 90.663085 -494.515128)
			(xy 90.738869 -494.513109) (xy 90.814439 -494.519158) (xy 90.888937 -494.533205) (xy 90.96152 -494.555091)
			(xy 91.031366 -494.584568) (xy 91.097683 -494.621303) (xy 91.159719 -494.664878) (xy 91.216772 -494.7148)
			(xy 91.268196 -494.770504) (xy 91.313407 -494.831359) (xy 91.351894 -494.896674) (xy 91.38322 -494.96571)
			(xy 91.40703 -495.037685) (xy 91.423055 -495.111783) (xy 91.431114 -495.187164) (xy 91.431618 -495.22507)
			(xy 91.431114 -495.262976) (xy 91.423055 -495.338357) (xy 91.40703 -495.412455) (xy 91.38322 -495.48443)
			(xy 91.351894 -495.553466) (xy 91.313407 -495.618781) (xy 91.268196 -495.679636) (xy 91.216772 -495.73534)
			(xy 91.159719 -495.785262) (xy 91.097683 -495.828837) (xy 91.031366 -495.865572) (xy 90.96152 -495.895049)
			(xy 90.888937 -495.916935) (xy 90.814439 -495.930982) (xy 90.738869 -495.937031) (xy 90.663085 -495.935012)
			(xy 90.587945 -495.92495) (xy 90.5143 -495.906958) (xy 90.442984 -495.88124) (xy 90.374807 -495.848088)
			(xy 90.310539 -495.807876) (xy 90.25091 -495.761061) (xy 90.196594 -495.708173) (xy 90.148208 -495.649811)
			(xy 90.1063 -495.586636) (xy 90.071344 -495.519365) (xy 90.043737 -495.44876) (xy 90.023791 -495.375619)
			(xy 90.011732 -495.300774) (xy 90.007697 -495.22507) (xy 88.891618 -495.22507) (xy 88.891114 -495.262976)
			(xy 88.883055 -495.338357) (xy 88.86703 -495.412455) (xy 88.84322 -495.48443) (xy 88.811894 -495.553466)
			(xy 88.773407 -495.618781) (xy 88.728196 -495.679636) (xy 88.676772 -495.73534) (xy 88.619719 -495.785262)
			(xy 88.557683 -495.828837) (xy 88.491366 -495.865572) (xy 88.42152 -495.895049) (xy 88.348937 -495.916935)
			(xy 88.274439 -495.930982) (xy 88.198869 -495.937031) (xy 88.123085 -495.935012) (xy 88.047945 -495.92495)
			(xy 87.9743 -495.906958) (xy 87.902984 -495.88124) (xy 87.834807 -495.848088) (xy 87.770539 -495.807876)
			(xy 87.71091 -495.761061) (xy 87.656594 -495.708173) (xy 87.608208 -495.649811) (xy 87.5663 -495.586636)
			(xy 87.531344 -495.519365) (xy 87.503737 -495.44876) (xy 87.483791 -495.375619) (xy 87.471732 -495.300774)
			(xy 87.467697 -495.22507) (xy 86.351618 -495.22507) (xy 86.351114 -495.262976) (xy 86.343055 -495.338357)
			(xy 86.32703 -495.412455) (xy 86.30322 -495.48443) (xy 86.271894 -495.553466) (xy 86.233407 -495.618781)
			(xy 86.188196 -495.679636) (xy 86.136772 -495.73534) (xy 86.079719 -495.785262) (xy 86.017683 -495.828837)
			(xy 85.951366 -495.865572) (xy 85.88152 -495.895049) (xy 85.808937 -495.916935) (xy 85.734439 -495.930982)
			(xy 85.658869 -495.937031) (xy 85.583085 -495.935012) (xy 85.507945 -495.92495) (xy 85.4343 -495.906958)
			(xy 85.362984 -495.88124) (xy 85.294807 -495.848088) (xy 85.230539 -495.807876) (xy 85.17091 -495.761061)
			(xy 85.116594 -495.708173) (xy 85.068208 -495.649811) (xy 85.0263 -495.586636) (xy 84.991344 -495.519365)
			(xy 84.963737 -495.44876) (xy 84.943791 -495.375619) (xy 84.931732 -495.300774) (xy 84.927697 -495.22507)
			(xy 43.056094 -495.22507) (xy 43.063974 -495.243209) (xy 43.10243 -495.351394) (xy 43.133415 -495.461952)
			(xy 43.156782 -495.574366) (xy 43.172424 -495.688113) (xy 43.180268 -495.802661) (xy 43.180762 -495.86007)
			(xy 43.180576 -495.893253) (xy 43.177909 -495.959567) (xy 43.175428 -495.992658) (xy 43.170272 -496.050942)
			(xy 43.152948 -496.166671) (xy 43.127616 -496.280914) (xy 43.094401 -496.393119) (xy 43.056327 -496.49507)
			(xy 86.197697 -496.49507) (xy 86.201732 -496.419366) (xy 86.213791 -496.344521) (xy 86.233737 -496.27138)
			(xy 86.261344 -496.200775) (xy 86.2963 -496.133504) (xy 86.338208 -496.070329) (xy 86.386594 -496.011967)
			(xy 86.44091 -495.959079) (xy 86.500539 -495.912264) (xy 86.564807 -495.872052) (xy 86.632984 -495.8389)
			(xy 86.7043 -495.813182) (xy 86.777945 -495.79519) (xy 86.853085 -495.785128) (xy 86.928869 -495.783109)
			(xy 87.004439 -495.789158) (xy 87.078937 -495.803205) (xy 87.15152 -495.825091) (xy 87.221366 -495.854568)
			(xy 87.287683 -495.891303) (xy 87.349719 -495.934878) (xy 87.406772 -495.9848) (xy 87.458196 -496.040504)
			(xy 87.503407 -496.101359) (xy 87.541894 -496.166674) (xy 87.57322 -496.23571) (xy 87.59703 -496.307685)
			(xy 87.613055 -496.381783) (xy 87.621114 -496.457164) (xy 87.621618 -496.49507) (xy 88.737697 -496.49507)
			(xy 88.741732 -496.419366) (xy 88.753791 -496.344521) (xy 88.773737 -496.27138) (xy 88.801344 -496.200775)
			(xy 88.8363 -496.133504) (xy 88.878208 -496.070329) (xy 88.926594 -496.011967) (xy 88.98091 -495.959079)
			(xy 89.040539 -495.912264) (xy 89.104807 -495.872052) (xy 89.172984 -495.8389) (xy 89.2443 -495.813182)
			(xy 89.317945 -495.79519) (xy 89.393085 -495.785128) (xy 89.468869 -495.783109) (xy 89.544439 -495.789158)
			(xy 89.618937 -495.803205) (xy 89.69152 -495.825091) (xy 89.761366 -495.854568) (xy 89.827683 -495.891303)
			(xy 89.889719 -495.934878) (xy 89.946772 -495.9848) (xy 89.998196 -496.040504) (xy 90.043407 -496.101359)
			(xy 90.081894 -496.166674) (xy 90.11322 -496.23571) (xy 90.13703 -496.307685) (xy 90.153055 -496.381783)
			(xy 90.161114 -496.457164) (xy 90.161618 -496.49507) (xy 91.277697 -496.49507) (xy 91.281732 -496.419366)
			(xy 91.293791 -496.344521) (xy 91.313737 -496.27138) (xy 91.341344 -496.200775) (xy 91.3763 -496.133504)
			(xy 91.418208 -496.070329) (xy 91.466594 -496.011967) (xy 91.52091 -495.959079) (xy 91.580539 -495.912264)
			(xy 91.644807 -495.872052) (xy 91.712984 -495.8389) (xy 91.7843 -495.813182) (xy 91.857945 -495.79519)
			(xy 91.933085 -495.785128) (xy 92.008869 -495.783109) (xy 92.084439 -495.789158) (xy 92.158937 -495.803205)
			(xy 92.23152 -495.825091) (xy 92.301366 -495.854568) (xy 92.367683 -495.891303) (xy 92.429719 -495.934878)
			(xy 92.486772 -495.9848) (xy 92.538196 -496.040504) (xy 92.583407 -496.101359) (xy 92.621894 -496.166674)
			(xy 92.65322 -496.23571) (xy 92.67703 -496.307685) (xy 92.693055 -496.381783) (xy 92.701114 -496.457164)
			(xy 92.701618 -496.49507) (xy 92.701114 -496.532976) (xy 92.693055 -496.608357) (xy 92.67703 -496.682455)
			(xy 92.65322 -496.75443) (xy 92.621894 -496.823466) (xy 92.583407 -496.888781) (xy 92.538196 -496.949636)
			(xy 92.486772 -497.00534) (xy 92.429719 -497.055262) (xy 92.367683 -497.098837) (xy 92.301366 -497.135572)
			(xy 92.23152 -497.165049) (xy 92.158937 -497.186935) (xy 92.084439 -497.200982) (xy 92.008869 -497.207031)
			(xy 91.933085 -497.205012) (xy 91.857945 -497.19495) (xy 91.7843 -497.176958) (xy 91.712984 -497.15124)
			(xy 91.644807 -497.118088) (xy 91.580539 -497.077876) (xy 91.52091 -497.031061) (xy 91.466594 -496.978173)
			(xy 91.418208 -496.919811) (xy 91.3763 -496.856636) (xy 91.341344 -496.789365) (xy 91.313737 -496.71876)
			(xy 91.293791 -496.645619) (xy 91.281732 -496.570774) (xy 91.277697 -496.49507) (xy 90.161618 -496.49507)
			(xy 90.161114 -496.532976) (xy 90.153055 -496.608357) (xy 90.13703 -496.682455) (xy 90.11322 -496.75443)
			(xy 90.081894 -496.823466) (xy 90.043407 -496.888781) (xy 89.998196 -496.949636) (xy 89.946772 -497.00534)
			(xy 89.889719 -497.055262) (xy 89.827683 -497.098837) (xy 89.761366 -497.135572) (xy 89.69152 -497.165049)
			(xy 89.618937 -497.186935) (xy 89.544439 -497.200982) (xy 89.468869 -497.207031) (xy 89.393085 -497.205012)
			(xy 89.317945 -497.19495) (xy 89.2443 -497.176958) (xy 89.172984 -497.15124) (xy 89.104807 -497.118088)
			(xy 89.040539 -497.077876) (xy 88.98091 -497.031061) (xy 88.926594 -496.978173) (xy 88.878208 -496.919811)
			(xy 88.8363 -496.856636) (xy 88.801344 -496.789365) (xy 88.773737 -496.71876) (xy 88.753791 -496.645619)
			(xy 88.741732 -496.570774) (xy 88.737697 -496.49507) (xy 87.621618 -496.49507) (xy 87.621114 -496.532976)
			(xy 87.613055 -496.608357) (xy 87.59703 -496.682455) (xy 87.57322 -496.75443) (xy 87.541894 -496.823466)
			(xy 87.503407 -496.888781) (xy 87.458196 -496.949636) (xy 87.406772 -497.00534) (xy 87.349719 -497.055262)
			(xy 87.287683 -497.098837) (xy 87.221366 -497.135572) (xy 87.15152 -497.165049) (xy 87.078937 -497.186935)
			(xy 87.004439 -497.200982) (xy 86.928869 -497.207031) (xy 86.853085 -497.205012) (xy 86.777945 -497.19495)
			(xy 86.7043 -497.176958) (xy 86.632984 -497.15124) (xy 86.564807 -497.118088) (xy 86.500539 -497.077876)
			(xy 86.44091 -497.031061) (xy 86.386594 -496.978173) (xy 86.338208 -496.919811) (xy 86.2963 -496.856636)
			(xy 86.261344 -496.789365) (xy 86.233737 -496.71876) (xy 86.213791 -496.645619) (xy 86.201732 -496.570774)
			(xy 86.197697 -496.49507) (xy 43.056327 -496.49507) (xy 43.055094 -496.498372) (xy 43.328336 -496.498372)
			(xy 44.751244 -496.498372) (xy 44.751244 -497.21008) (xy 45.867577 -497.21008) (xy 45.871612 -497.134376)
			(xy 45.883671 -497.059531) (xy 45.903617 -496.98639) (xy 45.931224 -496.915785) (xy 45.96618 -496.848514)
			(xy 46.008088 -496.785339) (xy 46.056474 -496.726977) (xy 46.11079 -496.674089) (xy 46.170419 -496.627274)
			(xy 46.234687 -496.587062) (xy 46.302864 -496.55391) (xy 46.37418 -496.528192) (xy 46.447825 -496.5102)
			(xy 46.522965 -496.500138) (xy 46.598749 -496.498119) (xy 46.674319 -496.504168) (xy 46.748817 -496.518215)
			(xy 46.8214 -496.540101) (xy 46.891246 -496.569578) (xy 46.957563 -496.606313) (xy 47.019599 -496.649888)
			(xy 47.076652 -496.69981) (xy 47.128076 -496.755514) (xy 47.173287 -496.816369) (xy 47.211774 -496.881684)
			(xy 47.2431 -496.95072) (xy 47.26691 -497.022695) (xy 47.282935 -497.096793) (xy 47.290994 -497.172174)
			(xy 47.291498 -497.21008) (xy 48.407577 -497.21008) (xy 48.411612 -497.134376) (xy 48.423671 -497.059531)
			(xy 48.443617 -496.98639) (xy 48.471224 -496.915785) (xy 48.50618 -496.848514) (xy 48.548088 -496.785339)
			(xy 48.596474 -496.726977) (xy 48.65079 -496.674089) (xy 48.710419 -496.627274) (xy 48.774687 -496.587062)
			(xy 48.842864 -496.55391) (xy 48.91418 -496.528192) (xy 48.987825 -496.5102) (xy 49.062965 -496.500138)
			(xy 49.138749 -496.498119) (xy 49.214319 -496.504168) (xy 49.288817 -496.518215) (xy 49.3614 -496.540101)
			(xy 49.431246 -496.569578) (xy 49.497563 -496.606313) (xy 49.559599 -496.649888) (xy 49.616652 -496.69981)
			(xy 49.668076 -496.755514) (xy 49.713287 -496.816369) (xy 49.751774 -496.881684) (xy 49.7831 -496.95072)
			(xy 49.80691 -497.022695) (xy 49.822935 -497.096793) (xy 49.830994 -497.172174) (xy 49.831498 -497.21008)
			(xy 50.947577 -497.21008) (xy 50.951612 -497.134376) (xy 50.963671 -497.059531) (xy 50.983617 -496.98639)
			(xy 51.011224 -496.915785) (xy 51.04618 -496.848514) (xy 51.088088 -496.785339) (xy 51.136474 -496.726977)
			(xy 51.19079 -496.674089) (xy 51.250419 -496.627274) (xy 51.314687 -496.587062) (xy 51.382864 -496.55391)
			(xy 51.45418 -496.528192) (xy 51.527825 -496.5102) (xy 51.602965 -496.500138) (xy 51.678749 -496.498119)
			(xy 51.754319 -496.504168) (xy 51.828817 -496.518215) (xy 51.9014 -496.540101) (xy 51.971246 -496.569578)
			(xy 52.037563 -496.606313) (xy 52.099599 -496.649888) (xy 52.156652 -496.69981) (xy 52.208076 -496.755514)
			(xy 52.253287 -496.816369) (xy 52.291774 -496.881684) (xy 52.3231 -496.95072) (xy 52.34691 -497.022695)
			(xy 52.362935 -497.096793) (xy 52.370994 -497.172174) (xy 52.371498 -497.21008) (xy 53.487577 -497.21008)
			(xy 53.491612 -497.134376) (xy 53.503671 -497.059531) (xy 53.523617 -496.98639) (xy 53.551224 -496.915785)
			(xy 53.58618 -496.848514) (xy 53.628088 -496.785339) (xy 53.676474 -496.726977) (xy 53.73079 -496.674089)
			(xy 53.790419 -496.627274) (xy 53.854687 -496.587062) (xy 53.922864 -496.55391) (xy 53.99418 -496.528192)
			(xy 54.067825 -496.5102) (xy 54.142965 -496.500138) (xy 54.218749 -496.498119) (xy 54.294319 -496.504168)
			(xy 54.368817 -496.518215) (xy 54.4414 -496.540101) (xy 54.511246 -496.569578) (xy 54.577563 -496.606313)
			(xy 54.639599 -496.649888) (xy 54.696652 -496.69981) (xy 54.748076 -496.755514) (xy 54.793287 -496.816369)
			(xy 54.831774 -496.881684) (xy 54.8631 -496.95072) (xy 54.88691 -497.022695) (xy 54.902935 -497.096793)
			(xy 54.910994 -497.172174) (xy 54.911498 -497.21008) (xy 56.027577 -497.21008) (xy 56.031612 -497.134376)
			(xy 56.043671 -497.059531) (xy 56.063617 -496.98639) (xy 56.091224 -496.915785) (xy 56.12618 -496.848514)
			(xy 56.168088 -496.785339) (xy 56.216474 -496.726977) (xy 56.27079 -496.674089) (xy 56.330419 -496.627274)
			(xy 56.394687 -496.587062) (xy 56.462864 -496.55391) (xy 56.53418 -496.528192) (xy 56.607825 -496.5102)
			(xy 56.682965 -496.500138) (xy 56.758749 -496.498119) (xy 56.834319 -496.504168) (xy 56.908817 -496.518215)
			(xy 56.9814 -496.540101) (xy 57.051246 -496.569578) (xy 57.117563 -496.606313) (xy 57.179599 -496.649888)
			(xy 57.236652 -496.69981) (xy 57.288076 -496.755514) (xy 57.333287 -496.816369) (xy 57.371774 -496.881684)
			(xy 57.4031 -496.95072) (xy 57.42691 -497.022695) (xy 57.442935 -497.096793) (xy 57.450994 -497.172174)
			(xy 57.451498 -497.21008) (xy 58.567577 -497.21008) (xy 58.571612 -497.134376) (xy 58.583671 -497.059531)
			(xy 58.603617 -496.98639) (xy 58.631224 -496.915785) (xy 58.66618 -496.848514) (xy 58.708088 -496.785339)
			(xy 58.756474 -496.726977) (xy 58.81079 -496.674089) (xy 58.870419 -496.627274) (xy 58.934687 -496.587062)
			(xy 59.002864 -496.55391) (xy 59.07418 -496.528192) (xy 59.147825 -496.5102) (xy 59.222965 -496.500138)
			(xy 59.298749 -496.498119) (xy 59.374319 -496.504168) (xy 59.448817 -496.518215) (xy 59.5214 -496.540101)
			(xy 59.591246 -496.569578) (xy 59.657563 -496.606313) (xy 59.719599 -496.649888) (xy 59.776652 -496.69981)
			(xy 59.828076 -496.755514) (xy 59.873287 -496.816369) (xy 59.911774 -496.881684) (xy 59.9431 -496.95072)
			(xy 59.96691 -497.022695) (xy 59.982935 -497.096793) (xy 59.990994 -497.172174) (xy 59.991498 -497.21008)
			(xy 61.107577 -497.21008) (xy 61.111612 -497.134376) (xy 61.123671 -497.059531) (xy 61.143617 -496.98639)
			(xy 61.171224 -496.915785) (xy 61.20618 -496.848514) (xy 61.248088 -496.785339) (xy 61.296474 -496.726977)
			(xy 61.35079 -496.674089) (xy 61.410419 -496.627274) (xy 61.474687 -496.587062) (xy 61.542864 -496.55391)
			(xy 61.61418 -496.528192) (xy 61.687825 -496.5102) (xy 61.762965 -496.500138) (xy 61.838749 -496.498119)
			(xy 61.914319 -496.504168) (xy 61.988817 -496.518215) (xy 62.0614 -496.540101) (xy 62.131246 -496.569578)
			(xy 62.197563 -496.606313) (xy 62.259599 -496.649888) (xy 62.316652 -496.69981) (xy 62.368076 -496.755514)
			(xy 62.413287 -496.816369) (xy 62.451774 -496.881684) (xy 62.4831 -496.95072) (xy 62.50691 -497.022695)
			(xy 62.522935 -497.096793) (xy 62.530994 -497.172174) (xy 62.531498 -497.21008) (xy 62.530994 -497.247986)
			(xy 62.522935 -497.323367) (xy 62.50691 -497.397465) (xy 62.4831 -497.46944) (xy 62.451774 -497.538476)
			(xy 62.413287 -497.603791) (xy 62.368076 -497.664646) (xy 62.316652 -497.72035) (xy 62.265544 -497.76507)
			(xy 84.927697 -497.76507) (xy 84.931732 -497.689366) (xy 84.943791 -497.614521) (xy 84.963737 -497.54138)
			(xy 84.991344 -497.470775) (xy 85.0263 -497.403504) (xy 85.068208 -497.340329) (xy 85.116594 -497.281967)
			(xy 85.17091 -497.229079) (xy 85.230539 -497.182264) (xy 85.294807 -497.142052) (xy 85.362984 -497.1089)
			(xy 85.4343 -497.083182) (xy 85.507945 -497.06519) (xy 85.583085 -497.055128) (xy 85.658869 -497.053109)
			(xy 85.734439 -497.059158) (xy 85.808937 -497.073205) (xy 85.88152 -497.095091) (xy 85.951366 -497.124568)
			(xy 86.017683 -497.161303) (xy 86.079719 -497.204878) (xy 86.136772 -497.2548) (xy 86.188196 -497.310504)
			(xy 86.233407 -497.371359) (xy 86.271894 -497.436674) (xy 86.30322 -497.50571) (xy 86.32703 -497.577685)
			(xy 86.343055 -497.651783) (xy 86.351114 -497.727164) (xy 86.351618 -497.76507) (xy 87.467697 -497.76507)
			(xy 87.471732 -497.689366) (xy 87.483791 -497.614521) (xy 87.503737 -497.54138) (xy 87.531344 -497.470775)
			(xy 87.5663 -497.403504) (xy 87.608208 -497.340329) (xy 87.656594 -497.281967) (xy 87.71091 -497.229079)
			(xy 87.770539 -497.182264) (xy 87.834807 -497.142052) (xy 87.902984 -497.1089) (xy 87.9743 -497.083182)
			(xy 88.047945 -497.06519) (xy 88.123085 -497.055128) (xy 88.198869 -497.053109) (xy 88.274439 -497.059158)
			(xy 88.348937 -497.073205) (xy 88.42152 -497.095091) (xy 88.491366 -497.124568) (xy 88.557683 -497.161303)
			(xy 88.619719 -497.204878) (xy 88.676772 -497.2548) (xy 88.728196 -497.310504) (xy 88.773407 -497.371359)
			(xy 88.811894 -497.436674) (xy 88.84322 -497.50571) (xy 88.86703 -497.577685) (xy 88.883055 -497.651783)
			(xy 88.891114 -497.727164) (xy 88.891618 -497.76507) (xy 90.007697 -497.76507) (xy 90.011732 -497.689366)
			(xy 90.023791 -497.614521) (xy 90.043737 -497.54138) (xy 90.071344 -497.470775) (xy 90.1063 -497.403504)
			(xy 90.148208 -497.340329) (xy 90.196594 -497.281967) (xy 90.25091 -497.229079) (xy 90.310539 -497.182264)
			(xy 90.374807 -497.142052) (xy 90.442984 -497.1089) (xy 90.5143 -497.083182) (xy 90.587945 -497.06519)
			(xy 90.663085 -497.055128) (xy 90.738869 -497.053109) (xy 90.814439 -497.059158) (xy 90.888937 -497.073205)
			(xy 90.96152 -497.095091) (xy 91.031366 -497.124568) (xy 91.097683 -497.161303) (xy 91.159719 -497.204878)
			(xy 91.165664 -497.21008) (xy 93.154506 -497.21008) (xy 93.158522 -497.09381) (xy 93.170549 -496.978095)
			(xy 93.190531 -496.863485) (xy 93.218373 -496.750526) (xy 93.253942 -496.639758) (xy 93.297068 -496.531707)
			(xy 93.347545 -496.426889) (xy 93.405134 -496.325804) (xy 93.46956 -496.228932) (xy 93.540515 -496.136736)
			(xy 93.617662 -496.049655) (xy 93.700633 -495.968104) (xy 93.789033 -495.892472) (xy 93.88244 -495.823118)
			(xy 93.980409 -495.760375) (xy 94.082473 -495.704539) (xy 94.188147 -495.655878) (xy 94.296926 -495.614624)
			(xy 94.408291 -495.580973) (xy 94.521714 -495.555085) (xy 94.636651 -495.537084) (xy 94.752557 -495.527055)
			(xy 94.868879 -495.525047) (xy 94.985062 -495.531069) (xy 95.100553 -495.545092) (xy 95.214801 -495.56705)
			(xy 95.327262 -495.596837) (xy 95.4374 -495.634312) (xy 95.54469 -495.679297) (xy 95.648621 -495.731576)
			(xy 95.748697 -495.790901) (xy 95.844443 -495.856989) (xy 95.9354 -495.929525) (xy 96.021136 -496.008164)
			(xy 96.101243 -496.09253) (xy 96.175339 -496.182222) (xy 96.243069 -496.276812) (xy 96.304113 -496.37585)
			(xy 96.358178 -496.478863) (xy 96.405008 -496.58536) (xy 96.444379 -496.694835) (xy 96.476103 -496.806765)
			(xy 96.500029 -496.920617) (xy 96.516043 -497.035849) (xy 96.52407 -497.151911) (xy 96.524572 -497.21008)
			(xy 96.52407 -497.268249) (xy 96.516043 -497.384311) (xy 96.500029 -497.499543) (xy 96.476103 -497.613395)
			(xy 96.444379 -497.725325) (xy 96.405008 -497.8348) (xy 96.358178 -497.941297) (xy 96.304113 -498.04431)
			(xy 96.243069 -498.143348) (xy 96.175339 -498.237938) (xy 96.101243 -498.32763) (xy 96.021136 -498.411996)
			(xy 95.9354 -498.490635) (xy 95.844443 -498.563171) (xy 95.748697 -498.629259) (xy 95.648621 -498.688584)
			(xy 95.54469 -498.740863) (xy 95.4374 -498.785848) (xy 95.327262 -498.823323) (xy 95.214801 -498.85311)
			(xy 95.100553 -498.875068) (xy 94.985062 -498.889091) (xy 94.868879 -498.895113) (xy 94.752557 -498.893105)
			(xy 94.636651 -498.883076) (xy 94.521714 -498.865075) (xy 94.408291 -498.839187) (xy 94.296926 -498.805536)
			(xy 94.188147 -498.764282) (xy 94.082473 -498.715621) (xy 93.980409 -498.659785) (xy 93.88244 -498.597042)
			(xy 93.789033 -498.527688) (xy 93.700633 -498.452056) (xy 93.617662 -498.370505) (xy 93.540515 -498.283424)
			(xy 93.46956 -498.191228) (xy 93.405134 -498.094356) (xy 93.347545 -497.993271) (xy 93.297068 -497.888453)
			(xy 93.253942 -497.780402) (xy 93.218373 -497.669634) (xy 93.190531 -497.556675) (xy 93.170549 -497.442065)
			(xy 93.158522 -497.32635) (xy 93.154506 -497.21008) (xy 91.165664 -497.21008) (xy 91.216772 -497.2548)
			(xy 91.268196 -497.310504) (xy 91.313407 -497.371359) (xy 91.351894 -497.436674) (xy 91.38322 -497.50571)
			(xy 91.40703 -497.577685) (xy 91.423055 -497.651783) (xy 91.431114 -497.727164) (xy 91.431618 -497.76507)
			(xy 91.431114 -497.802976) (xy 91.423055 -497.878357) (xy 91.40703 -497.952455) (xy 91.38322 -498.02443)
			(xy 91.351894 -498.093466) (xy 91.313407 -498.158781) (xy 91.268196 -498.219636) (xy 91.216772 -498.27534)
			(xy 91.159719 -498.325262) (xy 91.097683 -498.368837) (xy 91.031366 -498.405572) (xy 90.96152 -498.435049)
			(xy 90.888937 -498.456935) (xy 90.814439 -498.470982) (xy 90.738869 -498.477031) (xy 90.663085 -498.475012)
			(xy 90.587945 -498.46495) (xy 90.5143 -498.446958) (xy 90.442984 -498.42124) (xy 90.374807 -498.388088)
			(xy 90.310539 -498.347876) (xy 90.25091 -498.301061) (xy 90.196594 -498.248173) (xy 90.148208 -498.189811)
			(xy 90.1063 -498.126636) (xy 90.071344 -498.059365) (xy 90.043737 -497.98876) (xy 90.023791 -497.915619)
			(xy 90.011732 -497.840774) (xy 90.007697 -497.76507) (xy 88.891618 -497.76507) (xy 88.891114 -497.802976)
			(xy 88.883055 -497.878357) (xy 88.86703 -497.952455) (xy 88.84322 -498.02443) (xy 88.811894 -498.093466)
			(xy 88.773407 -498.158781) (xy 88.728196 -498.219636) (xy 88.676772 -498.27534) (xy 88.619719 -498.325262)
			(xy 88.557683 -498.368837) (xy 88.491366 -498.405572) (xy 88.42152 -498.435049) (xy 88.348937 -498.456935)
			(xy 88.274439 -498.470982) (xy 88.198869 -498.477031) (xy 88.123085 -498.475012) (xy 88.047945 -498.46495)
			(xy 87.9743 -498.446958) (xy 87.902984 -498.42124) (xy 87.834807 -498.388088) (xy 87.770539 -498.347876)
			(xy 87.71091 -498.301061) (xy 87.656594 -498.248173) (xy 87.608208 -498.189811) (xy 87.5663 -498.126636)
			(xy 87.531344 -498.059365) (xy 87.503737 -497.98876) (xy 87.483791 -497.915619) (xy 87.471732 -497.840774)
			(xy 87.467697 -497.76507) (xy 86.351618 -497.76507) (xy 86.351114 -497.802976) (xy 86.343055 -497.878357)
			(xy 86.32703 -497.952455) (xy 86.30322 -498.02443) (xy 86.271894 -498.093466) (xy 86.233407 -498.158781)
			(xy 86.188196 -498.219636) (xy 86.136772 -498.27534) (xy 86.079719 -498.325262) (xy 86.017683 -498.368837)
			(xy 85.951366 -498.405572) (xy 85.88152 -498.435049) (xy 85.808937 -498.456935) (xy 85.734439 -498.470982)
			(xy 85.658869 -498.477031) (xy 85.583085 -498.475012) (xy 85.507945 -498.46495) (xy 85.4343 -498.446958)
			(xy 85.362984 -498.42124) (xy 85.294807 -498.388088) (xy 85.230539 -498.347876) (xy 85.17091 -498.301061)
			(xy 85.116594 -498.248173) (xy 85.068208 -498.189811) (xy 85.0263 -498.126636) (xy 84.991344 -498.059365)
			(xy 84.963737 -497.98876) (xy 84.943791 -497.915619) (xy 84.931732 -497.840774) (xy 84.927697 -497.76507)
			(xy 62.265544 -497.76507) (xy 62.259599 -497.770272) (xy 62.197563 -497.813847) (xy 62.131246 -497.850582)
			(xy 62.0614 -497.880059) (xy 61.988817 -497.901945) (xy 61.914319 -497.915992) (xy 61.838749 -497.922041)
			(xy 61.762965 -497.920022) (xy 61.687825 -497.90996) (xy 61.61418 -497.891968) (xy 61.542864 -497.86625)
			(xy 61.474687 -497.833098) (xy 61.410419 -497.792886) (xy 61.35079 -497.746071) (xy 61.296474 -497.693183)
			(xy 61.248088 -497.634821) (xy 61.20618 -497.571646) (xy 61.171224 -497.504375) (xy 61.143617 -497.43377)
			(xy 61.123671 -497.360629) (xy 61.111612 -497.285784) (xy 61.107577 -497.21008) (xy 59.991498 -497.21008)
			(xy 59.990994 -497.247986) (xy 59.982935 -497.323367) (xy 59.96691 -497.397465) (xy 59.9431 -497.46944)
			(xy 59.911774 -497.538476) (xy 59.873287 -497.603791) (xy 59.828076 -497.664646) (xy 59.776652 -497.72035)
			(xy 59.719599 -497.770272) (xy 59.657563 -497.813847) (xy 59.591246 -497.850582) (xy 59.5214 -497.880059)
			(xy 59.448817 -497.901945) (xy 59.374319 -497.915992) (xy 59.298749 -497.922041) (xy 59.222965 -497.920022)
			(xy 59.147825 -497.90996) (xy 59.07418 -497.891968) (xy 59.002864 -497.86625) (xy 58.934687 -497.833098)
			(xy 58.870419 -497.792886) (xy 58.81079 -497.746071) (xy 58.756474 -497.693183) (xy 58.708088 -497.634821)
			(xy 58.66618 -497.571646) (xy 58.631224 -497.504375) (xy 58.603617 -497.43377) (xy 58.583671 -497.360629)
			(xy 58.571612 -497.285784) (xy 58.567577 -497.21008) (xy 57.451498 -497.21008) (xy 57.450994 -497.247986)
			(xy 57.442935 -497.323367) (xy 57.42691 -497.397465) (xy 57.4031 -497.46944) (xy 57.371774 -497.538476)
			(xy 57.333287 -497.603791) (xy 57.288076 -497.664646) (xy 57.236652 -497.72035) (xy 57.179599 -497.770272)
			(xy 57.117563 -497.813847) (xy 57.051246 -497.850582) (xy 56.9814 -497.880059) (xy 56.908817 -497.901945)
			(xy 56.834319 -497.915992) (xy 56.758749 -497.922041) (xy 56.682965 -497.920022) (xy 56.607825 -497.90996)
			(xy 56.53418 -497.891968) (xy 56.462864 -497.86625) (xy 56.394687 -497.833098) (xy 56.330419 -497.792886)
			(xy 56.27079 -497.746071) (xy 56.216474 -497.693183) (xy 56.168088 -497.634821) (xy 56.12618 -497.571646)
			(xy 56.091224 -497.504375) (xy 56.063617 -497.43377) (xy 56.043671 -497.360629) (xy 56.031612 -497.285784)
			(xy 56.027577 -497.21008) (xy 54.911498 -497.21008) (xy 54.910994 -497.247986) (xy 54.902935 -497.323367)
			(xy 54.88691 -497.397465) (xy 54.8631 -497.46944) (xy 54.831774 -497.538476) (xy 54.793287 -497.603791)
			(xy 54.748076 -497.664646) (xy 54.696652 -497.72035) (xy 54.639599 -497.770272) (xy 54.577563 -497.813847)
			(xy 54.511246 -497.850582) (xy 54.4414 -497.880059) (xy 54.368817 -497.901945) (xy 54.294319 -497.915992)
			(xy 54.218749 -497.922041) (xy 54.142965 -497.920022) (xy 54.067825 -497.90996) (xy 53.99418 -497.891968)
			(xy 53.922864 -497.86625) (xy 53.854687 -497.833098) (xy 53.790419 -497.792886) (xy 53.73079 -497.746071)
			(xy 53.676474 -497.693183) (xy 53.628088 -497.634821) (xy 53.58618 -497.571646) (xy 53.551224 -497.504375)
			(xy 53.523617 -497.43377) (xy 53.503671 -497.360629) (xy 53.491612 -497.285784) (xy 53.487577 -497.21008)
			(xy 52.371498 -497.21008) (xy 52.370994 -497.247986) (xy 52.362935 -497.323367) (xy 52.34691 -497.397465)
			(xy 52.3231 -497.46944) (xy 52.291774 -497.538476) (xy 52.253287 -497.603791) (xy 52.208076 -497.664646)
			(xy 52.156652 -497.72035) (xy 52.099599 -497.770272) (xy 52.037563 -497.813847) (xy 51.971246 -497.850582)
			(xy 51.9014 -497.880059) (xy 51.828817 -497.901945) (xy 51.754319 -497.915992) (xy 51.678749 -497.922041)
			(xy 51.602965 -497.920022) (xy 51.527825 -497.90996) (xy 51.45418 -497.891968) (xy 51.382864 -497.86625)
			(xy 51.314687 -497.833098) (xy 51.250419 -497.792886) (xy 51.19079 -497.746071) (xy 51.136474 -497.693183)
			(xy 51.088088 -497.634821) (xy 51.04618 -497.571646) (xy 51.011224 -497.504375) (xy 50.983617 -497.43377)
			(xy 50.963671 -497.360629) (xy 50.951612 -497.285784) (xy 50.947577 -497.21008) (xy 49.831498 -497.21008)
			(xy 49.830994 -497.247986) (xy 49.822935 -497.323367) (xy 49.80691 -497.397465) (xy 49.7831 -497.46944)
			(xy 49.751774 -497.538476) (xy 49.713287 -497.603791) (xy 49.668076 -497.664646) (xy 49.616652 -497.72035)
			(xy 49.559599 -497.770272) (xy 49.497563 -497.813847) (xy 49.431246 -497.850582) (xy 49.3614 -497.880059)
			(xy 49.288817 -497.901945) (xy 49.214319 -497.915992) (xy 49.138749 -497.922041) (xy 49.062965 -497.920022)
			(xy 48.987825 -497.90996) (xy 48.91418 -497.891968) (xy 48.842864 -497.86625) (xy 48.774687 -497.833098)
			(xy 48.710419 -497.792886) (xy 48.65079 -497.746071) (xy 48.596474 -497.693183) (xy 48.548088 -497.634821)
			(xy 48.50618 -497.571646) (xy 48.471224 -497.504375) (xy 48.443617 -497.43377) (xy 48.423671 -497.360629)
			(xy 48.411612 -497.285784) (xy 48.407577 -497.21008) (xy 47.291498 -497.21008) (xy 47.290994 -497.247986)
			(xy 47.282935 -497.323367) (xy 47.26691 -497.397465) (xy 47.2431 -497.46944) (xy 47.211774 -497.538476)
			(xy 47.173287 -497.603791) (xy 47.128076 -497.664646) (xy 47.076652 -497.72035) (xy 47.019599 -497.770272)
			(xy 46.957563 -497.813847) (xy 46.891246 -497.850582) (xy 46.8214 -497.880059) (xy 46.748817 -497.901945)
			(xy 46.674319 -497.915992) (xy 46.598749 -497.922041) (xy 46.522965 -497.920022) (xy 46.447825 -497.90996)
			(xy 46.37418 -497.891968) (xy 46.302864 -497.86625) (xy 46.234687 -497.833098) (xy 46.170419 -497.792886)
			(xy 46.11079 -497.746071) (xy 46.056474 -497.693183) (xy 46.008088 -497.634821) (xy 45.96618 -497.571646)
			(xy 45.931224 -497.504375) (xy 45.903617 -497.43377) (xy 45.883671 -497.360629) (xy 45.871612 -497.285784)
			(xy 45.867577 -497.21008) (xy 44.751244 -497.21008) (xy 44.751244 -497.921788) (xy 43.328336 -497.921788)
			(xy 43.328336 -496.498372) (xy 43.055094 -496.498372) (xy 43.053462 -496.502742) (xy 43.004999 -496.609253)
			(xy 42.949245 -496.712135) (xy 42.886471 -496.810891) (xy 42.816981 -496.905042) (xy 42.741111 -496.994132)
			(xy 42.659229 -497.077729) (xy 42.571732 -497.15543) (xy 42.479042 -497.226857) (xy 42.381609 -497.291665)
			(xy 42.279905 -497.34954) (xy 42.174422 -497.400202) (xy 42.065671 -497.443404) (xy 41.954179 -497.478939)
			(xy 41.840485 -497.506634) (xy 41.725141 -497.526354) (xy 41.608704 -497.538005) (xy 41.491739 -497.54153)
			(xy 41.374812 -497.536912) (xy 41.258489 -497.524173) (xy 41.143334 -497.503375) (xy 41.029905 -497.474618)
			(xy 40.91875 -497.438042) (xy 40.810407 -497.393825) (xy 40.705403 -497.342179) (xy 40.604244 -497.283356)
			(xy 40.507421 -497.21764) (xy 40.415403 -497.145349) (xy 40.328636 -497.066834) (xy 40.247539 -496.982474)
			(xy 40.172506 -496.892679) (xy 40.103899 -496.797883) (xy 40.042051 -496.698544) (xy 39.987262 -496.595145)
			(xy 39.939796 -496.488186) (xy 39.899884 -496.378185) (xy 39.86772 -496.265674) (xy 39.843457 -496.151199)
			(xy 39.827215 -496.035313) (xy 39.819072 -495.918579) (xy 39.818564 -495.86007) (xy 6.1258 -495.86007)
			(xy 6.074967 -495.879763) (xy 5.992514 -495.903223) (xy 5.908247 -495.918975) (xy 5.822887 -495.926885)
			(xy 5.737161 -495.926885) (xy 5.651801 -495.918975) (xy 5.567534 -495.903223) (xy 5.485081 -495.879763)
			(xy 5.405144 -495.848795) (xy 5.328405 -495.810584) (xy 5.255519 -495.765455) (xy 5.187108 -495.713794)
			(xy 5.123756 -495.65604) (xy 5.066002 -495.592688) (xy 5.014341 -495.524277) (xy 4.969212 -495.451391)
			(xy 4.931001 -495.374652) (xy 4.900033 -495.294715) (xy 4.876573 -495.212262) (xy 4.860821 -495.127995)
			(xy 4.852911 -495.042635) (xy 3.290253 -495.042635) (xy 5.32003 -497.072412) (xy 6.707632 -497.072412)
			(xy 6.707632 -498.92712) (xy 4.852416 -498.92712) (xy 4.852416 -497.539772) (xy 2.125472 -494.812828)
			(xy 2.108947 -494.798217) (xy 2.071862 -494.774341) (xy 2.031215 -494.757219) (xy 1.988224 -494.747366)
			(xy 1.944177 -494.745075) (xy 1.900395 -494.750416) (xy 1.858191 -494.763229) (xy 1.81883 -494.78313)
			(xy 1.783491 -494.809521) (xy 1.753234 -494.841612) (xy 1.728965 -494.878442) (xy 1.711413 -494.918905)
			(xy 1.701104 -494.961789) (xy 1.69926 -494.98377) (xy 1.69926 -500.99976) (xy 6.671831 -500.99976)
			(xy 6.675786 -500.907923) (xy 6.687621 -500.816766) (xy 6.707248 -500.726963) (xy 6.734522 -500.639181)
			(xy 6.769242 -500.554067) (xy 6.81115 -500.472254) (xy 6.859936 -500.394346) (xy 6.915239 -500.320921)
			(xy 6.976649 -500.252521) (xy 7.043711 -500.189654) (xy 7.11593 -500.132784) (xy 7.19277 -500.082333)
			(xy 7.273663 -500.038674) (xy 7.358009 -500.002131) (xy 7.445185 -499.972974) (xy 7.534544 -499.95142)
			(xy 7.625425 -499.937626) (xy 7.717156 -499.931696) (xy 7.809057 -499.933674) (xy 7.900448 -499.943545)
			(xy 7.990652 -499.961235) (xy 8.079001 -499.986615) (xy 8.164841 -500.019495) (xy 8.247537 -500.059633)
			(xy 8.326477 -500.106732) (xy 8.401075 -500.160442) (xy 8.470781 -500.220366) (xy 8.535076 -500.28606)
			(xy 8.593487 -500.357038) (xy 8.645579 -500.432775) (xy 8.690968 -500.51271) (xy 8.729318 -500.59625)
			(xy 8.760343 -500.682778) (xy 8.783816 -500.771653) (xy 8.799562 -500.862217) (xy 8.807464 -500.953799)
			(xy 8.807958 -500.99976) (xy 8.807464 -501.045721) (xy 8.799562 -501.137303) (xy 8.783816 -501.227867)
			(xy 8.760343 -501.316742) (xy 8.729318 -501.40327) (xy 8.690968 -501.48681) (xy 8.645579 -501.566745)
			(xy 8.593487 -501.642482) (xy 8.535076 -501.71346) (xy 8.470781 -501.779154) (xy 8.401075 -501.839078)
			(xy 8.326477 -501.892788) (xy 8.247537 -501.939887) (xy 8.164841 -501.980025) (xy 8.079001 -502.012905)
			(xy 7.990652 -502.038285) (xy 7.900448 -502.055975) (xy 7.809057 -502.065846) (xy 7.717156 -502.067824)
			(xy 7.625425 -502.061894) (xy 7.534544 -502.0481) (xy 7.445185 -502.026546) (xy 7.358009 -501.997389)
			(xy 7.273663 -501.960846) (xy 7.19277 -501.917187) (xy 7.11593 -501.866736) (xy 7.043711 -501.809866)
			(xy 6.976649 -501.746999) (xy 6.915239 -501.678599) (xy 6.859936 -501.605174) (xy 6.81115 -501.527266)
			(xy 6.769242 -501.445453) (xy 6.734522 -501.360339) (xy 6.707248 -501.272557) (xy 6.687621 -501.182754)
			(xy 6.675786 -501.091597) (xy 6.671831 -500.99976) (xy 1.69926 -500.99976) (xy 1.69926 -506.851412)
			(xy 51.474116 -506.851412) (xy 53.125624 -506.851412) (xy 53.125624 -508.503428) (xy 51.474116 -508.503428)
			(xy 51.474116 -506.851412) (xy 1.69926 -506.851412) (xy 1.69926 -507.717975) (xy 47.97424 -507.717975)
			(xy 47.97424 -507.636865) (xy 47.98219 -507.556146) (xy 47.998013 -507.476595) (xy 48.021558 -507.398979)
			(xy 48.052597 -507.324043) (xy 48.090832 -507.252511) (xy 48.135894 -507.185071) (xy 48.187349 -507.122372)
			(xy 48.244702 -507.065019) (xy 48.307401 -507.013564) (xy 48.374841 -506.968502) (xy 48.446373 -506.930267)
			(xy 48.521309 -506.899228) (xy 48.598925 -506.875683) (xy 48.678476 -506.85986) (xy 48.759195 -506.85191)
			(xy 48.840305 -506.85191) (xy 48.921024 -506.85986) (xy 49.000575 -506.875683) (xy 49.078191 -506.899228)
			(xy 49.153127 -506.930267) (xy 49.224659 -506.968502) (xy 49.292099 -507.013564) (xy 49.354798 -507.065019)
			(xy 49.412151 -507.122372) (xy 49.463606 -507.185071) (xy 49.508668 -507.252511) (xy 49.546903 -507.324043)
			(xy 49.577942 -507.398979) (xy 49.601487 -507.476595) (xy 49.61731 -507.556146) (xy 49.62526 -507.636865)
			(xy 49.625758 -507.67742) (xy 49.62526 -507.717975) (xy 49.61731 -507.798694) (xy 49.601487 -507.878245)
			(xy 49.577942 -507.955861) (xy 49.546903 -508.030797) (xy 49.508668 -508.102329) (xy 49.463606 -508.169769)
			(xy 49.412151 -508.232468) (xy 49.354798 -508.289821) (xy 49.292099 -508.341276) (xy 49.224659 -508.386338)
			(xy 49.153127 -508.424573) (xy 49.078191 -508.455612) (xy 49.000575 -508.479157) (xy 48.921024 -508.49498)
			(xy 48.840305 -508.50293) (xy 48.759195 -508.50293) (xy 48.678476 -508.49498) (xy 48.598925 -508.479157)
			(xy 48.521309 -508.455612) (xy 48.446373 -508.424573) (xy 48.374841 -508.386338) (xy 48.307401 -508.341276)
			(xy 48.244702 -508.289821) (xy 48.187349 -508.232468) (xy 48.135894 -508.169769) (xy 48.090832 -508.102329)
			(xy 48.052597 -508.030797) (xy 48.021558 -507.955861) (xy 47.998013 -507.878245) (xy 47.98219 -507.798694)
			(xy 47.97424 -507.717975) (xy 1.69926 -507.717975) (xy 1.69926 -511.049778) (xy 6.671831 -511.049778)
			(xy 6.675786 -510.957941) (xy 6.687621 -510.866784) (xy 6.707248 -510.776981) (xy 6.734522 -510.689199)
			(xy 6.769242 -510.604085) (xy 6.81115 -510.522272) (xy 6.859936 -510.444364) (xy 6.915239 -510.370939)
			(xy 6.976649 -510.302539) (xy 7.043711 -510.239672) (xy 7.11593 -510.182802) (xy 7.19277 -510.132351)
			(xy 7.273663 -510.088692) (xy 7.358009 -510.052149) (xy 7.445185 -510.022992) (xy 7.534544 -510.001438)
			(xy 7.625425 -509.987644) (xy 7.717156 -509.981714) (xy 7.809057 -509.983692) (xy 7.900448 -509.993563)
			(xy 7.990652 -510.011253) (xy 8.079001 -510.036633) (xy 8.164841 -510.069513) (xy 8.247537 -510.109651)
			(xy 8.326477 -510.15675) (xy 8.401075 -510.21046) (xy 8.470781 -510.270384) (xy 8.507692 -510.308098)
			(xy 79.39024 -510.308098) (xy 79.39024 -509.119378) (xy 79.390919 -509.083311) (xy 79.40125 -509.01192)
			(xy 79.410814 -508.977138) (xy 79.41564 -508.959612) (xy 79.41564 -508.585724) (xy 80.381856 -508.585724)
			(xy 80.381856 -508.959612) (xy 80.386682 -508.977138) (xy 80.396226 -509.011924) (xy 80.406552 -509.083313)
			(xy 80.407256 -509.119378) (xy 80.407256 -509.32461) (xy 80.783176 -509.32461) (xy 80.783176 -508.515874)
			(xy 80.783661 -508.483147) (xy 80.792059 -508.418234) (xy 80.808713 -508.354935) (xy 80.833348 -508.294294)
			(xy 80.865556 -508.237313) (xy 80.884776 -508.21082) (xy 80.910176 -508.177038) (xy 80.910176 -508.16002)
			(xy 80.925416 -508.16002) (xy 80.96123 -508.12954) (xy 80.986407 -508.108687) (xy 81.041139 -508.072936)
			(xy 81.100004 -508.044497) (xy 81.162029 -508.023842) (xy 81.226191 -508.011311) (xy 81.29143 -508.007111)
			(xy 81.356669 -508.011311) (xy 81.420831 -508.023842) (xy 81.482856 -508.044497) (xy 81.541721 -508.072936)
			(xy 81.596453 -508.108687) (xy 81.62163 -508.12954) (xy 81.657444 -508.16002) (xy 81.672684 -508.16002)
			(xy 81.672684 -508.177038) (xy 81.698084 -508.21082) (xy 81.714513 -508.233362) (xy 81.742882 -508.28139)
			(xy 81.765818 -508.332238) (xy 81.774792 -508.358648) (xy 81.780158 -508.37374) (xy 81.797289 -508.400795)
			(xy 81.820616 -508.422734) (xy 81.84867 -508.438175) (xy 81.879685 -508.446146) (xy 81.911707 -508.446146)
			(xy 81.942722 -508.438175) (xy 81.970776 -508.422734) (xy 81.994103 -508.400795) (xy 82.011234 -508.37374)
			(xy 82.0166 -508.358648) (xy 82.025572 -508.332237) (xy 82.048514 -508.281393) (xy 82.076883 -508.233364)
			(xy 82.093308 -508.21082) (xy 82.118708 -508.177038) (xy 82.118708 -508.16002) (xy 82.133948 -508.16002)
			(xy 82.169762 -508.12954) (xy 82.194939 -508.108687) (xy 82.249671 -508.072936) (xy 82.308536 -508.044497)
			(xy 82.370561 -508.023842) (xy 82.434723 -508.011311) (xy 82.499962 -508.007111) (xy 82.565201 -508.011311)
			(xy 82.629363 -508.023842) (xy 82.691388 -508.044497) (xy 82.750253 -508.072936) (xy 82.804985 -508.108687)
			(xy 82.830162 -508.12954) (xy 82.865976 -508.16002) (xy 82.881216 -508.16002) (xy 82.881216 -508.177038)
			(xy 82.906616 -508.21082) (xy 82.925875 -508.237288) (xy 82.958097 -508.294266) (xy 82.982731 -508.354913)
			(xy 82.999367 -508.418222) (xy 83.00773 -508.483144) (xy 83.008216 -508.515874) (xy 83.008216 -508.96012)
			(xy 86.39887 -508.96012) (xy 86.402874 -508.760022) (xy 86.414881 -508.560244) (xy 86.434872 -508.361107)
			(xy 86.462814 -508.162929) (xy 86.498662 -507.966027) (xy 86.54236 -507.770718) (xy 86.593837 -507.577313)
			(xy 86.653011 -507.386123) (xy 86.719787 -507.197453) (xy 86.794059 -507.011606) (xy 86.875706 -506.828879)
			(xy 86.964599 -506.649566) (xy 87.060595 -506.473952) (xy 87.16354 -506.30232) (xy 87.27327 -506.134944)
			(xy 87.389608 -505.972093) (xy 87.512369 -505.814026) (xy 87.641356 -505.660998) (xy 87.776363 -505.513253)
			(xy 87.917172 -505.371027) (xy 88.063559 -505.23455) (xy 88.215289 -505.104038) (xy 88.37212 -504.979702)
			(xy 88.533799 -504.86174) (xy 88.700069 -504.750341) (xy 88.870662 -504.645684) (xy 89.045306 -504.547936)
			(xy 89.223722 -504.457253) (xy 89.405622 -504.373782) (xy 89.590717 -504.297655) (xy 89.778709 -504.228995)
			(xy 89.969298 -504.167911) (xy 90.162178 -504.114501) (xy 90.35704 -504.068852) (xy 90.553573 -504.031035)
			(xy 90.751462 -504.001111) (xy 90.950389 -503.979129) (xy 91.150037 -503.965124) (xy 91.350085 -503.959118)
			(xy 91.550213 -503.96112) (xy 91.750101 -503.971128) (xy 91.949428 -503.989125) (xy 92.147876 -504.015083)
			(xy 92.345126 -504.04896) (xy 92.540863 -504.090702) (xy 92.734773 -504.140241) (xy 92.926546 -504.197499)
			(xy 93.115875 -504.262384) (xy 93.302455 -504.334792) (xy 93.48599 -504.414608) (xy 93.666184 -504.501702)
			(xy 93.842749 -504.595936) (xy 94.015402 -504.697159) (xy 94.183867 -504.805209) (xy 94.347875 -504.919912)
			(xy 94.507162 -505.041086) (xy 94.661473 -505.168535) (xy 94.810561 -505.302056) (xy 94.954188 -505.441436)
			(xy 95.092124 -505.58645) (xy 95.224147 -505.736867) (xy 95.350046 -505.892445) (xy 95.367266 -505.915557)
			(xy 96.320598 -505.915557) (xy 96.320598 -505.802003) (xy 96.328519 -505.688727) (xy 96.344322 -505.576279)
			(xy 96.367931 -505.465208) (xy 96.399231 -505.356053) (xy 96.438068 -505.249348) (xy 96.484254 -505.145613)
			(xy 96.537564 -505.045351) (xy 96.597738 -504.949053) (xy 96.664483 -504.857187) (xy 96.737473 -504.7702)
			(xy 96.816354 -504.688517) (xy 96.90074 -504.612535) (xy 96.990221 -504.542625) (xy 97.084361 -504.479127)
			(xy 97.182701 -504.42235) (xy 97.284761 -504.372572) (xy 97.390046 -504.330034) (xy 97.498041 -504.294944)
			(xy 97.608221 -504.267473) (xy 97.720049 -504.247755) (xy 97.83298 -504.235885) (xy 97.946464 -504.231923)
			(xy 98.059948 -504.235885) (xy 98.172879 -504.247755) (xy 98.284707 -504.267473) (xy 98.394887 -504.294944)
			(xy 98.502882 -504.330034) (xy 98.608167 -504.372572) (xy 98.710227 -504.42235) (xy 98.808567 -504.479127)
			(xy 98.902707 -504.542625) (xy 98.992188 -504.612535) (xy 99.076574 -504.688517) (xy 99.155455 -504.7702)
			(xy 99.228445 -504.857187) (xy 99.29519 -504.949053) (xy 99.355364 -505.045351) (xy 99.408674 -505.145613)
			(xy 99.45486 -505.249348) (xy 99.493697 -505.356053) (xy 99.524997 -505.465208) (xy 99.548606 -505.576279)
			(xy 99.564409 -505.688727) (xy 99.57233 -505.802003) (xy 99.572826 -505.85878) (xy 99.57233 -505.915557)
			(xy 99.564409 -506.028833) (xy 99.548606 -506.141281) (xy 99.524997 -506.252352) (xy 99.493697 -506.361507)
			(xy 99.45486 -506.468212) (xy 99.408674 -506.571947) (xy 99.355364 -506.672209) (xy 99.29519 -506.768507)
			(xy 99.228445 -506.860373) (xy 99.155455 -506.94736) (xy 99.076574 -507.029043) (xy 98.992188 -507.105025)
			(xy 98.902707 -507.174935) (xy 98.808567 -507.238433) (xy 98.710227 -507.29521) (xy 98.608167 -507.344988)
			(xy 98.502882 -507.387526) (xy 98.394887 -507.422616) (xy 98.284707 -507.450087) (xy 98.172879 -507.469805)
			(xy 98.059948 -507.481675) (xy 97.946464 -507.485638) (xy 97.83298 -507.481675) (xy 97.720049 -507.469805)
			(xy 97.608221 -507.450087) (xy 97.498041 -507.422616) (xy 97.390046 -507.387526) (xy 97.284761 -507.344988)
			(xy 97.182701 -507.29521) (xy 97.084361 -507.238433) (xy 96.990221 -507.174935) (xy 96.90074 -507.105025)
			(xy 96.816354 -507.029043) (xy 96.737473 -506.94736) (xy 96.664483 -506.860373) (xy 96.597738 -506.768507)
			(xy 96.537564 -506.672209) (xy 96.484254 -506.571947) (xy 96.438068 -506.468212) (xy 96.399231 -506.361507)
			(xy 96.367931 -506.252352) (xy 96.344322 -506.141281) (xy 96.328519 -506.028833) (xy 96.320598 -505.915557)
			(xy 95.367266 -505.915557) (xy 95.46962 -506.052937) (xy 95.582676 -506.218083) (xy 95.689035 -506.387621)
			(xy 95.788526 -506.561279) (xy 95.880989 -506.738778) (xy 95.966276 -506.919834) (xy 96.044251 -507.104158)
			(xy 96.114788 -507.291454) (xy 96.177776 -507.481422) (xy 96.233113 -507.673758) (xy 96.28071 -507.868154)
			(xy 96.320491 -508.064299) (xy 96.352393 -508.261878) (xy 96.376364 -508.460575) (xy 96.392366 -508.660073)
			(xy 96.400373 -508.860051) (xy 96.400874 -508.96012) (xy 96.400373 -509.060189) (xy 96.392366 -509.260167)
			(xy 96.376364 -509.459665) (xy 96.352393 -509.658362) (xy 96.320491 -509.855941) (xy 96.28071 -510.052086)
			(xy 96.233113 -510.246482) (xy 96.177776 -510.438818) (xy 96.114788 -510.628786) (xy 96.044251 -510.816082)
			(xy 95.966276 -511.000406) (xy 95.880989 -511.181462) (xy 95.788526 -511.358961) (xy 95.689035 -511.532619)
			(xy 95.582676 -511.702157) (xy 95.46962 -511.867303) (xy 95.350046 -512.027795) (xy 95.224147 -512.183373)
			(xy 95.092124 -512.33379) (xy 94.954188 -512.478804) (xy 94.810561 -512.618184) (xy 94.661473 -512.751705)
			(xy 94.507162 -512.879154) (xy 94.347875 -513.000328) (xy 94.183867 -513.115031) (xy 94.015402 -513.223081)
			(xy 93.842749 -513.324304) (xy 93.666184 -513.418538) (xy 93.48599 -513.505632) (xy 93.302455 -513.585448)
			(xy 93.115875 -513.657856) (xy 92.926546 -513.722741) (xy 92.734773 -513.779999) (xy 92.540863 -513.829538)
			(xy 92.345126 -513.87128) (xy 92.147876 -513.905157) (xy 91.949428 -513.931115) (xy 91.750101 -513.949112)
			(xy 91.550213 -513.95912) (xy 91.350085 -513.961122) (xy 91.150037 -513.955116) (xy 90.950389 -513.941111)
			(xy 90.751462 -513.919129) (xy 90.553573 -513.889205) (xy 90.35704 -513.851388) (xy 90.162178 -513.805739)
			(xy 89.969298 -513.752329) (xy 89.778709 -513.691245) (xy 89.590717 -513.622585) (xy 89.405622 -513.546458)
			(xy 89.223722 -513.462987) (xy 89.045306 -513.372304) (xy 88.870662 -513.274556) (xy 88.700069 -513.169899)
			(xy 88.533799 -513.0585) (xy 88.37212 -512.940538) (xy 88.215289 -512.816202) (xy 88.063559 -512.68569)
			(xy 87.917172 -512.549213) (xy 87.776363 -512.406987) (xy 87.641356 -512.259242) (xy 87.512369 -512.106214)
			(xy 87.389608 -511.948147) (xy 87.27327 -511.785296) (xy 87.16354 -511.61792) (xy 87.060595 -511.446288)
			(xy 86.964599 -511.270674) (xy 86.875706 -511.091361) (xy 86.794059 -510.908634) (xy 86.719787 -510.722787)
			(xy 86.653011 -510.534117) (xy 86.593837 -510.342927) (xy 86.54236 -510.149522) (xy 86.498662 -509.954213)
			(xy 86.462814 -509.757311) (xy 86.434872 -509.559133) (xy 86.414881 -509.359996) (xy 86.402874 -509.160218)
			(xy 86.39887 -508.96012) (xy 83.008216 -508.96012) (xy 83.008216 -509.339088) (xy 83.007656 -509.370842)
			(xy 82.999758 -509.433858) (xy 82.984069 -509.495398) (xy 82.960836 -509.554504) (xy 82.930419 -509.610255)
			(xy 82.893294 -509.661782) (xy 82.850038 -509.708282) (xy 82.801325 -509.74903) (xy 82.747915 -509.783392)
			(xy 82.69064 -509.810831) (xy 82.630393 -509.830921) (xy 82.568112 -509.843348) (xy 82.504768 -509.847918)
			(xy 82.441349 -509.844561) (xy 82.378842 -509.833328) (xy 82.318221 -509.814395) (xy 82.260431 -509.788057)
			(xy 82.206374 -509.754724) (xy 82.15689 -509.714915) (xy 82.112752 -509.669252) (xy 82.093308 -509.644142)
			(xy 82.078982 -509.62581) (xy 82.044749 -509.594307) (xy 82.005354 -509.569559) (xy 81.962114 -509.552394)
			(xy 81.916472 -509.543385) (xy 81.869952 -509.542832) (xy 81.824109 -509.550754) (xy 81.780473 -509.566887)
			(xy 81.740502 -509.590691) (xy 81.705529 -509.621372) (xy 81.690718 -509.639316) (xy 81.670807 -509.663662)
			(xy 81.626068 -509.707865) (xy 81.576218 -509.746211) (xy 81.522018 -509.778114) (xy 81.464296 -509.803087)
			(xy 81.403934 -509.820749) (xy 81.341855 -509.830829) (xy 81.279006 -509.833173) (xy 81.216348 -509.827746)
			(xy 81.154838 -509.814631) (xy 81.095416 -509.794027) (xy 81.03899 -509.76625) (xy 80.986422 -509.731724)
			(xy 80.938514 -509.690977) (xy 80.896 -509.644631) (xy 80.859527 -509.593394) (xy 80.829655 -509.538049)
			(xy 80.806838 -509.479441) (xy 80.791425 -509.418467) (xy 80.783653 -509.356056) (xy 80.783176 -509.32461)
			(xy 80.407256 -509.32461) (xy 80.407256 -510.308098) (xy 80.406754 -510.340059) (xy 80.398743 -510.403477)
			(xy 80.382846 -510.465391) (xy 80.359314 -510.524824) (xy 80.32852 -510.580839) (xy 80.290947 -510.632554)
			(xy 80.24719 -510.679151) (xy 80.197937 -510.719896) (xy 80.143966 -510.754147) (xy 80.086127 -510.781364)
			(xy 80.025334 -510.801117) (xy 79.962544 -510.813095) (xy 79.898748 -510.817109) (xy 79.834952 -510.813095)
			(xy 79.772162 -510.801117) (xy 79.711369 -510.781364) (xy 79.65353 -510.754147) (xy 79.599559 -510.719896)
			(xy 79.550306 -510.679151) (xy 79.506549 -510.632554) (xy 79.468976 -510.580839) (xy 79.438182 -510.524824)
			(xy 79.41465 -510.465391) (xy 79.398753 -510.403477) (xy 79.390742 -510.340059) (xy 79.39024 -510.308098)
			(xy 8.507692 -510.308098) (xy 8.535076 -510.336078) (xy 8.593487 -510.407056) (xy 8.645579 -510.482793)
			(xy 8.690968 -510.562728) (xy 8.729318 -510.646268) (xy 8.760343 -510.732796) (xy 8.783816 -510.821671)
			(xy 8.799562 -510.912235) (xy 8.807464 -511.003817) (xy 8.807958 -511.049778) (xy 8.807464 -511.095739)
			(xy 8.799562 -511.187321) (xy 8.783816 -511.277885) (xy 8.760343 -511.36676) (xy 8.729318 -511.453288)
			(xy 8.690968 -511.536828) (xy 8.645579 -511.616763) (xy 8.593487 -511.6925) (xy 8.535076 -511.763478)
			(xy 8.470781 -511.829172) (xy 8.401075 -511.889096) (xy 8.326477 -511.942806) (xy 8.247537 -511.989905)
			(xy 8.164841 -512.030043) (xy 8.079001 -512.062923) (xy 7.990652 -512.088303) (xy 7.900448 -512.105993)
			(xy 7.809057 -512.115864) (xy 7.717156 -512.117842) (xy 7.625425 -512.111912) (xy 7.534544 -512.098118)
			(xy 7.445185 -512.076564) (xy 7.358009 -512.047407) (xy 7.273663 -512.010864) (xy 7.19277 -511.967205)
			(xy 7.11593 -511.916754) (xy 7.043711 -511.859884) (xy 6.976649 -511.797017) (xy 6.915239 -511.728617)
			(xy 6.859936 -511.655192) (xy 6.81115 -511.577284) (xy 6.769242 -511.495471) (xy 6.734522 -511.410357)
			(xy 6.707248 -511.322575) (xy 6.687621 -511.232772) (xy 6.675786 -511.141615) (xy 6.671831 -511.049778)
			(xy 1.69926 -511.049778) (xy 1.69926 -512.501642) (xy 3.290253 -514.092635) (xy 4.852911 -514.092635)
			(xy 4.852911 -514.006909) (xy 4.860821 -513.921549) (xy 4.876573 -513.837282) (xy 4.900033 -513.754829)
			(xy 4.931001 -513.674892) (xy 4.969212 -513.598153) (xy 5.014341 -513.525267) (xy 5.066002 -513.456856)
			(xy 5.123756 -513.393504) (xy 5.187108 -513.33575) (xy 5.255519 -513.284089) (xy 5.328405 -513.23896)
			(xy 5.405144 -513.200749) (xy 5.485081 -513.169781) (xy 5.567534 -513.146321) (xy 5.651801 -513.130569)
			(xy 5.737161 -513.122659) (xy 5.822887 -513.122659) (xy 5.908247 -513.130569) (xy 5.992514 -513.146321)
			(xy 6.074967 -513.169781) (xy 6.154904 -513.200749) (xy 6.231643 -513.23896) (xy 6.304529 -513.284089)
			(xy 6.37294 -513.33575) (xy 6.436292 -513.393504) (xy 6.494046 -513.456856) (xy 6.545707 -513.525267)
			(xy 6.590836 -513.598153) (xy 6.629047 -513.674892) (xy 6.660015 -513.754829) (xy 6.683475 -513.837282)
			(xy 6.699227 -513.921549) (xy 6.707137 -514.006909) (xy 6.707632 -514.049772) (xy 6.707137 -514.092635)
			(xy 6.699227 -514.177995) (xy 6.683475 -514.262262) (xy 6.660015 -514.344715) (xy 6.629047 -514.424652)
			(xy 6.590836 -514.501391) (xy 6.545707 -514.574277) (xy 6.494046 -514.642688) (xy 6.436292 -514.70604)
			(xy 6.37294 -514.763794) (xy 6.304529 -514.815455) (xy 6.231643 -514.860584) (xy 6.154904 -514.898795)
			(xy 6.074967 -514.929763) (xy 5.992514 -514.953223) (xy 5.908247 -514.968975) (xy 5.822887 -514.976885)
			(xy 5.737161 -514.976885) (xy 5.651801 -514.968975) (xy 5.567534 -514.953223) (xy 5.485081 -514.929763)
			(xy 5.405144 -514.898795) (xy 5.328405 -514.860584) (xy 5.255519 -514.815455) (xy 5.187108 -514.763794)
			(xy 5.123756 -514.70604) (xy 5.066002 -514.642688) (xy 5.014341 -514.574277) (xy 4.969212 -514.501391)
			(xy 4.931001 -514.424652) (xy 4.900033 -514.344715) (xy 4.876573 -514.262262) (xy 4.860821 -514.177995)
			(xy 4.852911 -514.092635) (xy 3.290253 -514.092635) (xy 5.32003 -516.122412) (xy 6.707632 -516.122412)
			(xy 6.707632 -517.97712) (xy 4.852416 -517.97712) (xy 4.852416 -516.589772) (xy 1.703578 -513.440934)
			(xy 1.686936 -513.425002) (xy 1.649022 -513.398835) (xy 1.607013 -513.379931) (xy 1.562285 -513.368908)
			(xy 1.516302 -513.366127) (xy 1.470572 -513.371679) (xy 1.42659 -513.385383) (xy 1.385799 -513.406789)
			(xy 1.349535 -513.435197) (xy 1.318984 -513.469676) (xy 1.295148 -513.509097) (xy 1.278808 -513.552168)
			(xy 1.270498 -513.597479) (xy 1.27 -513.620512) (xy 1.27 -518.194544) (xy 51.322732 -518.194544)
			(xy 52.974748 -518.194544) (xy 52.974748 -519.049762) (xy 69.997838 -519.049762) (xy 70.001826 -518.797142)
			(xy 70.013787 -518.544774) (xy 70.033709 -518.29291) (xy 70.061573 -518.0418) (xy 70.097349 -517.791694)
			(xy 70.141003 -517.542843) (xy 70.192492 -517.295494) (xy 70.251763 -517.049893) (xy 70.318758 -516.806286)
			(xy 70.393409 -516.564916) (xy 70.475644 -516.326022) (xy 70.565378 -516.089844) (xy 70.662524 -515.856616)
			(xy 70.766984 -515.62657) (xy 70.878655 -515.399938) (xy 70.997424 -515.176943) (xy 71.123173 -514.957809)
			(xy 71.255778 -514.742754) (xy 71.395105 -514.531992) (xy 71.541017 -514.325734) (xy 71.693367 -514.124185)
			(xy 71.852003 -513.927545) (xy 72.016768 -513.736012) (xy 72.187498 -513.549775) (xy 72.364022 -513.369021)
			(xy 72.546164 -513.19393) (xy 72.733742 -513.024676) (xy 72.92657 -512.861427) (xy 73.124455 -512.704348)
			(xy 73.327201 -512.553593) (xy 73.534605 -512.409315) (xy 73.74646 -512.271655) (xy 73.962555 -512.140752)
			(xy 74.182675 -512.016736) (xy 74.4066 -511.899731) (xy 74.634107 -511.789853) (xy 74.864969 -511.687212)
			(xy 75.098957 -511.59191) (xy 75.335836 -511.504043) (xy 75.575372 -511.423696) (xy 75.817324 -511.350952)
			(xy 76.061452 -511.285882) (xy 76.307513 -511.228552) (xy 76.555261 -511.179018) (xy 76.804449 -511.137329)
			(xy 77.054829 -511.103528) (xy 77.306151 -511.077647) (xy 77.558165 -511.059714) (xy 77.810619 -511.049745)
			(xy 78.063263 -511.047751) (xy 78.315843 -511.053733) (xy 78.568109 -511.067686) (xy 78.819808 -511.089596)
			(xy 79.070691 -511.11944) (xy 79.320506 -511.15719) (xy 79.569005 -511.202807) (xy 79.81594 -511.256246)
			(xy 80.061065 -511.317454) (xy 80.304135 -511.386369) (xy 80.544909 -511.462924) (xy 80.783146 -511.547041)
			(xy 81.018609 -511.638638) (xy 81.251063 -511.737622) (xy 81.480277 -511.843894) (xy 81.706021 -511.95735)
			(xy 81.928071 -512.077875) (xy 82.146205 -512.205351) (xy 82.360207 -512.339649) (xy 82.569863 -512.480635)
			(xy 82.774963 -512.62817) (xy 82.975303 -512.782106) (xy 83.170684 -512.94229) (xy 83.360911 -513.108562)
			(xy 83.545794 -513.280757) (xy 83.72515 -513.458701) (xy 83.898798 -513.64222) (xy 84.066566 -513.831128)
			(xy 84.228287 -514.025239) (xy 84.3838 -514.224358) (xy 84.532949 -514.428287) (xy 84.675586 -514.636823)
			(xy 84.811569 -514.849758) (xy 84.940762 -515.06688) (xy 85.063037 -515.287972) (xy 85.178271 -515.512813)
			(xy 85.28635 -515.741181) (xy 85.387165 -515.972846) (xy 85.480617 -516.207579) (xy 85.566612 -516.445144)
			(xy 85.645065 -516.685306) (xy 85.715897 -516.927825) (xy 85.779038 -517.17246) (xy 85.834425 -517.418965)
			(xy 85.882002 -517.667096) (xy 85.921722 -517.916606) (xy 85.953546 -518.167245) (xy 85.977442 -518.418763)
			(xy 85.993386 -518.670911) (xy 86.001361 -518.923436) (xy 86.00186 -519.049762) (xy 86.001361 -519.176088)
			(xy 85.993386 -519.428613) (xy 85.977442 -519.680761) (xy 85.953546 -519.932279) (xy 85.921722 -520.182918)
			(xy 85.882002 -520.432428) (xy 85.834425 -520.680559) (xy 85.779038 -520.927064) (xy 85.715897 -521.171699)
			(xy 85.645065 -521.414218) (xy 85.566612 -521.65438) (xy 85.480617 -521.891945) (xy 85.387165 -522.126678)
			(xy 85.28635 -522.358343) (xy 85.178271 -522.586711) (xy 85.063037 -522.811552) (xy 84.940762 -523.032644)
			(xy 84.811569 -523.249766) (xy 84.675586 -523.462701) (xy 84.532949 -523.671237) (xy 84.3838 -523.875166)
			(xy 84.228287 -524.074285) (xy 84.066566 -524.268396) (xy 83.898798 -524.457304) (xy 83.72515 -524.640823)
			(xy 83.545794 -524.818767) (xy 83.360911 -524.990962) (xy 83.170684 -525.157234) (xy 82.975303 -525.317418)
			(xy 82.774963 -525.471354) (xy 82.569863 -525.618889) (xy 82.360207 -525.759875) (xy 82.146205 -525.894173)
			(xy 81.928071 -526.021649) (xy 81.706021 -526.142174) (xy 81.480277 -526.25563) (xy 81.251063 -526.361902)
			(xy 81.018609 -526.460886) (xy 80.783146 -526.552483) (xy 80.544909 -526.6366) (xy 80.304135 -526.713155)
			(xy 80.061065 -526.78207) (xy 79.81594 -526.843278) (xy 79.569005 -526.896717) (xy 79.320506 -526.942334)
			(xy 79.070691 -526.980084) (xy 78.819808 -527.009928) (xy 78.568109 -527.031838) (xy 78.315843 -527.045791)
			(xy 78.063263 -527.051773) (xy 77.810619 -527.049779) (xy 77.558165 -527.03981) (xy 77.306151 -527.021877)
			(xy 77.054829 -526.995996) (xy 76.804449 -526.962195) (xy 76.555261 -526.920506) (xy 76.307513 -526.870972)
			(xy 76.061452 -526.813642) (xy 75.817324 -526.748572) (xy 75.575372 -526.675828) (xy 75.335836 -526.595481)
			(xy 75.098957 -526.507614) (xy 74.864969 -526.412312) (xy 74.634107 -526.309671) (xy 74.4066 -526.199793)
			(xy 74.182675 -526.082788) (xy 73.962555 -525.958772) (xy 73.74646 -525.827869) (xy 73.534605 -525.690209)
			(xy 73.327201 -525.545931) (xy 73.124455 -525.395176) (xy 72.92657 -525.238097) (xy 72.733742 -525.074848)
			(xy 72.546164 -524.905594) (xy 72.364022 -524.730503) (xy 72.187498 -524.549749) (xy 72.016768 -524.363512)
			(xy 71.852003 -524.171979) (xy 71.693367 -523.975339) (xy 71.541017 -523.77379) (xy 71.395105 -523.567532)
			(xy 71.255778 -523.35677) (xy 71.123173 -523.141715) (xy 70.997424 -522.922581) (xy 70.878655 -522.699586)
			(xy 70.766984 -522.472954) (xy 70.662524 -522.242908) (xy 70.565378 -522.00968) (xy 70.475644 -521.773502)
			(xy 70.393409 -521.534608) (xy 70.318758 -521.293238) (xy 70.251763 -521.049631) (xy 70.192492 -520.80403)
			(xy 70.141003 -520.556681) (xy 70.097349 -520.30783) (xy 70.061573 -520.057724) (xy 70.033709 -519.806614)
			(xy 70.013787 -519.55475) (xy 70.001826 -519.302382) (xy 69.997838 -519.049762) (xy 52.974748 -519.049762)
			(xy 52.974748 -519.84656) (xy 51.322732 -519.84656) (xy 51.322732 -518.194544) (xy 1.27 -518.194544)
			(xy 1.27 -520.04976) (xy 6.671831 -520.04976) (xy 6.675786 -519.957923) (xy 6.687621 -519.866766)
			(xy 6.707248 -519.776963) (xy 6.734522 -519.689181) (xy 6.769242 -519.604067) (xy 6.81115 -519.522254)
			(xy 6.859936 -519.444346) (xy 6.915239 -519.370921) (xy 6.976649 -519.302521) (xy 7.043711 -519.239654)
			(xy 7.11593 -519.182784) (xy 7.19277 -519.132333) (xy 7.273663 -519.088674) (xy 7.358009 -519.052131)
			(xy 7.445185 -519.022974) (xy 7.534544 -519.00142) (xy 7.625425 -518.987626) (xy 7.717156 -518.981696)
			(xy 7.809057 -518.983674) (xy 7.900448 -518.993545) (xy 7.990652 -519.011235) (xy 8.079001 -519.036615)
			(xy 8.142942 -519.061107) (xy 47.82311 -519.061107) (xy 47.82311 -518.979997) (xy 47.83106 -518.899278)
			(xy 47.846883 -518.819727) (xy 47.870428 -518.742111) (xy 47.901467 -518.667175) (xy 47.939702 -518.595643)
			(xy 47.984764 -518.528203) (xy 48.036219 -518.465504) (xy 48.093572 -518.408151) (xy 48.156271 -518.356696)
			(xy 48.223711 -518.311634) (xy 48.295243 -518.273399) (xy 48.370179 -518.24236) (xy 48.447795 -518.218815)
			(xy 48.527346 -518.202992) (xy 48.608065 -518.195042) (xy 48.689175 -518.195042) (xy 48.769894 -518.202992)
			(xy 48.849445 -518.218815) (xy 48.927061 -518.24236) (xy 49.001997 -518.273399) (xy 49.073529 -518.311634)
			(xy 49.140969 -518.356696) (xy 49.203668 -518.408151) (xy 49.261021 -518.465504) (xy 49.312476 -518.528203)
			(xy 49.357538 -518.595643) (xy 49.395773 -518.667175) (xy 49.426812 -518.742111) (xy 49.450357 -518.819727)
			(xy 49.46618 -518.899278) (xy 49.47413 -518.979997) (xy 49.474628 -519.020552) (xy 49.47413 -519.061107)
			(xy 49.46618 -519.141826) (xy 49.450357 -519.221377) (xy 49.426812 -519.298993) (xy 49.395773 -519.373929)
			(xy 49.357538 -519.445461) (xy 49.312476 -519.512901) (xy 49.261021 -519.5756) (xy 49.203668 -519.632953)
			(xy 49.140969 -519.684408) (xy 49.073529 -519.72947) (xy 49.001997 -519.767705) (xy 48.927061 -519.798744)
			(xy 48.849445 -519.822289) (xy 48.769894 -519.838112) (xy 48.689175 -519.846062) (xy 48.608065 -519.846062)
			(xy 48.527346 -519.838112) (xy 48.447795 -519.822289) (xy 48.370179 -519.798744) (xy 48.295243 -519.767705)
			(xy 48.223711 -519.72947) (xy 48.156271 -519.684408) (xy 48.093572 -519.632953) (xy 48.036219 -519.5756)
			(xy 47.984764 -519.512901) (xy 47.939702 -519.445461) (xy 47.901467 -519.373929) (xy 47.870428 -519.298993)
			(xy 47.846883 -519.221377) (xy 47.83106 -519.141826) (xy 47.82311 -519.061107) (xy 8.142942 -519.061107)
			(xy 8.164841 -519.069495) (xy 8.247537 -519.109633) (xy 8.326477 -519.156732) (xy 8.401075 -519.210442)
			(xy 8.470781 -519.270366) (xy 8.535076 -519.33606) (xy 8.593487 -519.407038) (xy 8.645579 -519.482775)
			(xy 8.690968 -519.56271) (xy 8.729318 -519.64625) (xy 8.760343 -519.732778) (xy 8.783816 -519.821653)
			(xy 8.799562 -519.912217) (xy 8.807464 -520.003799) (xy 8.807958 -520.04976) (xy 8.807464 -520.095721)
			(xy 8.799562 -520.187303) (xy 8.783816 -520.277867) (xy 8.760343 -520.366742) (xy 8.729318 -520.45327)
			(xy 8.690968 -520.53681) (xy 8.645579 -520.616745) (xy 8.593487 -520.692482) (xy 8.535076 -520.76346)
			(xy 8.470781 -520.829154) (xy 8.401075 -520.889078) (xy 8.326477 -520.942788) (xy 8.247537 -520.989887)
			(xy 8.164841 -521.030025) (xy 8.079001 -521.062905) (xy 7.990652 -521.088285) (xy 7.900448 -521.105975)
			(xy 7.809057 -521.115846) (xy 7.717156 -521.117824) (xy 7.625425 -521.111894) (xy 7.534544 -521.0981)
			(xy 7.445185 -521.076546) (xy 7.358009 -521.047389) (xy 7.273663 -521.010846) (xy 7.19277 -520.967187)
			(xy 7.11593 -520.916736) (xy 7.043711 -520.859866) (xy 6.976649 -520.796999) (xy 6.915239 -520.728599)
			(xy 6.859936 -520.655174) (xy 6.81115 -520.577266) (xy 6.769242 -520.495453) (xy 6.734522 -520.410339)
			(xy 6.707248 -520.322557) (xy 6.687621 -520.232754) (xy 6.675786 -520.141597) (xy 6.671831 -520.04976)
			(xy 1.27 -520.04976) (xy 1.27 -524.500094) (xy 1.49987 -524.729964) (xy 23.50008 -524.729964) (xy 23.573919 -524.730454)
			(xy 23.721386 -524.738334) (xy 23.868223 -524.754063) (xy 24.014014 -524.777595) (xy 24.158343 -524.808865)
			(xy 24.3008 -524.847782) (xy 24.440981 -524.894237) (xy 24.578486 -524.948096) (xy 24.712926 -525.009208)
			(xy 24.843917 -525.077399) (xy 24.907748 -525.11452) (xy 24.950627 -525.140106) (xy 25.034722 -525.193968)
			(xy 25.075896 -525.222216) (xy 25.07615 -525.222216) (xy 25.077928 -525.22374) (xy 25.145573 -525.271385)
			(xy 25.275694 -525.373612) (xy 25.399481 -525.483425) (xy 25.45842 -525.541494) (xy 25.490151 -525.573501)
			(xy 25.551759 -525.639299) (xy 25.58161 -525.673066) (xy 25.586436 -525.6784) (xy 25.606245 -525.701205)
			(xy 25.644984 -525.747564) (xy 25.663906 -525.77111) (xy 25.722834 -525.847564) (xy 25.766299 -525.906856)
			(xy 25.847621 -526.029349) (xy 25.885394 -526.09242) (xy 25.922502 -526.156255) (xy 25.990667 -526.287252)
			(xy 26.051754 -526.421695) (xy 26.105588 -526.559203) (xy 26.152017 -526.699385) (xy 26.190908 -526.841842)
			(xy 26.222152 -526.98617) (xy 26.245659 -527.131958) (xy 26.261362 -527.278791) (xy 26.269217 -527.426253)
			(xy 26.269696 -527.500088) (xy 26.269696 -528.500086) (xy 26.270243 -528.52202) (xy 26.278593 -528.565086)
			(xy 26.294935 -528.605797) (xy 26.318682 -528.642682) (xy 26.348976 -528.674412) (xy 26.384723 -528.69984)
			(xy 26.424634 -528.718049) (xy 26.467268 -528.728382) (xy 26.489152 -528.729956)
		)
		(stroke
			(width 0)
			(type solid)
		)
		(fill yes)
		(layer "F.Cu")
		(net "P12V")
	)
	(gr_poly
		(pts
			(arc
				(start 28.804108 -116.685822)
				(mid 28.960906 -116.920487)
				(end 29.237686 -116.8654)
			)
			(xy 29.472382 -116.630704) (xy 37.217858 -116.630704)
			(arc
				(start 38.307772 -115.54079)
				(mid 38.363024 -115.263785)
				(end 38.128194 -115.106958)
			)
			(xy 29.663136 -115.106958) (xy 28.804108 -115.96624)
		)
		(stroke
			(width 0)
			(type solid)
		)
		(fill yes)
		(layer "B.Cu")
		(net "GND")
	)
	(gr_poly
		(pts
			(xy 83.003644 -430.150016) (xy 83.003143 -430.049886) (xy 82.995131 -429.849786) (xy 82.979119 -429.650167)
			(xy 82.955133 -429.451348) (xy 82.923212 -429.253649) (xy 82.883407 -429.057384) (xy 82.835781 -428.86287)
			(xy 82.78041 -428.670416) (xy 82.717384 -428.480333) (xy 82.646804 -428.292923) (xy 82.568781 -428.108487)
			(xy 82.483442 -427.92732) (xy 82.390923 -427.749713) (xy 82.291372 -427.575949) (xy 82.184948 -427.406308)
			(xy 82.071822 -427.24106) (xy 81.952176 -427.080471) (xy 81.8262 -426.924798) (xy 81.694096 -426.774289)
			(xy 81.556077 -426.629187) (xy 81.412362 -426.489723) (xy 81.263183 -426.35612) (xy 81.108778 -426.228593)
			(xy 80.949394 -426.107345) (xy 80.785286 -425.992572) (xy 80.616718 -425.884457) (xy 80.44396 -425.783172)
			(xy 80.267287 -425.68888) (xy 80.086983 -425.601733) (xy 79.903337 -425.521869) (xy 79.716642 -425.449417)
			(xy 79.527199 -425.384492) (xy 79.335309 -425.327199) (xy 79.141281 -425.277629) (xy 78.945424 -425.235862)
			(xy 78.748054 -425.201965) (xy 78.549485 -425.175991) (xy 78.350036 -425.157983) (xy 78.150027 -425.147969)
			(xy 77.949776 -425.145965) (xy 77.749606 -425.151975) (xy 77.549837 -425.165989) (xy 77.350789 -425.187985)
			(xy 77.152779 -425.217926) (xy 76.956127 -425.255766) (xy 76.761145 -425.301444) (xy 76.568148 -425.354886)
			(xy 76.377443 -425.416007) (xy 76.189336 -425.484709) (xy 76.004129 -425.560882) (xy 75.822117 -425.644405)
			(xy 75.643593 -425.735142) (xy 75.468842 -425.83295) (xy 75.298145 -425.937671) (xy 75.131774 -426.049138)
			(xy 74.969996 -426.167172) (xy 74.81307 -426.291584) (xy 74.661247 -426.422175) (xy 74.514771 -426.558736)
			(xy 74.373876 -426.701048) (xy 74.238787 -426.848883) (xy 74.109722 -427.002005) (xy 73.986886 -427.160167)
			(xy 73.870476 -427.323118) (xy 73.76068 -427.490596) (xy 73.657672 -427.662333) (xy 73.561617 -427.838053)
			(xy 73.47267 -428.017476) (xy 73.390973 -428.200314) (xy 73.316657 -428.386275) (xy 73.24984 -428.575059)
			(xy 73.19063 -428.766366) (xy 73.139121 -428.959889) (xy 73.095397 -429.155317) (xy 73.059526 -429.352339)
			(xy 73.031567 -429.550638) (xy 73.011564 -429.749896) (xy 72.99955 -429.949796) (xy 72.995543 -430.150016)
			(xy 75.484741 -430.150016) (xy 75.488769 -430.007724) (xy 75.500841 -429.865888) (xy 75.520918 -429.724961)
			(xy 75.548936 -429.585397) (xy 75.584805 -429.447641) (xy 75.62841 -429.312135) (xy 75.679611 -429.179313)
			(xy 75.738245 -429.0496) (xy 75.804123 -428.923413) (xy 75.877035 -428.801154) (xy 75.956747 -428.683217)
			(xy 76.043004 -428.569978) (xy 76.135528 -428.4618) (xy 76.234025 -428.35903) (xy 76.338179 -428.261997)
			(xy 76.447655 -428.171013) (xy 76.562103 -428.086367) (xy 76.681157 -428.008332) (xy 76.804435 -427.937158)
			(xy 76.931542 -427.873071) (xy 77.062071 -427.816279) (xy 77.195605 -427.766962) (xy 77.331714 -427.725279)
			(xy 77.469964 -427.691363) (xy 77.609911 -427.665323) (xy 77.751107 -427.647242) (xy 77.8931 -427.637179)
			(xy 78.035435 -427.635164) (xy 78.177656 -427.641206) (xy 78.319307 -427.655284) (xy 78.459935 -427.677353)
			(xy 78.599089 -427.707343) (xy 78.736324 -427.745158) (xy 78.871199 -427.790676) (xy 79.003283 -427.843752)
			(xy 79.132153 -427.904215) (xy 79.257396 -427.971872) (xy 79.37861 -428.046507) (xy 79.495408 -428.12788)
			(xy 79.607415 -428.21573) (xy 79.714273 -428.309777) (xy 79.815638 -428.409718) (xy 79.911187 -428.515234)
			(xy 80.000614 -428.625987) (xy 80.083632 -428.741621) (xy 80.159974 -428.861768) (xy 80.229397 -428.98604)
			(xy 80.291678 -429.114042) (xy 80.346618 -429.245362) (xy 80.39404 -429.379579) (xy 80.433793 -429.516265)
			(xy 80.465749 -429.654981) (xy 80.489806 -429.795282) (xy 80.505887 -429.93672) (xy 80.51394 -430.078841)
			(xy 80.514444 -430.150016) (xy 80.51394 -430.221191) (xy 80.505887 -430.363312) (xy 80.489806 -430.50475)
			(xy 80.465749 -430.645051) (xy 80.433793 -430.783767) (xy 80.39404 -430.920453) (xy 80.346618 -431.05467)
			(xy 80.291678 -431.18599) (xy 80.229397 -431.313992) (xy 80.159974 -431.438264) (xy 80.083632 -431.558411)
			(xy 80.000614 -431.674045) (xy 79.911187 -431.784798) (xy 79.815638 -431.890314) (xy 79.714273 -431.990255)
			(xy 79.607415 -432.084302) (xy 79.495408 -432.172152) (xy 79.37861 -432.253525) (xy 79.257396 -432.32816)
			(xy 79.132153 -432.395817) (xy 79.003283 -432.45628) (xy 78.871199 -432.509356) (xy 78.736324 -432.554874)
			(xy 78.599089 -432.592689) (xy 78.459935 -432.622679) (xy 78.319307 -432.644748) (xy 78.177656 -432.658826)
			(xy 78.035435 -432.664868) (xy 77.8931 -432.662853) (xy 77.751107 -432.65279) (xy 77.609911 -432.634709)
			(xy 77.469964 -432.608669) (xy 77.331714 -432.574753) (xy 77.195605 -432.53307) (xy 77.062071 -432.483753)
			(xy 76.931542 -432.426961) (xy 76.804435 -432.362874) (xy 76.681157 -432.2917) (xy 76.562103 -432.213665)
			(xy 76.447655 -432.129019) (xy 76.338179 -432.038035) (xy 76.234025 -431.941002) (xy 76.135528 -431.838232)
			(xy 76.043004 -431.730054) (xy 75.956747 -431.616815) (xy 75.877035 -431.498878) (xy 75.804123 -431.376619)
			(xy 75.738245 -431.250432) (xy 75.679611 -431.120719) (xy 75.62841 -430.987897) (xy 75.584805 -430.852391)
			(xy 75.548936 -430.714635) (xy 75.520918 -430.575071) (xy 75.500841 -430.434144) (xy 75.488769 -430.292308)
			(xy 75.484741 -430.150016) (xy 72.995543 -430.150016) (xy 72.99955 -430.350236) (xy 73.011564 -430.550136)
			(xy 73.031567 -430.749394) (xy 73.059526 -430.947693) (xy 73.095397 -431.144715) (xy 73.139121 -431.340143)
			(xy 73.19063 -431.533666) (xy 73.24984 -431.724973) (xy 73.316657 -431.913757) (xy 73.390973 -432.099718)
			(xy 73.47267 -432.282556) (xy 73.561617 -432.461979) (xy 73.657672 -432.637699) (xy 73.76068 -432.809436)
			(xy 73.870476 -432.976914) (xy 73.986886 -433.139865) (xy 74.109722 -433.298027) (xy 74.238787 -433.451149)
			(xy 74.373876 -433.598984) (xy 74.514771 -433.741296) (xy 74.661247 -433.877857) (xy 74.81307 -434.008448)
			(xy 74.969996 -434.13286) (xy 75.131774 -434.250894) (xy 75.298145 -434.362361) (xy 75.468842 -434.467082)
			(xy 75.643593 -434.56489) (xy 75.822117 -434.655627) (xy 76.004129 -434.73915) (xy 76.189336 -434.815323)
			(xy 76.377443 -434.884025) (xy 76.568148 -434.945146) (xy 76.761145 -434.998588) (xy 76.956127 -435.044266)
			(xy 77.152779 -435.082106) (xy 77.350789 -435.112047) (xy 77.549837 -435.134043) (xy 77.749606 -435.148057)
			(xy 77.949776 -435.154067) (xy 78.150027 -435.152063) (xy 78.350036 -435.142049) (xy 78.549485 -435.124041)
			(xy 78.748054 -435.098067) (xy 78.945424 -435.06417) (xy 79.141281 -435.022403) (xy 79.335309 -434.972833)
			(xy 79.527199 -434.91554) (xy 79.716642 -434.850615) (xy 79.903337 -434.778163) (xy 80.086983 -434.698299)
			(xy 80.267287 -434.611152) (xy 80.44396 -434.51686) (xy 80.616718 -434.415575) (xy 80.785286 -434.30746)
			(xy 80.949394 -434.192687) (xy 81.108778 -434.071439) (xy 81.263183 -433.943912) (xy 81.412362 -433.810309)
			(xy 81.556077 -433.670845) (xy 81.694096 -433.525743) (xy 81.8262 -433.375234) (xy 81.952176 -433.219561)
			(xy 82.071822 -433.058972) (xy 82.184948 -432.893724) (xy 82.291372 -432.724083) (xy 82.390923 -432.550319)
			(xy 82.483442 -432.372712) (xy 82.568781 -432.191545) (xy 82.646804 -432.007109) (xy 82.717384 -431.819699)
			(xy 82.78041 -431.629616) (xy 82.835781 -431.437162) (xy 82.883407 -431.242648) (xy 82.923212 -431.046383)
			(xy 82.955133 -430.848684) (xy 82.979119 -430.649865) (xy 82.995131 -430.450246) (xy 83.003143 -430.250146)
		)
		(stroke
			(width 0)
			(type solid)
		)
		(fill yes)
		(layer "B.Cu")
		(net "GND")
	)
	(gr_poly
		(pts
			(xy 83.003644 -341.250016) (xy 83.003143 -341.149886) (xy 82.995131 -340.949786) (xy 82.979119 -340.750167)
			(xy 82.955133 -340.551348) (xy 82.923212 -340.353649) (xy 82.883407 -340.157384) (xy 82.835781 -339.96287)
			(xy 82.78041 -339.770416) (xy 82.717384 -339.580333) (xy 82.646804 -339.392923) (xy 82.568781 -339.208487)
			(xy 82.483442 -339.02732) (xy 82.390923 -338.849713) (xy 82.291372 -338.675949) (xy 82.184948 -338.506308)
			(xy 82.071822 -338.34106) (xy 81.952176 -338.180471) (xy 81.8262 -338.024798) (xy 81.694096 -337.874289)
			(xy 81.556077 -337.729187) (xy 81.412362 -337.589723) (xy 81.263183 -337.45612) (xy 81.108778 -337.328593)
			(xy 80.949394 -337.207345) (xy 80.785286 -337.092572) (xy 80.616718 -336.984457) (xy 80.44396 -336.883172)
			(xy 80.267287 -336.78888) (xy 80.086983 -336.701733) (xy 79.903337 -336.621869) (xy 79.716642 -336.549417)
			(xy 79.527199 -336.484492) (xy 79.335309 -336.427199) (xy 79.141281 -336.377629) (xy 78.945424 -336.335862)
			(xy 78.748054 -336.301965) (xy 78.549485 -336.275991) (xy 78.350036 -336.257983) (xy 78.150027 -336.247969)
			(xy 77.949776 -336.245965) (xy 77.749606 -336.251975) (xy 77.549837 -336.265989) (xy 77.350789 -336.287985)
			(xy 77.152779 -336.317926) (xy 76.956127 -336.355766) (xy 76.761145 -336.401444) (xy 76.568148 -336.454886)
			(xy 76.377443 -336.516007) (xy 76.189336 -336.584709) (xy 76.004129 -336.660882) (xy 75.822117 -336.744405)
			(xy 75.643593 -336.835142) (xy 75.468842 -336.93295) (xy 75.298145 -337.037671) (xy 75.131774 -337.149138)
			(xy 74.969996 -337.267172) (xy 74.81307 -337.391584) (xy 74.661247 -337.522175) (xy 74.514771 -337.658736)
			(xy 74.373876 -337.801048) (xy 74.238787 -337.948883) (xy 74.109722 -338.102005) (xy 73.986886 -338.260167)
			(xy 73.870476 -338.423118) (xy 73.76068 -338.590596) (xy 73.657672 -338.762333) (xy 73.561617 -338.938053)
			(xy 73.47267 -339.117476) (xy 73.390973 -339.300314) (xy 73.316657 -339.486275) (xy 73.24984 -339.675059)
			(xy 73.19063 -339.866366) (xy 73.139121 -340.059889) (xy 73.095397 -340.255317) (xy 73.059526 -340.452339)
			(xy 73.031567 -340.650638) (xy 73.011564 -340.849896) (xy 72.99955 -341.049796) (xy 72.995543 -341.250016)
			(xy 75.484741 -341.250016) (xy 75.488769 -341.107724) (xy 75.500841 -340.965888) (xy 75.520918 -340.824961)
			(xy 75.548936 -340.685397) (xy 75.584805 -340.547641) (xy 75.62841 -340.412135) (xy 75.679611 -340.279313)
			(xy 75.738245 -340.1496) (xy 75.804123 -340.023413) (xy 75.877035 -339.901154) (xy 75.956747 -339.783217)
			(xy 76.043004 -339.669978) (xy 76.135528 -339.5618) (xy 76.234025 -339.45903) (xy 76.338179 -339.361997)
			(xy 76.447655 -339.271013) (xy 76.562103 -339.186367) (xy 76.681157 -339.108332) (xy 76.804435 -339.037158)
			(xy 76.931542 -338.973071) (xy 77.062071 -338.916279) (xy 77.195605 -338.866962) (xy 77.331714 -338.825279)
			(xy 77.469964 -338.791363) (xy 77.609911 -338.765323) (xy 77.751107 -338.747242) (xy 77.8931 -338.737179)
			(xy 78.035435 -338.735164) (xy 78.177656 -338.741206) (xy 78.319307 -338.755284) (xy 78.459935 -338.777353)
			(xy 78.599089 -338.807343) (xy 78.736324 -338.845158) (xy 78.871199 -338.890676) (xy 79.003283 -338.943752)
			(xy 79.132153 -339.004215) (xy 79.257396 -339.071872) (xy 79.37861 -339.146507) (xy 79.495408 -339.22788)
			(xy 79.607415 -339.31573) (xy 79.714273 -339.409777) (xy 79.815638 -339.509718) (xy 79.911187 -339.615234)
			(xy 80.000614 -339.725987) (xy 80.083632 -339.841621) (xy 80.159974 -339.961768) (xy 80.229397 -340.08604)
			(xy 80.291678 -340.214042) (xy 80.346618 -340.345362) (xy 80.39404 -340.479579) (xy 80.433793 -340.616265)
			(xy 80.465749 -340.754981) (xy 80.489806 -340.895282) (xy 80.505887 -341.03672) (xy 80.51394 -341.178841)
			(xy 80.514444 -341.250016) (xy 80.51394 -341.321191) (xy 80.505887 -341.463312) (xy 80.489806 -341.60475)
			(xy 80.465749 -341.745051) (xy 80.433793 -341.883767) (xy 80.39404 -342.020453) (xy 80.346618 -342.15467)
			(xy 80.291678 -342.28599) (xy 80.229397 -342.413992) (xy 80.159974 -342.538264) (xy 80.083632 -342.658411)
			(xy 80.000614 -342.774045) (xy 79.911187 -342.884798) (xy 79.815638 -342.990314) (xy 79.714273 -343.090255)
			(xy 79.607415 -343.184302) (xy 79.495408 -343.272152) (xy 79.37861 -343.353525) (xy 79.257396 -343.42816)
			(xy 79.132153 -343.495817) (xy 79.003283 -343.55628) (xy 78.871199 -343.609356) (xy 78.736324 -343.654874)
			(xy 78.599089 -343.692689) (xy 78.459935 -343.722679) (xy 78.319307 -343.744748) (xy 78.177656 -343.758826)
			(xy 78.035435 -343.764868) (xy 77.8931 -343.762853) (xy 77.751107 -343.75279) (xy 77.609911 -343.734709)
			(xy 77.469964 -343.708669) (xy 77.331714 -343.674753) (xy 77.195605 -343.63307) (xy 77.062071 -343.583753)
			(xy 76.931542 -343.526961) (xy 76.804435 -343.462874) (xy 76.681157 -343.3917) (xy 76.562103 -343.313665)
			(xy 76.447655 -343.229019) (xy 76.338179 -343.138035) (xy 76.234025 -343.041002) (xy 76.135528 -342.938232)
			(xy 76.043004 -342.830054) (xy 75.956747 -342.716815) (xy 75.877035 -342.598878) (xy 75.804123 -342.476619)
			(xy 75.738245 -342.350432) (xy 75.679611 -342.220719) (xy 75.62841 -342.087897) (xy 75.584805 -341.952391)
			(xy 75.548936 -341.814635) (xy 75.520918 -341.675071) (xy 75.500841 -341.534144) (xy 75.488769 -341.392308)
			(xy 75.484741 -341.250016) (xy 72.995543 -341.250016) (xy 72.99955 -341.450236) (xy 73.011564 -341.650136)
			(xy 73.031567 -341.849394) (xy 73.059526 -342.047693) (xy 73.095397 -342.244715) (xy 73.139121 -342.440143)
			(xy 73.19063 -342.633666) (xy 73.24984 -342.824973) (xy 73.316657 -343.013757) (xy 73.390973 -343.199718)
			(xy 73.47267 -343.382556) (xy 73.561617 -343.561979) (xy 73.657672 -343.737699) (xy 73.76068 -343.909436)
			(xy 73.870476 -344.076914) (xy 73.986886 -344.239865) (xy 74.109722 -344.398027) (xy 74.238787 -344.551149)
			(xy 74.373876 -344.698984) (xy 74.514771 -344.841296) (xy 74.661247 -344.977857) (xy 74.81307 -345.108448)
			(xy 74.969996 -345.23286) (xy 75.131774 -345.350894) (xy 75.298145 -345.462361) (xy 75.468842 -345.567082)
			(xy 75.643593 -345.66489) (xy 75.822117 -345.755627) (xy 76.004129 -345.83915) (xy 76.189336 -345.915323)
			(xy 76.377443 -345.984025) (xy 76.568148 -346.045146) (xy 76.761145 -346.098588) (xy 76.956127 -346.144266)
			(xy 77.152779 -346.182106) (xy 77.350789 -346.212047) (xy 77.549837 -346.234043) (xy 77.749606 -346.248057)
			(xy 77.949776 -346.254067) (xy 78.150027 -346.252063) (xy 78.350036 -346.242049) (xy 78.549485 -346.224041)
			(xy 78.748054 -346.198067) (xy 78.945424 -346.16417) (xy 79.141281 -346.122403) (xy 79.335309 -346.072833)
			(xy 79.527199 -346.01554) (xy 79.716642 -345.950615) (xy 79.903337 -345.878163) (xy 80.086983 -345.798299)
			(xy 80.267287 -345.711152) (xy 80.44396 -345.61686) (xy 80.616718 -345.515575) (xy 80.785286 -345.40746)
			(xy 80.949394 -345.292687) (xy 81.108778 -345.171439) (xy 81.263183 -345.043912) (xy 81.412362 -344.910309)
			(xy 81.556077 -344.770845) (xy 81.694096 -344.625743) (xy 81.8262 -344.475234) (xy 81.952176 -344.319561)
			(xy 82.071822 -344.158972) (xy 82.184948 -343.993724) (xy 82.291372 -343.824083) (xy 82.390923 -343.650319)
			(xy 82.483442 -343.472712) (xy 82.568781 -343.291545) (xy 82.646804 -343.107109) (xy 82.717384 -342.919699)
			(xy 82.78041 -342.729616) (xy 82.835781 -342.537162) (xy 82.883407 -342.342648) (xy 82.923212 -342.146383)
			(xy 82.955133 -341.948684) (xy 82.979119 -341.749865) (xy 82.995131 -341.550246) (xy 83.003143 -341.350146)
		)
		(stroke
			(width 0)
			(type solid)
		)
		(fill yes)
		(layer "B.Cu")
		(net "GND")
	)
	(gr_poly
		(pts
			(xy 83.003644 -210.09991) (xy 83.003143 -209.99978) (xy 82.995131 -209.79968) (xy 82.979119 -209.600061)
			(xy 82.955133 -209.401242) (xy 82.923212 -209.203543) (xy 82.883407 -209.007278) (xy 82.835781 -208.812764)
			(xy 82.78041 -208.62031) (xy 82.717384 -208.430227) (xy 82.646804 -208.242817) (xy 82.568781 -208.058381)
			(xy 82.483442 -207.877214) (xy 82.390923 -207.699607) (xy 82.291372 -207.525843) (xy 82.184948 -207.356202)
			(xy 82.071822 -207.190954) (xy 81.952176 -207.030365) (xy 81.8262 -206.874692) (xy 81.694096 -206.724183)
			(xy 81.556077 -206.579081) (xy 81.412362 -206.439617) (xy 81.263183 -206.306014) (xy 81.108778 -206.178487)
			(xy 80.949394 -206.057239) (xy 80.785286 -205.942466) (xy 80.616718 -205.834351) (xy 80.44396 -205.733066)
			(xy 80.267287 -205.638774) (xy 80.086983 -205.551627) (xy 79.903337 -205.471763) (xy 79.716642 -205.399311)
			(xy 79.527199 -205.334386) (xy 79.335309 -205.277093) (xy 79.141281 -205.227523) (xy 78.945424 -205.185756)
			(xy 78.748054 -205.151859) (xy 78.549485 -205.125885) (xy 78.350036 -205.107877) (xy 78.150027 -205.097863)
			(xy 77.949776 -205.095859) (xy 77.749606 -205.101869) (xy 77.549837 -205.115883) (xy 77.350789 -205.137879)
			(xy 77.152779 -205.16782) (xy 76.956127 -205.20566) (xy 76.761145 -205.251338) (xy 76.568148 -205.30478)
			(xy 76.377443 -205.365901) (xy 76.189336 -205.434603) (xy 76.004129 -205.510776) (xy 75.822117 -205.594299)
			(xy 75.643593 -205.685036) (xy 75.468842 -205.782844) (xy 75.298145 -205.887565) (xy 75.131774 -205.999032)
			(xy 74.969996 -206.117066) (xy 74.81307 -206.241478) (xy 74.661247 -206.372069) (xy 74.514771 -206.50863)
			(xy 74.373876 -206.650942) (xy 74.238787 -206.798777) (xy 74.109722 -206.951899) (xy 73.986886 -207.110061)
			(xy 73.870476 -207.273012) (xy 73.76068 -207.44049) (xy 73.657672 -207.612227) (xy 73.561617 -207.787947)
			(xy 73.47267 -207.96737) (xy 73.390973 -208.150208) (xy 73.316657 -208.336169) (xy 73.24984 -208.524953)
			(xy 73.19063 -208.71626) (xy 73.139121 -208.909783) (xy 73.095397 -209.105211) (xy 73.059526 -209.302233)
			(xy 73.031567 -209.500532) (xy 73.011564 -209.69979) (xy 72.99955 -209.89969) (xy 72.995543 -210.09991)
			(xy 75.484741 -210.09991) (xy 75.488769 -209.957618) (xy 75.500841 -209.815782) (xy 75.520918 -209.674855)
			(xy 75.548936 -209.535291) (xy 75.584805 -209.397535) (xy 75.62841 -209.262029) (xy 75.679611 -209.129207)
			(xy 75.738245 -208.999494) (xy 75.804123 -208.873307) (xy 75.877035 -208.751048) (xy 75.956747 -208.633111)
			(xy 76.043004 -208.519872) (xy 76.135528 -208.411694) (xy 76.234025 -208.308924) (xy 76.338179 -208.211891)
			(xy 76.447655 -208.120907) (xy 76.562103 -208.036261) (xy 76.681157 -207.958226) (xy 76.804435 -207.887052)
			(xy 76.931542 -207.822965) (xy 77.062071 -207.766173) (xy 77.195605 -207.716856) (xy 77.331714 -207.675173)
			(xy 77.469964 -207.641257) (xy 77.609911 -207.615217) (xy 77.751107 -207.597136) (xy 77.8931 -207.587073)
			(xy 78.035435 -207.585058) (xy 78.177656 -207.5911) (xy 78.319307 -207.605178) (xy 78.459935 -207.627247)
			(xy 78.599089 -207.657237) (xy 78.736324 -207.695052) (xy 78.871199 -207.74057) (xy 79.003283 -207.793646)
			(xy 79.132153 -207.854109) (xy 79.257396 -207.921766) (xy 79.37861 -207.996401) (xy 79.495408 -208.077774)
			(xy 79.607415 -208.165624) (xy 79.714273 -208.259671) (xy 79.815638 -208.359612) (xy 79.911187 -208.465128)
			(xy 80.000614 -208.575881) (xy 80.083632 -208.691515) (xy 80.159974 -208.811662) (xy 80.229397 -208.935934)
			(xy 80.291678 -209.063936) (xy 80.346618 -209.195256) (xy 80.39404 -209.329473) (xy 80.433793 -209.466159)
			(xy 80.465749 -209.604875) (xy 80.489806 -209.745176) (xy 80.505887 -209.886614) (xy 80.51394 -210.028735)
			(xy 80.514444 -210.09991) (xy 80.51394 -210.171085) (xy 80.505887 -210.313206) (xy 80.489806 -210.454644)
			(xy 80.465749 -210.594945) (xy 80.433793 -210.733661) (xy 80.39404 -210.870347) (xy 80.346618 -211.004564)
			(xy 80.291678 -211.135884) (xy 80.229397 -211.263886) (xy 80.159974 -211.388158) (xy 80.083632 -211.508305)
			(xy 80.000614 -211.623939) (xy 79.911187 -211.734692) (xy 79.815638 -211.840208) (xy 79.714273 -211.940149)
			(xy 79.607415 -212.034196) (xy 79.495408 -212.122046) (xy 79.37861 -212.203419) (xy 79.257396 -212.278054)
			(xy 79.132153 -212.345711) (xy 79.003283 -212.406174) (xy 78.871199 -212.45925) (xy 78.736324 -212.504768)
			(xy 78.599089 -212.542583) (xy 78.459935 -212.572573) (xy 78.319307 -212.594642) (xy 78.177656 -212.60872)
			(xy 78.035435 -212.614762) (xy 77.8931 -212.612747) (xy 77.751107 -212.602684) (xy 77.609911 -212.584603)
			(xy 77.469964 -212.558563) (xy 77.331714 -212.524647) (xy 77.195605 -212.482964) (xy 77.062071 -212.433647)
			(xy 76.931542 -212.376855) (xy 76.804435 -212.312768) (xy 76.681157 -212.241594) (xy 76.562103 -212.163559)
			(xy 76.447655 -212.078913) (xy 76.338179 -211.987929) (xy 76.234025 -211.890896) (xy 76.135528 -211.788126)
			(xy 76.043004 -211.679948) (xy 75.956747 -211.566709) (xy 75.877035 -211.448772) (xy 75.804123 -211.326513)
			(xy 75.738245 -211.200326) (xy 75.679611 -211.070613) (xy 75.62841 -210.937791) (xy 75.584805 -210.802285)
			(xy 75.548936 -210.664529) (xy 75.520918 -210.524965) (xy 75.500841 -210.384038) (xy 75.488769 -210.242202)
			(xy 75.484741 -210.09991) (xy 72.995543 -210.09991) (xy 72.99955 -210.30013) (xy 73.011564 -210.50003)
			(xy 73.031567 -210.699288) (xy 73.059526 -210.897587) (xy 73.095397 -211.094609) (xy 73.139121 -211.290037)
			(xy 73.19063 -211.48356) (xy 73.24984 -211.674867) (xy 73.316657 -211.863651) (xy 73.390973 -212.049612)
			(xy 73.47267 -212.23245) (xy 73.561617 -212.411873) (xy 73.657672 -212.587593) (xy 73.76068 -212.75933)
			(xy 73.870476 -212.926808) (xy 73.986886 -213.089759) (xy 74.109722 -213.247921) (xy 74.238787 -213.401043)
			(xy 74.373876 -213.548878) (xy 74.514771 -213.69119) (xy 74.661247 -213.827751) (xy 74.81307 -213.958342)
			(xy 74.969996 -214.082754) (xy 75.131774 -214.200788) (xy 75.298145 -214.312255) (xy 75.468842 -214.416976)
			(xy 75.643593 -214.514784) (xy 75.822117 -214.605521) (xy 76.004129 -214.689044) (xy 76.189336 -214.765217)
			(xy 76.377443 -214.833919) (xy 76.568148 -214.89504) (xy 76.761145 -214.948482) (xy 76.956127 -214.99416)
			(xy 77.152779 -215.032) (xy 77.350789 -215.061941) (xy 77.549837 -215.083937) (xy 77.749606 -215.097951)
			(xy 77.949776 -215.103961) (xy 78.150027 -215.101957) (xy 78.350036 -215.091943) (xy 78.549485 -215.073935)
			(xy 78.748054 -215.047961) (xy 78.945424 -215.014064) (xy 79.141281 -214.972297) (xy 79.335309 -214.922727)
			(xy 79.527199 -214.865434) (xy 79.716642 -214.800509) (xy 79.903337 -214.728057) (xy 80.086983 -214.648193)
			(xy 80.267287 -214.561046) (xy 80.44396 -214.466754) (xy 80.616718 -214.365469) (xy 80.785286 -214.257354)
			(xy 80.949394 -214.142581) (xy 81.108778 -214.021333) (xy 81.263183 -213.893806) (xy 81.412362 -213.760203)
			(xy 81.556077 -213.620739) (xy 81.694096 -213.475637) (xy 81.8262 -213.325128) (xy 81.952176 -213.169455)
			(xy 82.071822 -213.008866) (xy 82.184948 -212.843618) (xy 82.291372 -212.673977) (xy 82.390923 -212.500213)
			(xy 82.483442 -212.322606) (xy 82.568781 -212.141439) (xy 82.646804 -211.957003) (xy 82.717384 -211.769593)
			(xy 82.78041 -211.57951) (xy 82.835781 -211.387056) (xy 82.883407 -211.192542) (xy 82.923212 -210.996277)
			(xy 82.955133 -210.798578) (xy 82.979119 -210.599759) (xy 82.995131 -210.40014) (xy 83.003143 -210.20004)
		)
		(stroke
			(width 0)
			(type solid)
		)
		(fill yes)
		(layer "B.Cu")
		(net "GND")
	)
	(gr_poly
		(pts
			(xy 83.003644 -121.19991) (xy 83.003143 -121.09978) (xy 82.995131 -120.89968) (xy 82.979119 -120.700061)
			(xy 82.955133 -120.501242) (xy 82.923212 -120.303543) (xy 82.883407 -120.107278) (xy 82.835781 -119.912764)
			(xy 82.78041 -119.72031) (xy 82.717384 -119.530227) (xy 82.646804 -119.342817) (xy 82.568781 -119.158381)
			(xy 82.483442 -118.977214) (xy 82.390923 -118.799607) (xy 82.291372 -118.625843) (xy 82.184948 -118.456202)
			(xy 82.071822 -118.290954) (xy 81.952176 -118.130365) (xy 81.8262 -117.974692) (xy 81.694096 -117.824183)
			(xy 81.556077 -117.679081) (xy 81.412362 -117.539617) (xy 81.263183 -117.406014) (xy 81.108778 -117.278487)
			(xy 80.949394 -117.157239) (xy 80.785286 -117.042466) (xy 80.616718 -116.934351) (xy 80.44396 -116.833066)
			(xy 80.267287 -116.738774) (xy 80.086983 -116.651627) (xy 79.903337 -116.571763) (xy 79.716642 -116.499311)
			(xy 79.527199 -116.434386) (xy 79.335309 -116.377093) (xy 79.141281 -116.327523) (xy 78.945424 -116.285756)
			(xy 78.748054 -116.251859) (xy 78.549485 -116.225885) (xy 78.350036 -116.207877) (xy 78.150027 -116.197863)
			(xy 77.949776 -116.195859) (xy 77.749606 -116.201869) (xy 77.549837 -116.215883) (xy 77.350789 -116.237879)
			(xy 77.152779 -116.26782) (xy 76.956127 -116.30566) (xy 76.761145 -116.351338) (xy 76.568148 -116.40478)
			(xy 76.377443 -116.465901) (xy 76.189336 -116.534603) (xy 76.004129 -116.610776) (xy 75.822117 -116.694299)
			(xy 75.643593 -116.785036) (xy 75.468842 -116.882844) (xy 75.298145 -116.987565) (xy 75.131774 -117.099032)
			(xy 74.969996 -117.217066) (xy 74.81307 -117.341478) (xy 74.661247 -117.472069) (xy 74.514771 -117.60863)
			(xy 74.373876 -117.750942) (xy 74.238787 -117.898777) (xy 74.109722 -118.051899) (xy 73.986886 -118.210061)
			(xy 73.870476 -118.373012) (xy 73.76068 -118.54049) (xy 73.657672 -118.712227) (xy 73.561617 -118.887947)
			(xy 73.47267 -119.06737) (xy 73.390973 -119.250208) (xy 73.316657 -119.436169) (xy 73.24984 -119.624953)
			(xy 73.19063 -119.81626) (xy 73.139121 -120.009783) (xy 73.095397 -120.205211) (xy 73.059526 -120.402233)
			(xy 73.031567 -120.600532) (xy 73.011564 -120.79979) (xy 72.99955 -120.99969) (xy 72.995543 -121.19991)
			(xy 75.484741 -121.19991) (xy 75.488769 -121.057618) (xy 75.500841 -120.915782) (xy 75.520918 -120.774855)
			(xy 75.548936 -120.635291) (xy 75.584805 -120.497535) (xy 75.62841 -120.362029) (xy 75.679611 -120.229207)
			(xy 75.738245 -120.099494) (xy 75.804123 -119.973307) (xy 75.877035 -119.851048) (xy 75.956747 -119.733111)
			(xy 76.043004 -119.619872) (xy 76.135528 -119.511694) (xy 76.234025 -119.408924) (xy 76.338179 -119.311891)
			(xy 76.447655 -119.220907) (xy 76.562103 -119.136261) (xy 76.681157 -119.058226) (xy 76.804435 -118.987052)
			(xy 76.931542 -118.922965) (xy 77.062071 -118.866173) (xy 77.195605 -118.816856) (xy 77.331714 -118.775173)
			(xy 77.469964 -118.741257) (xy 77.609911 -118.715217) (xy 77.751107 -118.697136) (xy 77.8931 -118.687073)
			(xy 78.035435 -118.685058) (xy 78.177656 -118.6911) (xy 78.319307 -118.705178) (xy 78.459935 -118.727247)
			(xy 78.599089 -118.757237) (xy 78.736324 -118.795052) (xy 78.871199 -118.84057) (xy 79.003283 -118.893646)
			(xy 79.132153 -118.954109) (xy 79.257396 -119.021766) (xy 79.37861 -119.096401) (xy 79.495408 -119.177774)
			(xy 79.607415 -119.265624) (xy 79.714273 -119.359671) (xy 79.815638 -119.459612) (xy 79.911187 -119.565128)
			(xy 80.000614 -119.675881) (xy 80.083632 -119.791515) (xy 80.159974 -119.911662) (xy 80.229397 -120.035934)
			(xy 80.291678 -120.163936) (xy 80.346618 -120.295256) (xy 80.39404 -120.429473) (xy 80.433793 -120.566159)
			(xy 80.465749 -120.704875) (xy 80.489806 -120.845176) (xy 80.505887 -120.986614) (xy 80.51394 -121.128735)
			(xy 80.514444 -121.19991) (xy 80.51394 -121.271085) (xy 80.505887 -121.413206) (xy 80.489806 -121.554644)
			(xy 80.465749 -121.694945) (xy 80.433793 -121.833661) (xy 80.39404 -121.970347) (xy 80.346618 -122.104564)
			(xy 80.291678 -122.235884) (xy 80.229397 -122.363886) (xy 80.159974 -122.488158) (xy 80.083632 -122.608305)
			(xy 80.000614 -122.723939) (xy 79.911187 -122.834692) (xy 79.815638 -122.940208) (xy 79.714273 -123.040149)
			(xy 79.607415 -123.134196) (xy 79.495408 -123.222046) (xy 79.37861 -123.303419) (xy 79.257396 -123.378054)
			(xy 79.132153 -123.445711) (xy 79.003283 -123.506174) (xy 78.871199 -123.55925) (xy 78.736324 -123.604768)
			(xy 78.599089 -123.642583) (xy 78.459935 -123.672573) (xy 78.319307 -123.694642) (xy 78.177656 -123.70872)
			(xy 78.035435 -123.714762) (xy 77.8931 -123.712747) (xy 77.751107 -123.702684) (xy 77.609911 -123.684603)
			(xy 77.469964 -123.658563) (xy 77.331714 -123.624647) (xy 77.195605 -123.582964) (xy 77.062071 -123.533647)
			(xy 76.931542 -123.476855) (xy 76.804435 -123.412768) (xy 76.681157 -123.341594) (xy 76.562103 -123.263559)
			(xy 76.447655 -123.178913) (xy 76.338179 -123.087929) (xy 76.234025 -122.990896) (xy 76.135528 -122.888126)
			(xy 76.043004 -122.779948) (xy 75.956747 -122.666709) (xy 75.877035 -122.548772) (xy 75.804123 -122.426513)
			(xy 75.738245 -122.300326) (xy 75.679611 -122.170613) (xy 75.62841 -122.037791) (xy 75.584805 -121.902285)
			(xy 75.548936 -121.764529) (xy 75.520918 -121.624965) (xy 75.500841 -121.484038) (xy 75.488769 -121.342202)
			(xy 75.484741 -121.19991) (xy 72.995543 -121.19991) (xy 72.99955 -121.40013) (xy 73.011564 -121.60003)
			(xy 73.031567 -121.799288) (xy 73.059526 -121.997587) (xy 73.095397 -122.194609) (xy 73.139121 -122.390037)
			(xy 73.19063 -122.58356) (xy 73.24984 -122.774867) (xy 73.316657 -122.963651) (xy 73.390973 -123.149612)
			(xy 73.47267 -123.33245) (xy 73.561617 -123.511873) (xy 73.657672 -123.687593) (xy 73.76068 -123.85933)
			(xy 73.870476 -124.026808) (xy 73.986886 -124.189759) (xy 74.109722 -124.347921) (xy 74.238787 -124.501043)
			(xy 74.373876 -124.648878) (xy 74.514771 -124.79119) (xy 74.661247 -124.927751) (xy 74.81307 -125.058342)
			(xy 74.969996 -125.182754) (xy 75.131774 -125.300788) (xy 75.298145 -125.412255) (xy 75.468842 -125.516976)
			(xy 75.643593 -125.614784) (xy 75.822117 -125.705521) (xy 76.004129 -125.789044) (xy 76.189336 -125.865217)
			(xy 76.377443 -125.933919) (xy 76.568148 -125.99504) (xy 76.761145 -126.048482) (xy 76.956127 -126.09416)
			(xy 77.152779 -126.132) (xy 77.350789 -126.161941) (xy 77.549837 -126.183937) (xy 77.749606 -126.197951)
			(xy 77.949776 -126.203961) (xy 78.150027 -126.201957) (xy 78.350036 -126.191943) (xy 78.549485 -126.173935)
			(xy 78.748054 -126.147961) (xy 78.945424 -126.114064) (xy 79.141281 -126.072297) (xy 79.335309 -126.022727)
			(xy 79.527199 -125.965434) (xy 79.716642 -125.900509) (xy 79.903337 -125.828057) (xy 80.086983 -125.748193)
			(xy 80.267287 -125.661046) (xy 80.44396 -125.566754) (xy 80.616718 -125.465469) (xy 80.785286 -125.357354)
			(xy 80.949394 -125.242581) (xy 81.108778 -125.121333) (xy 81.263183 -124.993806) (xy 81.412362 -124.860203)
			(xy 81.556077 -124.720739) (xy 81.694096 -124.575637) (xy 81.8262 -124.425128) (xy 81.952176 -124.269455)
			(xy 82.071822 -124.108866) (xy 82.184948 -123.943618) (xy 82.291372 -123.773977) (xy 82.390923 -123.600213)
			(xy 82.483442 -123.422606) (xy 82.568781 -123.241439) (xy 82.646804 -123.057003) (xy 82.717384 -122.869593)
			(xy 82.78041 -122.67951) (xy 82.835781 -122.487056) (xy 82.883407 -122.292542) (xy 82.923212 -122.096277)
			(xy 82.955133 -121.898578) (xy 82.979119 -121.699759) (xy 82.995131 -121.50014) (xy 83.003143 -121.30004)
		)
		(stroke
			(width 0)
			(type solid)
		)
		(fill yes)
		(layer "B.Cu")
		(net "GND")
	)
	(gr_poly
		(pts
			(xy 83.003644 -32.29991) (xy 83.003143 -32.19978) (xy 82.995131 -31.99968) (xy 82.979119 -31.800061)
			(xy 82.955133 -31.601242) (xy 82.923212 -31.403543) (xy 82.883407 -31.207278) (xy 82.835781 -31.012764)
			(xy 82.78041 -30.82031) (xy 82.717384 -30.630227) (xy 82.646804 -30.442817) (xy 82.568781 -30.258381)
			(xy 82.483442 -30.077214) (xy 82.390923 -29.899607) (xy 82.291372 -29.725843) (xy 82.184948 -29.556202)
			(xy 82.071822 -29.390954) (xy 81.952176 -29.230365) (xy 81.8262 -29.074692) (xy 81.694096 -28.924183)
			(xy 81.556077 -28.779081) (xy 81.412362 -28.639617) (xy 81.263183 -28.506014) (xy 81.108778 -28.378487)
			(xy 80.949394 -28.257239) (xy 80.785286 -28.142466) (xy 80.616718 -28.034351) (xy 80.44396 -27.933066)
			(xy 80.267287 -27.838774) (xy 80.086983 -27.751627) (xy 79.903337 -27.671763) (xy 79.716642 -27.599311)
			(xy 79.527199 -27.534386) (xy 79.335309 -27.477093) (xy 79.141281 -27.427523) (xy 78.945424 -27.385756)
			(xy 78.748054 -27.351859) (xy 78.549485 -27.325885) (xy 78.350036 -27.307877) (xy 78.150027 -27.297863)
			(xy 77.949776 -27.295859) (xy 77.749606 -27.301869) (xy 77.549837 -27.315883) (xy 77.350789 -27.337879)
			(xy 77.152779 -27.36782) (xy 76.956127 -27.40566) (xy 76.761145 -27.451338) (xy 76.568148 -27.50478)
			(xy 76.377443 -27.565901) (xy 76.189336 -27.634603) (xy 76.004129 -27.710776) (xy 75.822117 -27.794299)
			(xy 75.643593 -27.885036) (xy 75.468842 -27.982844) (xy 75.298145 -28.087565) (xy 75.131774 -28.199032)
			(xy 74.969996 -28.317066) (xy 74.81307 -28.441478) (xy 74.661247 -28.572069) (xy 74.514771 -28.70863)
			(xy 74.373876 -28.850942) (xy 74.238787 -28.998777) (xy 74.109722 -29.151899) (xy 73.986886 -29.310061)
			(xy 73.870476 -29.473012) (xy 73.76068 -29.64049) (xy 73.657672 -29.812227) (xy 73.561617 -29.987947)
			(xy 73.47267 -30.16737) (xy 73.390973 -30.350208) (xy 73.316657 -30.536169) (xy 73.24984 -30.724953)
			(xy 73.19063 -30.91626) (xy 73.139121 -31.109783) (xy 73.095397 -31.305211) (xy 73.059526 -31.502233)
			(xy 73.031567 -31.700532) (xy 73.011564 -31.89979) (xy 72.99955 -32.09969) (xy 72.995543 -32.29991)
			(xy 75.484741 -32.29991) (xy 75.488769 -32.157618) (xy 75.500841 -32.015782) (xy 75.520918 -31.874855)
			(xy 75.548936 -31.735291) (xy 75.584805 -31.597535) (xy 75.62841 -31.462029) (xy 75.679611 -31.329207)
			(xy 75.738245 -31.199494) (xy 75.804123 -31.073307) (xy 75.877035 -30.951048) (xy 75.956747 -30.833111)
			(xy 76.043004 -30.719872) (xy 76.135528 -30.611694) (xy 76.234025 -30.508924) (xy 76.338179 -30.411891)
			(xy 76.447655 -30.320907) (xy 76.562103 -30.236261) (xy 76.681157 -30.158226) (xy 76.804435 -30.087052)
			(xy 76.931542 -30.022965) (xy 77.062071 -29.966173) (xy 77.195605 -29.916856) (xy 77.331714 -29.875173)
			(xy 77.469964 -29.841257) (xy 77.609911 -29.815217) (xy 77.751107 -29.797136) (xy 77.8931 -29.787073)
			(xy 78.035435 -29.785058) (xy 78.177656 -29.7911) (xy 78.319307 -29.805178) (xy 78.459935 -29.827247)
			(xy 78.599089 -29.857237) (xy 78.736324 -29.895052) (xy 78.871199 -29.94057) (xy 79.003283 -29.993646)
			(xy 79.132153 -30.054109) (xy 79.257396 -30.121766) (xy 79.37861 -30.196401) (xy 79.495408 -30.277774)
			(xy 79.607415 -30.365624) (xy 79.714273 -30.459671) (xy 79.815638 -30.559612) (xy 79.911187 -30.665128)
			(xy 80.000614 -30.775881) (xy 80.083632 -30.891515) (xy 80.159974 -31.011662) (xy 80.229397 -31.135934)
			(xy 80.291678 -31.263936) (xy 80.346618 -31.395256) (xy 80.39404 -31.529473) (xy 80.433793 -31.666159)
			(xy 80.465749 -31.804875) (xy 80.489806 -31.945176) (xy 80.505887 -32.086614) (xy 80.51394 -32.228735)
			(xy 80.514444 -32.29991) (xy 80.51394 -32.371085) (xy 80.505887 -32.513206) (xy 80.489806 -32.654644)
			(xy 80.465749 -32.794945) (xy 80.433793 -32.933661) (xy 80.39404 -33.070347) (xy 80.346618 -33.204564)
			(xy 80.291678 -33.335884) (xy 80.229397 -33.463886) (xy 80.159974 -33.588158) (xy 80.083632 -33.708305)
			(xy 80.000614 -33.823939) (xy 79.911187 -33.934692) (xy 79.815638 -34.040208) (xy 79.714273 -34.140149)
			(xy 79.607415 -34.234196) (xy 79.495408 -34.322046) (xy 79.37861 -34.403419) (xy 79.257396 -34.478054)
			(xy 79.132153 -34.545711) (xy 79.003283 -34.606174) (xy 78.871199 -34.65925) (xy 78.736324 -34.704768)
			(xy 78.599089 -34.742583) (xy 78.459935 -34.772573) (xy 78.319307 -34.794642) (xy 78.177656 -34.80872)
			(xy 78.035435 -34.814762) (xy 77.8931 -34.812747) (xy 77.751107 -34.802684) (xy 77.609911 -34.784603)
			(xy 77.469964 -34.758563) (xy 77.331714 -34.724647) (xy 77.195605 -34.682964) (xy 77.062071 -34.633647)
			(xy 76.931542 -34.576855) (xy 76.804435 -34.512768) (xy 76.681157 -34.441594) (xy 76.562103 -34.363559)
			(xy 76.447655 -34.278913) (xy 76.338179 -34.187929) (xy 76.234025 -34.090896) (xy 76.135528 -33.988126)
			(xy 76.043004 -33.879948) (xy 75.956747 -33.766709) (xy 75.877035 -33.648772) (xy 75.804123 -33.526513)
			(xy 75.738245 -33.400326) (xy 75.679611 -33.270613) (xy 75.62841 -33.137791) (xy 75.584805 -33.002285)
			(xy 75.548936 -32.864529) (xy 75.520918 -32.724965) (xy 75.500841 -32.584038) (xy 75.488769 -32.442202)
			(xy 75.484741 -32.29991) (xy 72.995543 -32.29991) (xy 72.99955 -32.50013) (xy 73.011564 -32.70003)
			(xy 73.031567 -32.899288) (xy 73.059526 -33.097587) (xy 73.095397 -33.294609) (xy 73.139121 -33.490037)
			(xy 73.19063 -33.68356) (xy 73.24984 -33.874867) (xy 73.316657 -34.063651) (xy 73.390973 -34.249612)
			(xy 73.47267 -34.43245) (xy 73.561617 -34.611873) (xy 73.657672 -34.787593) (xy 73.76068 -34.95933)
			(xy 73.870476 -35.126808) (xy 73.986886 -35.289759) (xy 74.109722 -35.447921) (xy 74.238787 -35.601043)
			(xy 74.373876 -35.748878) (xy 74.514771 -35.89119) (xy 74.661247 -36.027751) (xy 74.81307 -36.158342)
			(xy 74.969996 -36.282754) (xy 75.131774 -36.400788) (xy 75.298145 -36.512255) (xy 75.468842 -36.616976)
			(xy 75.643593 -36.714784) (xy 75.822117 -36.805521) (xy 76.004129 -36.889044) (xy 76.189336 -36.965217)
			(xy 76.377443 -37.033919) (xy 76.568148 -37.09504) (xy 76.761145 -37.148482) (xy 76.956127 -37.19416)
			(xy 77.152779 -37.232) (xy 77.350789 -37.261941) (xy 77.549837 -37.283937) (xy 77.749606 -37.297951)
			(xy 77.949776 -37.303961) (xy 78.150027 -37.301957) (xy 78.350036 -37.291943) (xy 78.549485 -37.273935)
			(xy 78.748054 -37.247961) (xy 78.945424 -37.214064) (xy 79.141281 -37.172297) (xy 79.335309 -37.122727)
			(xy 79.527199 -37.065434) (xy 79.716642 -37.000509) (xy 79.903337 -36.928057) (xy 80.086983 -36.848193)
			(xy 80.267287 -36.761046) (xy 80.44396 -36.666754) (xy 80.616718 -36.565469) (xy 80.785286 -36.457354)
			(xy 80.949394 -36.342581) (xy 81.108778 -36.221333) (xy 81.263183 -36.093806) (xy 81.412362 -35.960203)
			(xy 81.556077 -35.820739) (xy 81.694096 -35.675637) (xy 81.8262 -35.525128) (xy 81.952176 -35.369455)
			(xy 82.071822 -35.208866) (xy 82.184948 -35.043618) (xy 82.291372 -34.873977) (xy 82.390923 -34.700213)
			(xy 82.483442 -34.522606) (xy 82.568781 -34.341439) (xy 82.646804 -34.157003) (xy 82.717384 -33.969593)
			(xy 82.78041 -33.77951) (xy 82.835781 -33.587056) (xy 82.883407 -33.392542) (xy 82.923212 -33.196277)
			(xy 82.955133 -32.998578) (xy 82.979119 -32.799759) (xy 82.995131 -32.60014) (xy 83.003143 -32.40004)
		)
		(stroke
			(width 0)
			(type solid)
		)
		(fill yes)
		(layer "B.Cu")
		(net "GND")
	)
	(gr_poly
		(pts
			(xy 83.003898 -519.049762) (xy 83.003397 -518.949632) (xy 82.995385 -518.749532) (xy 82.979373 -518.549913)
			(xy 82.955387 -518.351094) (xy 82.923466 -518.153395) (xy 82.883661 -517.95713) (xy 82.836035 -517.762616)
			(xy 82.780664 -517.570162) (xy 82.717638 -517.380079) (xy 82.647058 -517.192669) (xy 82.569035 -517.008233)
			(xy 82.483696 -516.827066) (xy 82.391177 -516.649459) (xy 82.291626 -516.475695) (xy 82.185202 -516.306054)
			(xy 82.072076 -516.140806) (xy 81.95243 -515.980217) (xy 81.826454 -515.824544) (xy 81.69435 -515.674035)
			(xy 81.556331 -515.528933) (xy 81.412616 -515.389469) (xy 81.263437 -515.255866) (xy 81.109032 -515.128339)
			(xy 80.949648 -515.007091) (xy 80.78554 -514.892318) (xy 80.616972 -514.784203) (xy 80.444214 -514.682918)
			(xy 80.267541 -514.588626) (xy 80.087237 -514.501479) (xy 79.903591 -514.421615) (xy 79.716896 -514.349163)
			(xy 79.527453 -514.284238) (xy 79.335563 -514.226945) (xy 79.141535 -514.177375) (xy 78.945678 -514.135608)
			(xy 78.748308 -514.101711) (xy 78.549739 -514.075737) (xy 78.35029 -514.057729) (xy 78.150281 -514.047715)
			(xy 77.95003 -514.045711) (xy 77.74986 -514.051721) (xy 77.550091 -514.065735) (xy 77.351043 -514.087731)
			(xy 77.153033 -514.117672) (xy 76.956381 -514.155512) (xy 76.761399 -514.20119) (xy 76.568402 -514.254632)
			(xy 76.377697 -514.315753) (xy 76.18959 -514.384455) (xy 76.004383 -514.460628) (xy 75.822371 -514.544151)
			(xy 75.643847 -514.634888) (xy 75.469096 -514.732696) (xy 75.298399 -514.837417) (xy 75.132028 -514.948884)
			(xy 74.97025 -515.066918) (xy 74.813324 -515.19133) (xy 74.661501 -515.321921) (xy 74.515025 -515.458482)
			(xy 74.37413 -515.600794) (xy 74.239041 -515.748629) (xy 74.109976 -515.901751) (xy 73.98714 -516.059913)
			(xy 73.87073 -516.222864) (xy 73.760934 -516.390342) (xy 73.657926 -516.562079) (xy 73.561871 -516.737799)
			(xy 73.472924 -516.917222) (xy 73.391227 -517.10006) (xy 73.316911 -517.286021) (xy 73.250094 -517.474805)
			(xy 73.190884 -517.666112) (xy 73.139375 -517.859635) (xy 73.095651 -518.055063) (xy 73.05978 -518.252085)
			(xy 73.031821 -518.450384) (xy 73.011818 -518.649642) (xy 72.999804 -518.849542) (xy 72.995797 -519.049762)
			(xy 75.484995 -519.049762) (xy 75.489023 -518.90747) (xy 75.501095 -518.765634) (xy 75.521172 -518.624707)
			(xy 75.54919 -518.485143) (xy 75.585059 -518.347387) (xy 75.628664 -518.211881) (xy 75.679865 -518.079059)
			(xy 75.738499 -517.949346) (xy 75.804377 -517.823159) (xy 75.877289 -517.7009) (xy 75.957001 -517.582963)
			(xy 76.043258 -517.469724) (xy 76.135782 -517.361546) (xy 76.234279 -517.258776) (xy 76.338433 -517.161743)
			(xy 76.447909 -517.070759) (xy 76.562357 -516.986113) (xy 76.681411 -516.908078) (xy 76.804689 -516.836904)
			(xy 76.931796 -516.772817) (xy 77.062325 -516.716025) (xy 77.195859 -516.666708) (xy 77.331968 -516.625025)
			(xy 77.470218 -516.591109) (xy 77.610165 -516.565069) (xy 77.751361 -516.546988) (xy 77.893354 -516.536925)
			(xy 78.035689 -516.53491) (xy 78.17791 -516.540952) (xy 78.319561 -516.55503) (xy 78.460189 -516.577099)
			(xy 78.599343 -516.607089) (xy 78.736578 -516.644904) (xy 78.871453 -516.690422) (xy 79.003537 -516.743498)
			(xy 79.132407 -516.803961) (xy 79.25765 -516.871618) (xy 79.378864 -516.946253) (xy 79.495662 -517.027626)
			(xy 79.607669 -517.115476) (xy 79.714527 -517.209523) (xy 79.815892 -517.309464) (xy 79.911441 -517.41498)
			(xy 80.000868 -517.525733) (xy 80.083886 -517.641367) (xy 80.160228 -517.761514) (xy 80.229651 -517.885786)
			(xy 80.291932 -518.013788) (xy 80.346872 -518.145108) (xy 80.394294 -518.279325) (xy 80.434047 -518.416011)
			(xy 80.466003 -518.554727) (xy 80.49006 -518.695028) (xy 80.506141 -518.836466) (xy 80.514194 -518.978587)
			(xy 80.514698 -519.049762) (xy 80.514194 -519.120937) (xy 80.506141 -519.263058) (xy 80.49006 -519.404496)
			(xy 80.466003 -519.544797) (xy 80.434047 -519.683513) (xy 80.394294 -519.820199) (xy 80.346872 -519.954416)
			(xy 80.291932 -520.085736) (xy 80.229651 -520.213738) (xy 80.160228 -520.33801) (xy 80.083886 -520.458157)
			(xy 80.000868 -520.573791) (xy 79.911441 -520.684544) (xy 79.815892 -520.79006) (xy 79.714527 -520.890001)
			(xy 79.607669 -520.984048) (xy 79.495662 -521.071898) (xy 79.378864 -521.153271) (xy 79.25765 -521.227906)
			(xy 79.132407 -521.295563) (xy 79.003537 -521.356026) (xy 78.871453 -521.409102) (xy 78.736578 -521.45462)
			(xy 78.599343 -521.492435) (xy 78.460189 -521.522425) (xy 78.319561 -521.544494) (xy 78.17791 -521.558572)
			(xy 78.035689 -521.564614) (xy 77.893354 -521.562599) (xy 77.751361 -521.552536) (xy 77.610165 -521.534455)
			(xy 77.470218 -521.508415) (xy 77.331968 -521.474499) (xy 77.195859 -521.432816) (xy 77.062325 -521.383499)
			(xy 76.931796 -521.326707) (xy 76.804689 -521.26262) (xy 76.681411 -521.191446) (xy 76.562357 -521.113411)
			(xy 76.447909 -521.028765) (xy 76.338433 -520.937781) (xy 76.234279 -520.840748) (xy 76.135782 -520.737978)
			(xy 76.043258 -520.6298) (xy 75.957001 -520.516561) (xy 75.877289 -520.398624) (xy 75.804377 -520.276365)
			(xy 75.738499 -520.150178) (xy 75.679865 -520.020465) (xy 75.628664 -519.887643) (xy 75.585059 -519.752137)
			(xy 75.54919 -519.614381) (xy 75.521172 -519.474817) (xy 75.501095 -519.33389) (xy 75.489023 -519.192054)
			(xy 75.484995 -519.049762) (xy 72.995797 -519.049762) (xy 72.999804 -519.249982) (xy 73.011818 -519.449882)
			(xy 73.031821 -519.64914) (xy 73.05978 -519.847439) (xy 73.095651 -520.044461) (xy 73.139375 -520.239889)
			(xy 73.190884 -520.433412) (xy 73.250094 -520.624719) (xy 73.316911 -520.813503) (xy 73.391227 -520.999464)
			(xy 73.472924 -521.182302) (xy 73.561871 -521.361725) (xy 73.657926 -521.537445) (xy 73.760934 -521.709182)
			(xy 73.87073 -521.87666) (xy 73.98714 -522.039611) (xy 74.109976 -522.197773) (xy 74.239041 -522.350895)
			(xy 74.37413 -522.49873) (xy 74.515025 -522.641042) (xy 74.661501 -522.777603) (xy 74.813324 -522.908194)
			(xy 74.97025 -523.032606) (xy 75.132028 -523.15064) (xy 75.298399 -523.262107) (xy 75.469096 -523.366828)
			(xy 75.643847 -523.464636) (xy 75.822371 -523.555373) (xy 76.004383 -523.638896) (xy 76.18959 -523.715069)
			(xy 76.377697 -523.783771) (xy 76.568402 -523.844892) (xy 76.761399 -523.898334) (xy 76.956381 -523.944012)
			(xy 77.153033 -523.981852) (xy 77.351043 -524.011793) (xy 77.550091 -524.033789) (xy 77.74986 -524.047803)
			(xy 77.95003 -524.053813) (xy 78.150281 -524.051809) (xy 78.35029 -524.041795) (xy 78.549739 -524.023787)
			(xy 78.748308 -523.997813) (xy 78.945678 -523.963916) (xy 79.141535 -523.922149) (xy 79.335563 -523.872579)
			(xy 79.527453 -523.815286) (xy 79.716896 -523.750361) (xy 79.903591 -523.677909) (xy 80.087237 -523.598045)
			(xy 80.267541 -523.510898) (xy 80.444214 -523.416606) (xy 80.616972 -523.315321) (xy 80.78554 -523.207206)
			(xy 80.949648 -523.092433) (xy 81.109032 -522.971185) (xy 81.263437 -522.843658) (xy 81.412616 -522.710055)
			(xy 81.556331 -522.570591) (xy 81.69435 -522.425489) (xy 81.826454 -522.27498) (xy 81.95243 -522.119307)
			(xy 82.072076 -521.958718) (xy 82.185202 -521.79347) (xy 82.291626 -521.623829) (xy 82.391177 -521.450065)
			(xy 82.483696 -521.272458) (xy 82.569035 -521.091291) (xy 82.647058 -520.906855) (xy 82.717638 -520.719445)
			(xy 82.780664 -520.529362) (xy 82.836035 -520.336908) (xy 82.883661 -520.142394) (xy 82.923466 -519.946129)
			(xy 82.955387 -519.74843) (xy 82.979373 -519.549611) (xy 82.995385 -519.349992) (xy 83.003397 -519.149892)
		)
		(stroke
			(width 0)
			(type solid)
		)
		(fill yes)
		(layer "B.Cu")
		(net "GND")
	)
	(gr_poly
		(pts
			(xy 16.599916 -468.69604) (xy 16.499786 -468.696541) (xy 16.299686 -468.704553) (xy 16.100067 -468.720565)
			(xy 15.901248 -468.744551) (xy 15.703549 -468.776472) (xy 15.507284 -468.816277) (xy 15.31277 -468.863903)
			(xy 15.120316 -468.919274) (xy 14.930233 -468.9823) (xy 14.742823 -469.05288) (xy 14.558387 -469.130903)
			(xy 14.37722 -469.216242) (xy 14.199613 -469.308761) (xy 14.025849 -469.408312) (xy 13.856208 -469.514736)
			(xy 13.69096 -469.627862) (xy 13.530371 -469.747508) (xy 13.374698 -469.873484) (xy 13.224189 -470.005588)
			(xy 13.079087 -470.143607) (xy 12.939623 -470.287322) (xy 12.80602 -470.436501) (xy 12.678493 -470.590906)
			(xy 12.557245 -470.75029) (xy 12.442472 -470.914398) (xy 12.334357 -471.082966) (xy 12.233072 -471.255724)
			(xy 12.13878 -471.432397) (xy 12.051633 -471.612701) (xy 11.971769 -471.796347) (xy 11.899317 -471.983042)
			(xy 11.834392 -472.172485) (xy 11.777099 -472.364375) (xy 11.727529 -472.558403) (xy 11.685762 -472.75426)
			(xy 11.651865 -472.95163) (xy 11.625891 -473.150199) (xy 11.607883 -473.349648) (xy 11.597869 -473.549657)
			(xy 11.596722 -473.664249) (xy 14.085064 -473.664249) (xy 14.091106 -473.522028) (xy 14.105184 -473.380377)
			(xy 14.127253 -473.239749) (xy 14.157243 -473.100595) (xy 14.195058 -472.96336) (xy 14.240576 -472.828485)
			(xy 14.293652 -472.696401) (xy 14.354115 -472.567531) (xy 14.421772 -472.442288) (xy 14.496407 -472.321074)
			(xy 14.57778 -472.204276) (xy 14.66563 -472.092269) (xy 14.759677 -471.985411) (xy 14.859618 -471.884046)
			(xy 14.965134 -471.788497) (xy 15.075887 -471.69907) (xy 15.191521 -471.616052) (xy 15.311668 -471.53971)
			(xy 15.43594 -471.470287) (xy 15.563942 -471.408006) (xy 15.695262 -471.353066) (xy 15.829479 -471.305644)
			(xy 15.966165 -471.265891) (xy 16.104881 -471.233935) (xy 16.245182 -471.209878) (xy 16.38662 -471.193797)
			(xy 16.528741 -471.185744) (xy 16.599916 -471.18524) (xy 16.671091 -471.185744) (xy 16.813212 -471.193797)
			(xy 16.95465 -471.209878) (xy 17.094951 -471.233935) (xy 17.233667 -471.265891) (xy 17.370353 -471.305644)
			(xy 17.50457 -471.353066) (xy 17.63589 -471.408006) (xy 17.763892 -471.470287) (xy 17.888164 -471.53971)
			(xy 18.008311 -471.616052) (xy 18.123945 -471.69907) (xy 18.234698 -471.788497) (xy 18.340214 -471.884046)
			(xy 18.440155 -471.985411) (xy 18.534202 -472.092269) (xy 18.622052 -472.204276) (xy 18.703425 -472.321074)
			(xy 18.77806 -472.442288) (xy 18.845717 -472.567531) (xy 18.90618 -472.696401) (xy 18.959256 -472.828485)
			(xy 19.004774 -472.96336) (xy 19.042589 -473.100595) (xy 19.072579 -473.239749) (xy 19.094648 -473.380377)
			(xy 19.108726 -473.522028) (xy 19.114768 -473.664249) (xy 19.112753 -473.806584) (xy 19.10269 -473.948577)
			(xy 19.084609 -474.089773) (xy 19.058569 -474.22972) (xy 19.024653 -474.36797) (xy 18.98297 -474.504079)
			(xy 18.933653 -474.637613) (xy 18.876861 -474.768142) (xy 18.812774 -474.895249) (xy 18.7416 -475.018527)
			(xy 18.663565 -475.137581) (xy 18.578919 -475.252029) (xy 18.487935 -475.361505) (xy 18.390902 -475.465659)
			(xy 18.288132 -475.564156) (xy 18.179954 -475.65668) (xy 18.066715 -475.742937) (xy 17.948778 -475.822649)
			(xy 17.826519 -475.895561) (xy 17.700332 -475.961439) (xy 17.570619 -476.020073) (xy 17.437797 -476.071274)
			(xy 17.302291 -476.114879) (xy 17.164535 -476.150748) (xy 17.024971 -476.178766) (xy 16.884044 -476.198843)
			(xy 16.742208 -476.210915) (xy 16.599916 -476.214944) (xy 16.457624 -476.210915) (xy 16.315788 -476.198843)
			(xy 16.174861 -476.178766) (xy 16.035297 -476.150748) (xy 15.897541 -476.114879) (xy 15.762035 -476.071274)
			(xy 15.629213 -476.020073) (xy 15.4995 -475.961439) (xy 15.373313 -475.895561) (xy 15.251054 -475.822649)
			(xy 15.133117 -475.742937) (xy 15.019878 -475.65668) (xy 14.9117 -475.564156) (xy 14.80893 -475.465659)
			(xy 14.711897 -475.361505) (xy 14.620913 -475.252029) (xy 14.536267 -475.137581) (xy 14.458232 -475.018527)
			(xy 14.387058 -474.895249) (xy 14.322971 -474.768142) (xy 14.266179 -474.637613) (xy 14.216862 -474.504079)
			(xy 14.175179 -474.36797) (xy 14.141263 -474.22972) (xy 14.115223 -474.089773) (xy 14.097142 -473.948577)
			(xy 14.087079 -473.806584) (xy 14.085064 -473.664249) (xy 11.596722 -473.664249) (xy 11.595865 -473.749908)
			(xy 11.601875 -473.950078) (xy 11.615889 -474.149847) (xy 11.637885 -474.348895) (xy 11.667826 -474.546905)
			(xy 11.705666 -474.743557) (xy 11.751344 -474.938539) (xy 11.804786 -475.131536) (xy 11.865907 -475.322241)
			(xy 11.934609 -475.510348) (xy 12.010782 -475.695555) (xy 12.094305 -475.877567) (xy 12.185042 -476.056091)
			(xy 12.28285 -476.230842) (xy 12.387571 -476.401539) (xy 12.499038 -476.56791) (xy 12.617072 -476.729688)
			(xy 12.741484 -476.886614) (xy 12.872075 -477.038437) (xy 13.008636 -477.184913) (xy 13.150948 -477.325808)
			(xy 13.298783 -477.460897) (xy 13.451905 -477.589962) (xy 13.610067 -477.712798) (xy 13.773018 -477.829208)
			(xy 13.940496 -477.939004) (xy 14.112233 -478.042012) (xy 14.287953 -478.138067) (xy 14.467376 -478.227014)
			(xy 14.650214 -478.308711) (xy 14.836175 -478.383027) (xy 15.024959 -478.449844) (xy 15.216266 -478.509054)
			(xy 15.409789 -478.560563) (xy 15.605217 -478.604287) (xy 15.802239 -478.640158) (xy 16.000538 -478.668117)
			(xy 16.199796 -478.68812) (xy 16.399696 -478.700134) (xy 16.599916 -478.704141) (xy 16.800136 -478.700134)
			(xy 17.000036 -478.68812) (xy 17.199294 -478.668117) (xy 17.397593 -478.640158) (xy 17.594615 -478.604287)
			(xy 17.790043 -478.560563) (xy 17.983566 -478.509054) (xy 18.174873 -478.449844) (xy 18.363657 -478.383027)
			(xy 18.549618 -478.308711) (xy 18.732456 -478.227014) (xy 18.911879 -478.138067) (xy 19.087599 -478.042012)
			(xy 19.259336 -477.939004) (xy 19.426814 -477.829208) (xy 19.589765 -477.712798) (xy 19.747927 -477.589962)
			(xy 19.901049 -477.460897) (xy 20.048884 -477.325808) (xy 20.191196 -477.184913) (xy 20.327757 -477.038437)
			(xy 20.458348 -476.886614) (xy 20.58276 -476.729688) (xy 20.700794 -476.56791) (xy 20.812261 -476.401539)
			(xy 20.916982 -476.230842) (xy 21.01479 -476.056091) (xy 21.105527 -475.877567) (xy 21.18905 -475.695555)
			(xy 21.265223 -475.510348) (xy 21.333925 -475.322241) (xy 21.395046 -475.131536) (xy 21.448488 -474.938539)
			(xy 21.494166 -474.743557) (xy 21.532006 -474.546905) (xy 21.561947 -474.348895) (xy 21.583943 -474.149847)
			(xy 21.597957 -473.950078) (xy 21.603967 -473.749908) (xy 21.601963 -473.549657) (xy 21.591949 -473.349648)
			(xy 21.573941 -473.150199) (xy 21.547967 -472.95163) (xy 21.51407 -472.75426) (xy 21.472303 -472.558403)
			(xy 21.422733 -472.364375) (xy 21.36544 -472.172485) (xy 21.300515 -471.983042) (xy 21.228063 -471.796347)
			(xy 21.148199 -471.612701) (xy 21.061052 -471.432397) (xy 20.96676 -471.255724) (xy 20.865475 -471.082966)
			(xy 20.75736 -470.914398) (xy 20.642587 -470.75029) (xy 20.521339 -470.590906) (xy 20.393812 -470.436501)
			(xy 20.260209 -470.287322) (xy 20.120745 -470.143607) (xy 19.975643 -470.005588) (xy 19.825134 -469.873484)
			(xy 19.669461 -469.747508) (xy 19.508872 -469.627862) (xy 19.343624 -469.514736) (xy 19.173983 -469.408312)
			(xy 19.000219 -469.308761) (xy 18.822612 -469.216242) (xy 18.641445 -469.130903) (xy 18.457009 -469.05288)
			(xy 18.269599 -468.9823) (xy 18.079516 -468.919274) (xy 17.887062 -468.863903) (xy 17.692548 -468.816277)
			(xy 17.496283 -468.776472) (xy 17.298584 -468.744551) (xy 17.099765 -468.720565) (xy 16.900146 -468.704553)
			(xy 16.700046 -468.696541)
		)
		(stroke
			(width 0)
			(type solid)
		)
		(fill yes)
		(layer "B.Cu")
		(net "GND")
	)
	(gr_poly
		(pts
			(xy 16.599916 -379.79604) (xy 16.499786 -379.796541) (xy 16.299686 -379.804553) (xy 16.100067 -379.820565)
			(xy 15.901248 -379.844551) (xy 15.703549 -379.876472) (xy 15.507284 -379.916277) (xy 15.31277 -379.963903)
			(xy 15.120316 -380.019274) (xy 14.930233 -380.0823) (xy 14.742823 -380.15288) (xy 14.558387 -380.230903)
			(xy 14.37722 -380.316242) (xy 14.199613 -380.408761) (xy 14.025849 -380.508312) (xy 13.856208 -380.614736)
			(xy 13.69096 -380.727862) (xy 13.530371 -380.847508) (xy 13.374698 -380.973484) (xy 13.224189 -381.105588)
			(xy 13.079087 -381.243607) (xy 12.939623 -381.387322) (xy 12.80602 -381.536501) (xy 12.678493 -381.690906)
			(xy 12.557245 -381.85029) (xy 12.442472 -382.014398) (xy 12.334357 -382.182966) (xy 12.233072 -382.355724)
			(xy 12.13878 -382.532397) (xy 12.051633 -382.712701) (xy 11.971769 -382.896347) (xy 11.899317 -383.083042)
			(xy 11.834392 -383.272485) (xy 11.777099 -383.464375) (xy 11.727529 -383.658403) (xy 11.685762 -383.85426)
			(xy 11.651865 -384.05163) (xy 11.625891 -384.250199) (xy 11.607883 -384.449648) (xy 11.597869 -384.649657)
			(xy 11.596722 -384.764249) (xy 14.085064 -384.764249) (xy 14.091106 -384.622028) (xy 14.105184 -384.480377)
			(xy 14.127253 -384.339749) (xy 14.157243 -384.200595) (xy 14.195058 -384.06336) (xy 14.240576 -383.928485)
			(xy 14.293652 -383.796401) (xy 14.354115 -383.667531) (xy 14.421772 -383.542288) (xy 14.496407 -383.421074)
			(xy 14.57778 -383.304276) (xy 14.66563 -383.192269) (xy 14.759677 -383.085411) (xy 14.859618 -382.984046)
			(xy 14.965134 -382.888497) (xy 15.075887 -382.79907) (xy 15.191521 -382.716052) (xy 15.311668 -382.63971)
			(xy 15.43594 -382.570287) (xy 15.563942 -382.508006) (xy 15.695262 -382.453066) (xy 15.829479 -382.405644)
			(xy 15.966165 -382.365891) (xy 16.104881 -382.333935) (xy 16.245182 -382.309878) (xy 16.38662 -382.293797)
			(xy 16.528741 -382.285744) (xy 16.599916 -382.28524) (xy 16.671091 -382.285744) (xy 16.813212 -382.293797)
			(xy 16.95465 -382.309878) (xy 17.094951 -382.333935) (xy 17.233667 -382.365891) (xy 17.370353 -382.405644)
			(xy 17.50457 -382.453066) (xy 17.63589 -382.508006) (xy 17.763892 -382.570287) (xy 17.888164 -382.63971)
			(xy 18.008311 -382.716052) (xy 18.123945 -382.79907) (xy 18.234698 -382.888497) (xy 18.340214 -382.984046)
			(xy 18.440155 -383.085411) (xy 18.534202 -383.192269) (xy 18.622052 -383.304276) (xy 18.703425 -383.421074)
			(xy 18.77806 -383.542288) (xy 18.845717 -383.667531) (xy 18.90618 -383.796401) (xy 18.959256 -383.928485)
			(xy 19.004774 -384.06336) (xy 19.042589 -384.200595) (xy 19.072579 -384.339749) (xy 19.094648 -384.480377)
			(xy 19.108726 -384.622028) (xy 19.114768 -384.764249) (xy 19.112753 -384.906584) (xy 19.10269 -385.048577)
			(xy 19.084609 -385.189773) (xy 19.058569 -385.32972) (xy 19.024653 -385.46797) (xy 18.98297 -385.604079)
			(xy 18.933653 -385.737613) (xy 18.876861 -385.868142) (xy 18.812774 -385.995249) (xy 18.7416 -386.118527)
			(xy 18.663565 -386.237581) (xy 18.578919 -386.352029) (xy 18.487935 -386.461505) (xy 18.390902 -386.565659)
			(xy 18.288132 -386.664156) (xy 18.179954 -386.75668) (xy 18.066715 -386.842937) (xy 17.948778 -386.922649)
			(xy 17.826519 -386.995561) (xy 17.700332 -387.061439) (xy 17.570619 -387.120073) (xy 17.437797 -387.171274)
			(xy 17.302291 -387.214879) (xy 17.164535 -387.250748) (xy 17.024971 -387.278766) (xy 16.884044 -387.298843)
			(xy 16.742208 -387.310915) (xy 16.599916 -387.314944) (xy 16.457624 -387.310915) (xy 16.315788 -387.298843)
			(xy 16.174861 -387.278766) (xy 16.035297 -387.250748) (xy 15.897541 -387.214879) (xy 15.762035 -387.171274)
			(xy 15.629213 -387.120073) (xy 15.4995 -387.061439) (xy 15.373313 -386.995561) (xy 15.251054 -386.922649)
			(xy 15.133117 -386.842937) (xy 15.019878 -386.75668) (xy 14.9117 -386.664156) (xy 14.80893 -386.565659)
			(xy 14.711897 -386.461505) (xy 14.620913 -386.352029) (xy 14.536267 -386.237581) (xy 14.458232 -386.118527)
			(xy 14.387058 -385.995249) (xy 14.322971 -385.868142) (xy 14.266179 -385.737613) (xy 14.216862 -385.604079)
			(xy 14.175179 -385.46797) (xy 14.141263 -385.32972) (xy 14.115223 -385.189773) (xy 14.097142 -385.048577)
			(xy 14.087079 -384.906584) (xy 14.085064 -384.764249) (xy 11.596722 -384.764249) (xy 11.595865 -384.849908)
			(xy 11.601875 -385.050078) (xy 11.615889 -385.249847) (xy 11.637885 -385.448895) (xy 11.667826 -385.646905)
			(xy 11.705666 -385.843557) (xy 11.751344 -386.038539) (xy 11.804786 -386.231536) (xy 11.865907 -386.422241)
			(xy 11.934609 -386.610348) (xy 12.010782 -386.795555) (xy 12.094305 -386.977567) (xy 12.185042 -387.156091)
			(xy 12.28285 -387.330842) (xy 12.387571 -387.501539) (xy 12.499038 -387.66791) (xy 12.617072 -387.829688)
			(xy 12.741484 -387.986614) (xy 12.872075 -388.138437) (xy 13.008636 -388.284913) (xy 13.150948 -388.425808)
			(xy 13.298783 -388.560897) (xy 13.451905 -388.689962) (xy 13.610067 -388.812798) (xy 13.773018 -388.929208)
			(xy 13.940496 -389.039004) (xy 14.112233 -389.142012) (xy 14.287953 -389.238067) (xy 14.467376 -389.327014)
			(xy 14.650214 -389.408711) (xy 14.836175 -389.483027) (xy 15.024959 -389.549844) (xy 15.216266 -389.609054)
			(xy 15.409789 -389.660563) (xy 15.605217 -389.704287) (xy 15.802239 -389.740158) (xy 16.000538 -389.768117)
			(xy 16.199796 -389.78812) (xy 16.399696 -389.800134) (xy 16.599916 -389.804141) (xy 16.800136 -389.800134)
			(xy 17.000036 -389.78812) (xy 17.199294 -389.768117) (xy 17.397593 -389.740158) (xy 17.594615 -389.704287)
			(xy 17.790043 -389.660563) (xy 17.983566 -389.609054) (xy 18.174873 -389.549844) (xy 18.363657 -389.483027)
			(xy 18.549618 -389.408711) (xy 18.732456 -389.327014) (xy 18.911879 -389.238067) (xy 19.087599 -389.142012)
			(xy 19.259336 -389.039004) (xy 19.426814 -388.929208) (xy 19.589765 -388.812798) (xy 19.747927 -388.689962)
			(xy 19.901049 -388.560897) (xy 20.048884 -388.425808) (xy 20.191196 -388.284913) (xy 20.327757 -388.138437)
			(xy 20.458348 -387.986614) (xy 20.58276 -387.829688) (xy 20.700794 -387.66791) (xy 20.812261 -387.501539)
			(xy 20.916982 -387.330842) (xy 21.01479 -387.156091) (xy 21.105527 -386.977567) (xy 21.18905 -386.795555)
			(xy 21.265223 -386.610348) (xy 21.333925 -386.422241) (xy 21.395046 -386.231536) (xy 21.448488 -386.038539)
			(xy 21.494166 -385.843557) (xy 21.532006 -385.646905) (xy 21.561947 -385.448895) (xy 21.583943 -385.249847)
			(xy 21.597957 -385.050078) (xy 21.603967 -384.849908) (xy 21.601963 -384.649657) (xy 21.591949 -384.449648)
			(xy 21.573941 -384.250199) (xy 21.547967 -384.05163) (xy 21.51407 -383.85426) (xy 21.472303 -383.658403)
			(xy 21.422733 -383.464375) (xy 21.36544 -383.272485) (xy 21.300515 -383.083042) (xy 21.228063 -382.896347)
			(xy 21.148199 -382.712701) (xy 21.061052 -382.532397) (xy 20.96676 -382.355724) (xy 20.865475 -382.182966)
			(xy 20.75736 -382.014398) (xy 20.642587 -381.85029) (xy 20.521339 -381.690906) (xy 20.393812 -381.536501)
			(xy 20.260209 -381.387322) (xy 20.120745 -381.243607) (xy 19.975643 -381.105588) (xy 19.825134 -380.973484)
			(xy 19.669461 -380.847508) (xy 19.508872 -380.727862) (xy 19.343624 -380.614736) (xy 19.173983 -380.508312)
			(xy 19.000219 -380.408761) (xy 18.822612 -380.316242) (xy 18.641445 -380.230903) (xy 18.457009 -380.15288)
			(xy 18.269599 -380.0823) (xy 18.079516 -380.019274) (xy 17.887062 -379.963903) (xy 17.692548 -379.916277)
			(xy 17.496283 -379.876472) (xy 17.298584 -379.844551) (xy 17.099765 -379.820565) (xy 16.900146 -379.804553)
			(xy 16.700046 -379.796541)
		)
		(stroke
			(width 0)
			(type solid)
		)
		(fill yes)
		(layer "B.Cu")
		(net "GND")
	)
	(gr_poly
		(pts
			(xy 16.599916 -290.89604) (xy 16.499786 -290.896541) (xy 16.299686 -290.904553) (xy 16.100067 -290.920565)
			(xy 15.901248 -290.944551) (xy 15.703549 -290.976472) (xy 15.507284 -291.016277) (xy 15.31277 -291.063903)
			(xy 15.120316 -291.119274) (xy 14.930233 -291.1823) (xy 14.742823 -291.25288) (xy 14.558387 -291.330903)
			(xy 14.37722 -291.416242) (xy 14.199613 -291.508761) (xy 14.025849 -291.608312) (xy 13.856208 -291.714736)
			(xy 13.69096 -291.827862) (xy 13.530371 -291.947508) (xy 13.374698 -292.073484) (xy 13.224189 -292.205588)
			(xy 13.079087 -292.343607) (xy 12.939623 -292.487322) (xy 12.80602 -292.636501) (xy 12.678493 -292.790906)
			(xy 12.557245 -292.95029) (xy 12.442472 -293.114398) (xy 12.334357 -293.282966) (xy 12.233072 -293.455724)
			(xy 12.13878 -293.632397) (xy 12.051633 -293.812701) (xy 11.971769 -293.996347) (xy 11.899317 -294.183042)
			(xy 11.834392 -294.372485) (xy 11.777099 -294.564375) (xy 11.727529 -294.758403) (xy 11.685762 -294.95426)
			(xy 11.651865 -295.15163) (xy 11.625891 -295.350199) (xy 11.607883 -295.549648) (xy 11.597869 -295.749657)
			(xy 11.596722 -295.864249) (xy 14.085064 -295.864249) (xy 14.091106 -295.722028) (xy 14.105184 -295.580377)
			(xy 14.127253 -295.439749) (xy 14.157243 -295.300595) (xy 14.195058 -295.16336) (xy 14.240576 -295.028485)
			(xy 14.293652 -294.896401) (xy 14.354115 -294.767531) (xy 14.421772 -294.642288) (xy 14.496407 -294.521074)
			(xy 14.57778 -294.404276) (xy 14.66563 -294.292269) (xy 14.759677 -294.185411) (xy 14.859618 -294.084046)
			(xy 14.965134 -293.988497) (xy 15.075887 -293.89907) (xy 15.191521 -293.816052) (xy 15.311668 -293.73971)
			(xy 15.43594 -293.670287) (xy 15.563942 -293.608006) (xy 15.695262 -293.553066) (xy 15.829479 -293.505644)
			(xy 15.966165 -293.465891) (xy 16.104881 -293.433935) (xy 16.245182 -293.409878) (xy 16.38662 -293.393797)
			(xy 16.528741 -293.385744) (xy 16.599916 -293.38524) (xy 16.671091 -293.385744) (xy 16.813212 -293.393797)
			(xy 16.95465 -293.409878) (xy 17.094951 -293.433935) (xy 17.233667 -293.465891) (xy 17.370353 -293.505644)
			(xy 17.50457 -293.553066) (xy 17.63589 -293.608006) (xy 17.763892 -293.670287) (xy 17.888164 -293.73971)
			(xy 18.008311 -293.816052) (xy 18.123945 -293.89907) (xy 18.234698 -293.988497) (xy 18.340214 -294.084046)
			(xy 18.440155 -294.185411) (xy 18.534202 -294.292269) (xy 18.622052 -294.404276) (xy 18.703425 -294.521074)
			(xy 18.77806 -294.642288) (xy 18.845717 -294.767531) (xy 18.90618 -294.896401) (xy 18.959256 -295.028485)
			(xy 19.004774 -295.16336) (xy 19.042589 -295.300595) (xy 19.072579 -295.439749) (xy 19.094648 -295.580377)
			(xy 19.108726 -295.722028) (xy 19.114768 -295.864249) (xy 19.112753 -296.006584) (xy 19.10269 -296.148577)
			(xy 19.084609 -296.289773) (xy 19.058569 -296.42972) (xy 19.024653 -296.56797) (xy 18.98297 -296.704079)
			(xy 18.933653 -296.837613) (xy 18.876861 -296.968142) (xy 18.812774 -297.095249) (xy 18.7416 -297.218527)
			(xy 18.663565 -297.337581) (xy 18.578919 -297.452029) (xy 18.487935 -297.561505) (xy 18.390902 -297.665659)
			(xy 18.288132 -297.764156) (xy 18.179954 -297.85668) (xy 18.066715 -297.942937) (xy 17.948778 -298.022649)
			(xy 17.826519 -298.095561) (xy 17.700332 -298.161439) (xy 17.570619 -298.220073) (xy 17.437797 -298.271274)
			(xy 17.302291 -298.314879) (xy 17.164535 -298.350748) (xy 17.024971 -298.378766) (xy 16.884044 -298.398843)
			(xy 16.742208 -298.410915) (xy 16.599916 -298.414944) (xy 16.457624 -298.410915) (xy 16.315788 -298.398843)
			(xy 16.174861 -298.378766) (xy 16.035297 -298.350748) (xy 15.897541 -298.314879) (xy 15.762035 -298.271274)
			(xy 15.629213 -298.220073) (xy 15.4995 -298.161439) (xy 15.373313 -298.095561) (xy 15.251054 -298.022649)
			(xy 15.133117 -297.942937) (xy 15.019878 -297.85668) (xy 14.9117 -297.764156) (xy 14.80893 -297.665659)
			(xy 14.711897 -297.561505) (xy 14.620913 -297.452029) (xy 14.536267 -297.337581) (xy 14.458232 -297.218527)
			(xy 14.387058 -297.095249) (xy 14.322971 -296.968142) (xy 14.266179 -296.837613) (xy 14.216862 -296.704079)
			(xy 14.175179 -296.56797) (xy 14.141263 -296.42972) (xy 14.115223 -296.289773) (xy 14.097142 -296.148577)
			(xy 14.087079 -296.006584) (xy 14.085064 -295.864249) (xy 11.596722 -295.864249) (xy 11.595865 -295.949908)
			(xy 11.601875 -296.150078) (xy 11.615889 -296.349847) (xy 11.637885 -296.548895) (xy 11.667826 -296.746905)
			(xy 11.705666 -296.943557) (xy 11.751344 -297.138539) (xy 11.804786 -297.331536) (xy 11.865907 -297.522241)
			(xy 11.934609 -297.710348) (xy 12.010782 -297.895555) (xy 12.094305 -298.077567) (xy 12.185042 -298.256091)
			(xy 12.28285 -298.430842) (xy 12.387571 -298.601539) (xy 12.499038 -298.76791) (xy 12.617072 -298.929688)
			(xy 12.741484 -299.086614) (xy 12.872075 -299.238437) (xy 13.008636 -299.384913) (xy 13.150948 -299.525808)
			(xy 13.298783 -299.660897) (xy 13.451905 -299.789962) (xy 13.610067 -299.912798) (xy 13.773018 -300.029208)
			(xy 13.940496 -300.139004) (xy 14.112233 -300.242012) (xy 14.287953 -300.338067) (xy 14.467376 -300.427014)
			(xy 14.650214 -300.508711) (xy 14.836175 -300.583027) (xy 15.024959 -300.649844) (xy 15.216266 -300.709054)
			(xy 15.409789 -300.760563) (xy 15.605217 -300.804287) (xy 15.802239 -300.840158) (xy 16.000538 -300.868117)
			(xy 16.199796 -300.88812) (xy 16.399696 -300.900134) (xy 16.599916 -300.904141) (xy 16.800136 -300.900134)
			(xy 17.000036 -300.88812) (xy 17.199294 -300.868117) (xy 17.397593 -300.840158) (xy 17.594615 -300.804287)
			(xy 17.790043 -300.760563) (xy 17.983566 -300.709054) (xy 18.174873 -300.649844) (xy 18.363657 -300.583027)
			(xy 18.549618 -300.508711) (xy 18.732456 -300.427014) (xy 18.911879 -300.338067) (xy 19.087599 -300.242012)
			(xy 19.259336 -300.139004) (xy 19.426814 -300.029208) (xy 19.589765 -299.912798) (xy 19.747927 -299.789962)
			(xy 19.901049 -299.660897) (xy 20.048884 -299.525808) (xy 20.191196 -299.384913) (xy 20.327757 -299.238437)
			(xy 20.458348 -299.086614) (xy 20.58276 -298.929688) (xy 20.700794 -298.76791) (xy 20.812261 -298.601539)
			(xy 20.916982 -298.430842) (xy 21.01479 -298.256091) (xy 21.105527 -298.077567) (xy 21.18905 -297.895555)
			(xy 21.265223 -297.710348) (xy 21.333925 -297.522241) (xy 21.395046 -297.331536) (xy 21.448488 -297.138539)
			(xy 21.494166 -296.943557) (xy 21.532006 -296.746905) (xy 21.561947 -296.548895) (xy 21.583943 -296.349847)
			(xy 21.597957 -296.150078) (xy 21.603967 -295.949908) (xy 21.601963 -295.749657) (xy 21.591949 -295.549648)
			(xy 21.573941 -295.350199) (xy 21.547967 -295.15163) (xy 21.51407 -294.95426) (xy 21.472303 -294.758403)
			(xy 21.422733 -294.564375) (xy 21.36544 -294.372485) (xy 21.300515 -294.183042) (xy 21.228063 -293.996347)
			(xy 21.148199 -293.812701) (xy 21.061052 -293.632397) (xy 20.96676 -293.455724) (xy 20.865475 -293.282966)
			(xy 20.75736 -293.114398) (xy 20.642587 -292.95029) (xy 20.521339 -292.790906) (xy 20.393812 -292.636501)
			(xy 20.260209 -292.487322) (xy 20.120745 -292.343607) (xy 19.975643 -292.205588) (xy 19.825134 -292.073484)
			(xy 19.669461 -291.947508) (xy 19.508872 -291.827862) (xy 19.343624 -291.714736) (xy 19.173983 -291.608312)
			(xy 19.000219 -291.508761) (xy 18.822612 -291.416242) (xy 18.641445 -291.330903) (xy 18.457009 -291.25288)
			(xy 18.269599 -291.1823) (xy 18.079516 -291.119274) (xy 17.887062 -291.063903) (xy 17.692548 -291.016277)
			(xy 17.496283 -290.976472) (xy 17.298584 -290.944551) (xy 17.099765 -290.920565) (xy 16.900146 -290.904553)
			(xy 16.700046 -290.896541)
		)
		(stroke
			(width 0)
			(type solid)
		)
		(fill yes)
		(layer "B.Cu")
		(net "GND")
	)
	(gr_poly
		(pts
			(xy 16.599916 -201.99604) (xy 16.499786 -201.996541) (xy 16.299686 -202.004553) (xy 16.100067 -202.020565)
			(xy 15.901248 -202.044551) (xy 15.703549 -202.076472) (xy 15.507284 -202.116277) (xy 15.31277 -202.163903)
			(xy 15.120316 -202.219274) (xy 14.930233 -202.2823) (xy 14.742823 -202.35288) (xy 14.558387 -202.430903)
			(xy 14.37722 -202.516242) (xy 14.199613 -202.608761) (xy 14.025849 -202.708312) (xy 13.856208 -202.814736)
			(xy 13.69096 -202.927862) (xy 13.530371 -203.047508) (xy 13.374698 -203.173484) (xy 13.224189 -203.305588)
			(xy 13.079087 -203.443607) (xy 12.939623 -203.587322) (xy 12.80602 -203.736501) (xy 12.678493 -203.890906)
			(xy 12.557245 -204.05029) (xy 12.442472 -204.214398) (xy 12.334357 -204.382966) (xy 12.233072 -204.555724)
			(xy 12.13878 -204.732397) (xy 12.051633 -204.912701) (xy 11.971769 -205.096347) (xy 11.899317 -205.283042)
			(xy 11.834392 -205.472485) (xy 11.777099 -205.664375) (xy 11.727529 -205.858403) (xy 11.685762 -206.05426)
			(xy 11.651865 -206.25163) (xy 11.625891 -206.450199) (xy 11.607883 -206.649648) (xy 11.597869 -206.849657)
			(xy 11.596722 -206.964249) (xy 14.085064 -206.964249) (xy 14.091106 -206.822028) (xy 14.105184 -206.680377)
			(xy 14.127253 -206.539749) (xy 14.157243 -206.400595) (xy 14.195058 -206.26336) (xy 14.240576 -206.128485)
			(xy 14.293652 -205.996401) (xy 14.354115 -205.867531) (xy 14.421772 -205.742288) (xy 14.496407 -205.621074)
			(xy 14.57778 -205.504276) (xy 14.66563 -205.392269) (xy 14.759677 -205.285411) (xy 14.859618 -205.184046)
			(xy 14.965134 -205.088497) (xy 15.075887 -204.99907) (xy 15.191521 -204.916052) (xy 15.311668 -204.83971)
			(xy 15.43594 -204.770287) (xy 15.563942 -204.708006) (xy 15.695262 -204.653066) (xy 15.829479 -204.605644)
			(xy 15.966165 -204.565891) (xy 16.104881 -204.533935) (xy 16.245182 -204.509878) (xy 16.38662 -204.493797)
			(xy 16.528741 -204.485744) (xy 16.599916 -204.48524) (xy 16.671091 -204.485744) (xy 16.813212 -204.493797)
			(xy 16.95465 -204.509878) (xy 17.094951 -204.533935) (xy 17.233667 -204.565891) (xy 17.370353 -204.605644)
			(xy 17.50457 -204.653066) (xy 17.63589 -204.708006) (xy 17.763892 -204.770287) (xy 17.888164 -204.83971)
			(xy 18.008311 -204.916052) (xy 18.123945 -204.99907) (xy 18.234698 -205.088497) (xy 18.340214 -205.184046)
			(xy 18.440155 -205.285411) (xy 18.534202 -205.392269) (xy 18.622052 -205.504276) (xy 18.703425 -205.621074)
			(xy 18.77806 -205.742288) (xy 18.845717 -205.867531) (xy 18.90618 -205.996401) (xy 18.959256 -206.128485)
			(xy 19.004774 -206.26336) (xy 19.042589 -206.400595) (xy 19.072579 -206.539749) (xy 19.094648 -206.680377)
			(xy 19.108726 -206.822028) (xy 19.114768 -206.964249) (xy 19.112753 -207.106584) (xy 19.10269 -207.248577)
			(xy 19.084609 -207.389773) (xy 19.058569 -207.52972) (xy 19.024653 -207.66797) (xy 18.98297 -207.804079)
			(xy 18.933653 -207.937613) (xy 18.876861 -208.068142) (xy 18.812774 -208.195249) (xy 18.7416 -208.318527)
			(xy 18.663565 -208.437581) (xy 18.578919 -208.552029) (xy 18.487935 -208.661505) (xy 18.390902 -208.765659)
			(xy 18.288132 -208.864156) (xy 18.179954 -208.95668) (xy 18.066715 -209.042937) (xy 17.948778 -209.122649)
			(xy 17.826519 -209.195561) (xy 17.700332 -209.261439) (xy 17.570619 -209.320073) (xy 17.437797 -209.371274)
			(xy 17.302291 -209.414879) (xy 17.164535 -209.450748) (xy 17.024971 -209.478766) (xy 16.884044 -209.498843)
			(xy 16.742208 -209.510915) (xy 16.599916 -209.514944) (xy 16.457624 -209.510915) (xy 16.315788 -209.498843)
			(xy 16.174861 -209.478766) (xy 16.035297 -209.450748) (xy 15.897541 -209.414879) (xy 15.762035 -209.371274)
			(xy 15.629213 -209.320073) (xy 15.4995 -209.261439) (xy 15.373313 -209.195561) (xy 15.251054 -209.122649)
			(xy 15.133117 -209.042937) (xy 15.019878 -208.95668) (xy 14.9117 -208.864156) (xy 14.80893 -208.765659)
			(xy 14.711897 -208.661505) (xy 14.620913 -208.552029) (xy 14.536267 -208.437581) (xy 14.458232 -208.318527)
			(xy 14.387058 -208.195249) (xy 14.322971 -208.068142) (xy 14.266179 -207.937613) (xy 14.216862 -207.804079)
			(xy 14.175179 -207.66797) (xy 14.141263 -207.52972) (xy 14.115223 -207.389773) (xy 14.097142 -207.248577)
			(xy 14.087079 -207.106584) (xy 14.085064 -206.964249) (xy 11.596722 -206.964249) (xy 11.595865 -207.049908)
			(xy 11.601875 -207.250078) (xy 11.615889 -207.449847) (xy 11.637885 -207.648895) (xy 11.667826 -207.846905)
			(xy 11.705666 -208.043557) (xy 11.751344 -208.238539) (xy 11.804786 -208.431536) (xy 11.865907 -208.622241)
			(xy 11.934609 -208.810348) (xy 12.010782 -208.995555) (xy 12.094305 -209.177567) (xy 12.185042 -209.356091)
			(xy 12.28285 -209.530842) (xy 12.387571 -209.701539) (xy 12.499038 -209.86791) (xy 12.617072 -210.029688)
			(xy 12.741484 -210.186614) (xy 12.872075 -210.338437) (xy 13.008636 -210.484913) (xy 13.150948 -210.625808)
			(xy 13.298783 -210.760897) (xy 13.451905 -210.889962) (xy 13.610067 -211.012798) (xy 13.773018 -211.129208)
			(xy 13.940496 -211.239004) (xy 14.112233 -211.342012) (xy 14.287953 -211.438067) (xy 14.467376 -211.527014)
			(xy 14.650214 -211.608711) (xy 14.836175 -211.683027) (xy 15.024959 -211.749844) (xy 15.216266 -211.809054)
			(xy 15.409789 -211.860563) (xy 15.605217 -211.904287) (xy 15.802239 -211.940158) (xy 16.000538 -211.968117)
			(xy 16.199796 -211.98812) (xy 16.399696 -212.000134) (xy 16.599916 -212.004141) (xy 16.800136 -212.000134)
			(xy 17.000036 -211.98812) (xy 17.199294 -211.968117) (xy 17.397593 -211.940158) (xy 17.594615 -211.904287)
			(xy 17.790043 -211.860563) (xy 17.983566 -211.809054) (xy 18.174873 -211.749844) (xy 18.363657 -211.683027)
			(xy 18.549618 -211.608711) (xy 18.732456 -211.527014) (xy 18.911879 -211.438067) (xy 19.087599 -211.342012)
			(xy 19.259336 -211.239004) (xy 19.426814 -211.129208) (xy 19.589765 -211.012798) (xy 19.747927 -210.889962)
			(xy 19.901049 -210.760897) (xy 20.048884 -210.625808) (xy 20.191196 -210.484913) (xy 20.327757 -210.338437)
			(xy 20.458348 -210.186614) (xy 20.58276 -210.029688) (xy 20.700794 -209.86791) (xy 20.812261 -209.701539)
			(xy 20.916982 -209.530842) (xy 21.01479 -209.356091) (xy 21.105527 -209.177567) (xy 21.18905 -208.995555)
			(xy 21.265223 -208.810348) (xy 21.333925 -208.622241) (xy 21.395046 -208.431536) (xy 21.448488 -208.238539)
			(xy 21.494166 -208.043557) (xy 21.532006 -207.846905) (xy 21.561947 -207.648895) (xy 21.583943 -207.449847)
			(xy 21.597957 -207.250078) (xy 21.603967 -207.049908) (xy 21.601963 -206.849657) (xy 21.591949 -206.649648)
			(xy 21.573941 -206.450199) (xy 21.547967 -206.25163) (xy 21.51407 -206.05426) (xy 21.472303 -205.858403)
			(xy 21.422733 -205.664375) (xy 21.36544 -205.472485) (xy 21.300515 -205.283042) (xy 21.228063 -205.096347)
			(xy 21.148199 -204.912701) (xy 21.061052 -204.732397) (xy 20.96676 -204.555724) (xy 20.865475 -204.382966)
			(xy 20.75736 -204.214398) (xy 20.642587 -204.05029) (xy 20.521339 -203.890906) (xy 20.393812 -203.736501)
			(xy 20.260209 -203.587322) (xy 20.120745 -203.443607) (xy 19.975643 -203.305588) (xy 19.825134 -203.173484)
			(xy 19.669461 -203.047508) (xy 19.508872 -202.927862) (xy 19.343624 -202.814736) (xy 19.173983 -202.708312)
			(xy 19.000219 -202.608761) (xy 18.822612 -202.516242) (xy 18.641445 -202.430903) (xy 18.457009 -202.35288)
			(xy 18.269599 -202.2823) (xy 18.079516 -202.219274) (xy 17.887062 -202.163903) (xy 17.692548 -202.116277)
			(xy 17.496283 -202.076472) (xy 17.298584 -202.044551) (xy 17.099765 -202.020565) (xy 16.900146 -202.004553)
			(xy 16.700046 -201.996541)
		)
		(stroke
			(width 0)
			(type solid)
		)
		(fill yes)
		(layer "B.Cu")
		(net "GND")
	)
	(gr_poly
		(pts
			(xy 16.599916 -113.09604) (xy 16.499786 -113.096541) (xy 16.299686 -113.104553) (xy 16.100067 -113.120565)
			(xy 15.901248 -113.144551) (xy 15.703549 -113.176472) (xy 15.507284 -113.216277) (xy 15.31277 -113.263903)
			(xy 15.120316 -113.319274) (xy 14.930233 -113.3823) (xy 14.742823 -113.45288) (xy 14.558387 -113.530903)
			(xy 14.37722 -113.616242) (xy 14.199613 -113.708761) (xy 14.025849 -113.808312) (xy 13.856208 -113.914736)
			(xy 13.69096 -114.027862) (xy 13.530371 -114.147508) (xy 13.374698 -114.273484) (xy 13.224189 -114.405588)
			(xy 13.079087 -114.543607) (xy 12.939623 -114.687322) (xy 12.80602 -114.836501) (xy 12.678493 -114.990906)
			(xy 12.557245 -115.15029) (xy 12.442472 -115.314398) (xy 12.334357 -115.482966) (xy 12.233072 -115.655724)
			(xy 12.13878 -115.832397) (xy 12.051633 -116.012701) (xy 11.971769 -116.196347) (xy 11.899317 -116.383042)
			(xy 11.834392 -116.572485) (xy 11.777099 -116.764375) (xy 11.727529 -116.958403) (xy 11.685762 -117.15426)
			(xy 11.651865 -117.35163) (xy 11.625891 -117.550199) (xy 11.607883 -117.749648) (xy 11.597869 -117.949657)
			(xy 11.596722 -118.064249) (xy 14.085064 -118.064249) (xy 14.091106 -117.922028) (xy 14.105184 -117.780377)
			(xy 14.127253 -117.639749) (xy 14.157243 -117.500595) (xy 14.195058 -117.36336) (xy 14.240576 -117.228485)
			(xy 14.293652 -117.096401) (xy 14.354115 -116.967531) (xy 14.421772 -116.842288) (xy 14.496407 -116.721074)
			(xy 14.57778 -116.604276) (xy 14.66563 -116.492269) (xy 14.759677 -116.385411) (xy 14.859618 -116.284046)
			(xy 14.965134 -116.188497) (xy 15.075887 -116.09907) (xy 15.191521 -116.016052) (xy 15.311668 -115.93971)
			(xy 15.43594 -115.870287) (xy 15.563942 -115.808006) (xy 15.695262 -115.753066) (xy 15.829479 -115.705644)
			(xy 15.966165 -115.665891) (xy 16.104881 -115.633935) (xy 16.245182 -115.609878) (xy 16.38662 -115.593797)
			(xy 16.528741 -115.585744) (xy 16.599916 -115.58524) (xy 16.671091 -115.585744) (xy 16.813212 -115.593797)
			(xy 16.95465 -115.609878) (xy 17.094951 -115.633935) (xy 17.233667 -115.665891) (xy 17.370353 -115.705644)
			(xy 17.50457 -115.753066) (xy 17.63589 -115.808006) (xy 17.763892 -115.870287) (xy 17.888164 -115.93971)
			(xy 18.008311 -116.016052) (xy 18.123945 -116.09907) (xy 18.234698 -116.188497) (xy 18.340214 -116.284046)
			(xy 18.440155 -116.385411) (xy 18.534202 -116.492269) (xy 18.622052 -116.604276) (xy 18.703425 -116.721074)
			(xy 18.77806 -116.842288) (xy 18.845717 -116.967531) (xy 18.90618 -117.096401) (xy 18.959256 -117.228485)
			(xy 19.004774 -117.36336) (xy 19.042589 -117.500595) (xy 19.072579 -117.639749) (xy 19.094648 -117.780377)
			(xy 19.108726 -117.922028) (xy 19.114768 -118.064249) (xy 19.112753 -118.206584) (xy 19.10269 -118.348577)
			(xy 19.084609 -118.489773) (xy 19.058569 -118.62972) (xy 19.024653 -118.76797) (xy 18.98297 -118.904079)
			(xy 18.933653 -119.037613) (xy 18.876861 -119.168142) (xy 18.812774 -119.295249) (xy 18.7416 -119.418527)
			(xy 18.663565 -119.537581) (xy 18.578919 -119.652029) (xy 18.487935 -119.761505) (xy 18.390902 -119.865659)
			(xy 18.288132 -119.964156) (xy 18.179954 -120.05668) (xy 18.066715 -120.142937) (xy 17.948778 -120.222649)
			(xy 17.826519 -120.295561) (xy 17.700332 -120.361439) (xy 17.570619 -120.420073) (xy 17.437797 -120.471274)
			(xy 17.302291 -120.514879) (xy 17.164535 -120.550748) (xy 17.024971 -120.578766) (xy 16.884044 -120.598843)
			(xy 16.742208 -120.610915) (xy 16.599916 -120.614944) (xy 16.457624 -120.610915) (xy 16.315788 -120.598843)
			(xy 16.174861 -120.578766) (xy 16.035297 -120.550748) (xy 15.897541 -120.514879) (xy 15.762035 -120.471274)
			(xy 15.629213 -120.420073) (xy 15.4995 -120.361439) (xy 15.373313 -120.295561) (xy 15.251054 -120.222649)
			(xy 15.133117 -120.142937) (xy 15.019878 -120.05668) (xy 14.9117 -119.964156) (xy 14.80893 -119.865659)
			(xy 14.711897 -119.761505) (xy 14.620913 -119.652029) (xy 14.536267 -119.537581) (xy 14.458232 -119.418527)
			(xy 14.387058 -119.295249) (xy 14.322971 -119.168142) (xy 14.266179 -119.037613) (xy 14.216862 -118.904079)
			(xy 14.175179 -118.76797) (xy 14.141263 -118.62972) (xy 14.115223 -118.489773) (xy 14.097142 -118.348577)
			(xy 14.087079 -118.206584) (xy 14.085064 -118.064249) (xy 11.596722 -118.064249) (xy 11.595865 -118.149908)
			(xy 11.601875 -118.350078) (xy 11.615889 -118.549847) (xy 11.637885 -118.748895) (xy 11.667826 -118.946905)
			(xy 11.705666 -119.143557) (xy 11.751344 -119.338539) (xy 11.804786 -119.531536) (xy 11.865907 -119.722241)
			(xy 11.934609 -119.910348) (xy 12.010782 -120.095555) (xy 12.094305 -120.277567) (xy 12.185042 -120.456091)
			(xy 12.28285 -120.630842) (xy 12.387571 -120.801539) (xy 12.499038 -120.96791) (xy 12.617072 -121.129688)
			(xy 12.741484 -121.286614) (xy 12.872075 -121.438437) (xy 13.008636 -121.584913) (xy 13.150948 -121.725808)
			(xy 13.298783 -121.860897) (xy 13.451905 -121.989962) (xy 13.610067 -122.112798) (xy 13.773018 -122.229208)
			(xy 13.940496 -122.339004) (xy 14.112233 -122.442012) (xy 14.287953 -122.538067) (xy 14.467376 -122.627014)
			(xy 14.650214 -122.708711) (xy 14.836175 -122.783027) (xy 15.024959 -122.849844) (xy 15.216266 -122.909054)
			(xy 15.409789 -122.960563) (xy 15.605217 -123.004287) (xy 15.802239 -123.040158) (xy 16.000538 -123.068117)
			(xy 16.199796 -123.08812) (xy 16.399696 -123.100134) (xy 16.599916 -123.104141) (xy 16.800136 -123.100134)
			(xy 17.000036 -123.08812) (xy 17.199294 -123.068117) (xy 17.397593 -123.040158) (xy 17.594615 -123.004287)
			(xy 17.790043 -122.960563) (xy 17.983566 -122.909054) (xy 18.174873 -122.849844) (xy 18.363657 -122.783027)
			(xy 18.549618 -122.708711) (xy 18.732456 -122.627014) (xy 18.911879 -122.538067) (xy 19.087599 -122.442012)
			(xy 19.259336 -122.339004) (xy 19.426814 -122.229208) (xy 19.589765 -122.112798) (xy 19.747927 -121.989962)
			(xy 19.901049 -121.860897) (xy 20.048884 -121.725808) (xy 20.191196 -121.584913) (xy 20.327757 -121.438437)
			(xy 20.458348 -121.286614) (xy 20.58276 -121.129688) (xy 20.700794 -120.96791) (xy 20.812261 -120.801539)
			(xy 20.916982 -120.630842) (xy 21.01479 -120.456091) (xy 21.105527 -120.277567) (xy 21.18905 -120.095555)
			(xy 21.265223 -119.910348) (xy 21.333925 -119.722241) (xy 21.395046 -119.531536) (xy 21.448488 -119.338539)
			(xy 21.494166 -119.143557) (xy 21.532006 -118.946905) (xy 21.561947 -118.748895) (xy 21.583943 -118.549847)
			(xy 21.597957 -118.350078) (xy 21.603967 -118.149908) (xy 21.601963 -117.949657) (xy 21.591949 -117.749648)
			(xy 21.573941 -117.550199) (xy 21.547967 -117.35163) (xy 21.51407 -117.15426) (xy 21.472303 -116.958403)
			(xy 21.422733 -116.764375) (xy 21.36544 -116.572485) (xy 21.300515 -116.383042) (xy 21.228063 -116.196347)
			(xy 21.148199 -116.012701) (xy 21.061052 -115.832397) (xy 20.96676 -115.655724) (xy 20.865475 -115.482966)
			(xy 20.75736 -115.314398) (xy 20.642587 -115.15029) (xy 20.521339 -114.990906) (xy 20.393812 -114.836501)
			(xy 20.260209 -114.687322) (xy 20.120745 -114.543607) (xy 19.975643 -114.405588) (xy 19.825134 -114.273484)
			(xy 19.669461 -114.147508) (xy 19.508872 -114.027862) (xy 19.343624 -113.914736) (xy 19.173983 -113.808312)
			(xy 19.000219 -113.708761) (xy 18.822612 -113.616242) (xy 18.641445 -113.530903) (xy 18.457009 -113.45288)
			(xy 18.269599 -113.3823) (xy 18.079516 -113.319274) (xy 17.887062 -113.263903) (xy 17.692548 -113.216277)
			(xy 17.496283 -113.176472) (xy 17.298584 -113.144551) (xy 17.099765 -113.120565) (xy 16.900146 -113.104553)
			(xy 16.700046 -113.096541)
		)
		(stroke
			(width 0)
			(type solid)
		)
		(fill yes)
		(layer "B.Cu")
		(net "GND")
	)
	(gr_poly
		(pts
			(xy 16.599916 -24.19604) (xy 16.499786 -24.196541) (xy 16.299686 -24.204553) (xy 16.100067 -24.220565)
			(xy 15.901248 -24.244551) (xy 15.703549 -24.276472) (xy 15.507284 -24.316277) (xy 15.31277 -24.363903)
			(xy 15.120316 -24.419274) (xy 14.930233 -24.4823) (xy 14.742823 -24.55288) (xy 14.558387 -24.630903)
			(xy 14.37722 -24.716242) (xy 14.199613 -24.808761) (xy 14.025849 -24.908312) (xy 13.856208 -25.014736)
			(xy 13.69096 -25.127862) (xy 13.530371 -25.247508) (xy 13.374698 -25.373484) (xy 13.224189 -25.505588)
			(xy 13.079087 -25.643607) (xy 12.939623 -25.787322) (xy 12.80602 -25.936501) (xy 12.678493 -26.090906)
			(xy 12.557245 -26.25029) (xy 12.442472 -26.414398) (xy 12.334357 -26.582966) (xy 12.233072 -26.755724)
			(xy 12.13878 -26.932397) (xy 12.051633 -27.112701) (xy 11.971769 -27.296347) (xy 11.899317 -27.483042)
			(xy 11.834392 -27.672485) (xy 11.777099 -27.864375) (xy 11.727529 -28.058403) (xy 11.685762 -28.25426)
			(xy 11.651865 -28.45163) (xy 11.625891 -28.650199) (xy 11.607883 -28.849648) (xy 11.597869 -29.049657)
			(xy 11.596722 -29.164249) (xy 14.085064 -29.164249) (xy 14.091106 -29.022028) (xy 14.105184 -28.880377)
			(xy 14.127253 -28.739749) (xy 14.157243 -28.600595) (xy 14.195058 -28.46336) (xy 14.240576 -28.328485)
			(xy 14.293652 -28.196401) (xy 14.354115 -28.067531) (xy 14.421772 -27.942288) (xy 14.496407 -27.821074)
			(xy 14.57778 -27.704276) (xy 14.66563 -27.592269) (xy 14.759677 -27.485411) (xy 14.859618 -27.384046)
			(xy 14.965134 -27.288497) (xy 15.075887 -27.19907) (xy 15.191521 -27.116052) (xy 15.311668 -27.03971)
			(xy 15.43594 -26.970287) (xy 15.563942 -26.908006) (xy 15.695262 -26.853066) (xy 15.829479 -26.805644)
			(xy 15.966165 -26.765891) (xy 16.104881 -26.733935) (xy 16.245182 -26.709878) (xy 16.38662 -26.693797)
			(xy 16.528741 -26.685744) (xy 16.599916 -26.68524) (xy 16.671091 -26.685744) (xy 16.813212 -26.693797)
			(xy 16.95465 -26.709878) (xy 17.094951 -26.733935) (xy 17.233667 -26.765891) (xy 17.370353 -26.805644)
			(xy 17.50457 -26.853066) (xy 17.63589 -26.908006) (xy 17.763892 -26.970287) (xy 17.888164 -27.03971)
			(xy 18.008311 -27.116052) (xy 18.123945 -27.19907) (xy 18.234698 -27.288497) (xy 18.340214 -27.384046)
			(xy 18.440155 -27.485411) (xy 18.534202 -27.592269) (xy 18.622052 -27.704276) (xy 18.703425 -27.821074)
			(xy 18.77806 -27.942288) (xy 18.845717 -28.067531) (xy 18.90618 -28.196401) (xy 18.959256 -28.328485)
			(xy 19.004774 -28.46336) (xy 19.042589 -28.600595) (xy 19.072579 -28.739749) (xy 19.094648 -28.880377)
			(xy 19.108726 -29.022028) (xy 19.114768 -29.164249) (xy 19.112753 -29.306584) (xy 19.10269 -29.448577)
			(xy 19.084609 -29.589773) (xy 19.058569 -29.72972) (xy 19.024653 -29.86797) (xy 18.98297 -30.004079)
			(xy 18.933653 -30.137613) (xy 18.876861 -30.268142) (xy 18.812774 -30.395249) (xy 18.7416 -30.518527)
			(xy 18.663565 -30.637581) (xy 18.578919 -30.752029) (xy 18.487935 -30.861505) (xy 18.390902 -30.965659)
			(xy 18.288132 -31.064156) (xy 18.179954 -31.15668) (xy 18.066715 -31.242937) (xy 17.948778 -31.322649)
			(xy 17.826519 -31.395561) (xy 17.700332 -31.461439) (xy 17.570619 -31.520073) (xy 17.437797 -31.571274)
			(xy 17.302291 -31.614879) (xy 17.164535 -31.650748) (xy 17.024971 -31.678766) (xy 16.884044 -31.698843)
			(xy 16.742208 -31.710915) (xy 16.599916 -31.714944) (xy 16.457624 -31.710915) (xy 16.315788 -31.698843)
			(xy 16.174861 -31.678766) (xy 16.035297 -31.650748) (xy 15.897541 -31.614879) (xy 15.762035 -31.571274)
			(xy 15.629213 -31.520073) (xy 15.4995 -31.461439) (xy 15.373313 -31.395561) (xy 15.251054 -31.322649)
			(xy 15.133117 -31.242937) (xy 15.019878 -31.15668) (xy 14.9117 -31.064156) (xy 14.80893 -30.965659)
			(xy 14.711897 -30.861505) (xy 14.620913 -30.752029) (xy 14.536267 -30.637581) (xy 14.458232 -30.518527)
			(xy 14.387058 -30.395249) (xy 14.322971 -30.268142) (xy 14.266179 -30.137613) (xy 14.216862 -30.004079)
			(xy 14.175179 -29.86797) (xy 14.141263 -29.72972) (xy 14.115223 -29.589773) (xy 14.097142 -29.448577)
			(xy 14.087079 -29.306584) (xy 14.085064 -29.164249) (xy 11.596722 -29.164249) (xy 11.595865 -29.249908)
			(xy 11.601875 -29.450078) (xy 11.615889 -29.649847) (xy 11.637885 -29.848895) (xy 11.667826 -30.046905)
			(xy 11.705666 -30.243557) (xy 11.751344 -30.438539) (xy 11.804786 -30.631536) (xy 11.865907 -30.822241)
			(xy 11.934609 -31.010348) (xy 12.010782 -31.195555) (xy 12.094305 -31.377567) (xy 12.185042 -31.556091)
			(xy 12.28285 -31.730842) (xy 12.387571 -31.901539) (xy 12.499038 -32.06791) (xy 12.617072 -32.229688)
			(xy 12.741484 -32.386614) (xy 12.872075 -32.538437) (xy 13.008636 -32.684913) (xy 13.150948 -32.825808)
			(xy 13.298783 -32.960897) (xy 13.451905 -33.089962) (xy 13.610067 -33.212798) (xy 13.773018 -33.329208)
			(xy 13.940496 -33.439004) (xy 14.112233 -33.542012) (xy 14.287953 -33.638067) (xy 14.467376 -33.727014)
			(xy 14.650214 -33.808711) (xy 14.836175 -33.883027) (xy 15.024959 -33.949844) (xy 15.216266 -34.009054)
			(xy 15.409789 -34.060563) (xy 15.605217 -34.104287) (xy 15.802239 -34.140158) (xy 16.000538 -34.168117)
			(xy 16.199796 -34.18812) (xy 16.399696 -34.200134) (xy 16.599916 -34.204141) (xy 16.800136 -34.200134)
			(xy 17.000036 -34.18812) (xy 17.199294 -34.168117) (xy 17.397593 -34.140158) (xy 17.594615 -34.104287)
			(xy 17.790043 -34.060563) (xy 17.983566 -34.009054) (xy 18.174873 -33.949844) (xy 18.363657 -33.883027)
			(xy 18.549618 -33.808711) (xy 18.732456 -33.727014) (xy 18.911879 -33.638067) (xy 19.087599 -33.542012)
			(xy 19.259336 -33.439004) (xy 19.426814 -33.329208) (xy 19.589765 -33.212798) (xy 19.747927 -33.089962)
			(xy 19.901049 -32.960897) (xy 20.048884 -32.825808) (xy 20.191196 -32.684913) (xy 20.327757 -32.538437)
			(xy 20.458348 -32.386614) (xy 20.58276 -32.229688) (xy 20.700794 -32.06791) (xy 20.812261 -31.901539)
			(xy 20.916982 -31.730842) (xy 21.01479 -31.556091) (xy 21.105527 -31.377567) (xy 21.18905 -31.195555)
			(xy 21.265223 -31.010348) (xy 21.333925 -30.822241) (xy 21.395046 -30.631536) (xy 21.448488 -30.438539)
			(xy 21.494166 -30.243557) (xy 21.532006 -30.046905) (xy 21.561947 -29.848895) (xy 21.583943 -29.649847)
			(xy 21.597957 -29.450078) (xy 21.603967 -29.249908) (xy 21.601963 -29.049657) (xy 21.591949 -28.849648)
			(xy 21.573941 -28.650199) (xy 21.547967 -28.45163) (xy 21.51407 -28.25426) (xy 21.472303 -28.058403)
			(xy 21.422733 -27.864375) (xy 21.36544 -27.672485) (xy 21.300515 -27.483042) (xy 21.228063 -27.296347)
			(xy 21.148199 -27.112701) (xy 21.061052 -26.932397) (xy 20.96676 -26.755724) (xy 20.865475 -26.582966)
			(xy 20.75736 -26.414398) (xy 20.642587 -26.25029) (xy 20.521339 -26.090906) (xy 20.393812 -25.936501)
			(xy 20.260209 -25.787322) (xy 20.120745 -25.643607) (xy 19.975643 -25.505588) (xy 19.825134 -25.373484)
			(xy 19.669461 -25.247508) (xy 19.508872 -25.127862) (xy 19.343624 -25.014736) (xy 19.173983 -24.908312)
			(xy 19.000219 -24.808761) (xy 18.822612 -24.716242) (xy 18.641445 -24.630903) (xy 18.457009 -24.55288)
			(xy 18.269599 -24.4823) (xy 18.079516 -24.419274) (xy 17.887062 -24.363903) (xy 17.692548 -24.316277)
			(xy 17.496283 -24.276472) (xy 17.298584 -24.244551) (xy 17.099765 -24.220565) (xy 16.900146 -24.204553)
			(xy 16.700046 -24.196541)
		)
		(stroke
			(width 0)
			(type solid)
		)
		(fill yes)
		(layer "B.Cu")
		(net "GND")
	)
	(gr_poly
		(pts
			(xy 101.000052 -529.49094) (xy 101.055822 -529.490433) (xy 101.167051 -529.482101) (xy 101.277346 -529.46548)
			(xy 101.38609 -529.440662) (xy 101.492675 -529.407788) (xy 101.596506 -529.367039) (xy 101.697001 -529.318645)
			(xy 101.793598 -529.262876) (xy 101.885758 -529.200044) (xy 101.972964 -529.130501) (xy 102.054729 -529.054635)
			(xy 102.130596 -528.97287) (xy 102.20014 -528.885664) (xy 102.262972 -528.793505) (xy 102.318742 -528.696908)
			(xy 102.367136 -528.596413) (xy 102.407885 -528.492583) (xy 102.44076 -528.385998) (xy 102.465578 -528.277253)
			(xy 102.4822 -528.166959) (xy 102.490533 -528.05573) (xy 102.491032 -527.99996) (xy 102.491032 -1.999996)
			(xy 102.490523 -1.944227) (xy 102.482188 -1.833002) (xy 102.465563 -1.72271) (xy 102.440743 -1.613969)
			(xy 102.407866 -1.507387) (xy 102.367116 -1.40356) (xy 102.31872 -1.303069) (xy 102.26295 -1.206475)
			(xy 102.200118 -1.11432) (xy 102.130574 -1.027117) (xy 102.054708 -0.945356) (xy 101.972944 -0.869492)
			(xy 101.885739 -0.799951) (xy 101.793581 -0.737122) (xy 101.696985 -0.681355) (xy 101.596492 -0.632964)
			(xy 101.492664 -0.592217) (xy 101.386081 -0.559343) (xy 101.277339 -0.534527) (xy 101.167047 -0.517907)
			(xy 101.055821 -0.509575) (xy 101.000052 -0.509016) (xy 26.500074 -0.509016) (xy 26.454278 -0.509546)
			(xy 26.363077 -0.517999) (xy 26.273045 -0.534832) (xy 26.184949 -0.559899) (xy 26.099543 -0.592988)
			(xy 26.017554 -0.633817) (xy 25.939682 -0.682036) (xy 25.866592 -0.737234) (xy 25.798906 -0.798941)
			(xy 25.737202 -0.86663) (xy 25.682007 -0.939724) (xy 25.633792 -1.017598) (xy 25.592968 -1.099589)
			(xy 25.559883 -1.184997) (xy 25.53482 -1.273093) (xy 25.517992 -1.363126) (xy 25.509543 -1.454328)
			(xy 25.508966 -1.500124) (xy 25.508966 -2.500122) (xy 25.50847 -2.563238) (xy 25.500544 -2.689221)
			(xy 25.484723 -2.814458) (xy 25.461069 -2.938455) (xy 25.429676 -3.060721) (xy 25.390668 -3.180775)
			(xy 25.344199 -3.298143) (xy 25.290452 -3.412362) (xy 25.229639 -3.52298) (xy 25.162 -3.629561) (xy 25.087803 -3.731685)
			(xy 25.007339 -3.828949) (xy 24.920927 -3.920968) (xy 24.828907 -4.00738) (xy 24.731644 -4.087844)
			(xy 24.62952 -4.162041) (xy 24.522938 -4.22968) (xy 24.41232 -4.290493) (xy 24.298101 -4.34424) (xy 24.180733 -4.390709)
			(xy 24.060679 -4.429717) (xy 23.938413 -4.46111) (xy 23.814416 -4.484763) (xy 23.689179 -4.500584)
			(xy 23.563196 -4.50851) (xy 23.50008 -4.509008) (xy 1.500124 -4.509008) (xy 1.454327 -4.509537) (xy 1.363123 -4.517988)
			(xy 1.273088 -4.534819) (xy 1.18499 -4.559885) (xy 1.099581 -4.592972) (xy 1.017589 -4.6338) (xy 0.939714 -4.682018)
			(xy 0.86662 -4.737216) (xy 0.798931 -4.798923) (xy 0.737224 -4.866612) (xy 0.682026 -4.939706) (xy 0.633808 -5.017581)
			(xy 0.59298 -5.099573) (xy 0.559893 -5.184982) (xy 0.534827 -5.27308) (xy 0.517996 -5.363115) (xy 0.509545 -5.454319)
			(xy 0.509222 -5.482255) (xy 1.01507 -5.482255) (xy 1.021763 -5.417929) (xy 1.036946 -5.355063) (xy 1.06035 -5.294772)
			(xy 1.091558 -5.238126) (xy 1.130019 -5.186131) (xy 1.175048 -5.139708) (xy 1.225848 -5.099682) (xy 1.281516 -5.066762)
			(xy 1.341066 -5.041533) (xy 1.403441 -5.024442) (xy 1.467534 -5.015793) (xy 1.49987 -5.01523) (xy 1.500124 -5.01523)
			(xy 1.500124 -5.015484) (xy 23.266908 -5.015484) (xy 23.266908 -5.01523) (xy 23.50008 -5.01523) (xy 23.570631 -5.014727)
			(xy 23.711511 -5.006802) (xy 23.851725 -4.990991) (xy 23.990832 -4.967345) (xy 24.128395 -4.935937)
			(xy 24.26398 -4.896866) (xy 24.397162 -4.850255) (xy 24.527521 -4.796251) (xy 24.654648 -4.735024)
			(xy 24.778142 -4.666765) (xy 24.897614 -4.591691) (xy 25.01269 -4.510037) (xy 25.123008 -4.422059)
			(xy 25.228219 -4.328035) (xy 25.327994 -4.228261) (xy 25.422018 -4.123049) (xy 25.509995 -4.012732)
			(xy 25.59165 -3.897656) (xy 25.666724 -3.778183) (xy 25.734983 -3.654689) (xy 25.796211 -3.527563)
			(xy 25.850215 -3.397204) (xy 25.896826 -3.264022) (xy 25.935897 -3.128437) (xy 25.967305 -2.990874)
			(xy 25.990951 -2.851767) (xy 26.006762 -2.711553) (xy 26.014687 -2.570673) (xy 26.015188 -2.500122)
			(xy 26.015188 -1.500124) (xy 26.01562 -1.46838) (xy 26.023881 -1.405431) (xy 26.04029 -1.3441) (xy 26.064566 -1.285437)
			(xy 26.096294 -1.230445) (xy 26.13493 -1.180067) (xy 26.179813 -1.135165) (xy 26.230175 -1.096507)
			(xy 26.285154 -1.064756) (xy 26.343807 -1.040455) (xy 26.405131 -1.024021) (xy 26.468076 -1.015734)
			(xy 26.49982 -1.015238) (xy 26.500074 -1.015238) (xy 26.500074 -1.015492) (xy 101.000052 -1.015492)
			(xy 101.045544 -1.016051) (xy 101.13614 -1.024442) (xy 101.225575 -1.041156) (xy 101.313087 -1.066052)
			(xy 101.397928 -1.098916) (xy 101.479375 -1.139468) (xy 101.556732 -1.187362) (xy 101.629341 -1.24219)
			(xy 101.69658 -1.303483) (xy 101.757877 -1.370719) (xy 101.812709 -1.443325) (xy 101.860607 -1.52068)
			(xy 101.901163 -1.602124) (xy 101.934032 -1.686964) (xy 101.958932 -1.774474) (xy 101.975651 -1.863909)
			(xy 101.984046 -1.954504) (xy 101.984556 -1.999996) (xy 101.984556 -486.544366) (xy 101.98481 -486.544366)
			(xy 101.98481 -486.547414) (xy 101.984556 -486.549954) (xy 101.984556 -527.99996) (xy 101.984056 -528.045454)
			(xy 101.975664 -528.136053) (xy 101.958948 -528.225491) (xy 101.93405 -528.313006) (xy 101.901184 -528.397849)
			(xy 101.860628 -528.479298) (xy 101.812731 -528.556657) (xy 101.757899 -528.629267) (xy 101.696601 -528.696507)
			(xy 101.629361 -528.757804) (xy 101.556751 -528.812635) (xy 101.479391 -528.860532) (xy 101.397942 -528.901087)
			(xy 101.313098 -528.933953) (xy 101.225583 -528.95885) (xy 101.136145 -528.975565) (xy 101.045546 -528.983957)
			(xy 101.000052 -528.984464) (xy 26.500074 -528.984464) (xy 26.500074 -528.984718) (xy 26.49982 -528.984718)
			(xy 26.468088 -528.984217) (xy 26.405167 -528.975935) (xy 26.343864 -528.959512) (xy 26.285231 -528.935226)
			(xy 26.230269 -528.903495) (xy 26.179919 -528.864861) (xy 26.135043 -528.819986) (xy 26.096408 -528.769636)
			(xy 26.064676 -528.714675) (xy 26.04039 -528.656041) (xy 26.023966 -528.594739) (xy 26.015683 -528.531818)
			(xy 26.015188 -528.500086) (xy 26.015188 -527.500088) (xy 26.014716 -527.429524) (xy 26.006818 -527.288618)
			(xy 25.991032 -527.148377) (xy 25.967407 -527.009241) (xy 25.936016 -526.871649) (xy 25.89696 -526.736034)
			(xy 25.850361 -526.602822) (xy 25.796365 -526.472433) (xy 25.735143 -526.345277) (xy 25.666887 -526.221754)
			(xy 25.591812 -526.102252) (xy 25.510154 -525.987148) (xy 25.42217 -525.876805) (xy 25.328137 -525.771568)
			(xy 25.278588 -525.721326) (xy 25.228345 -525.671786) (xy 25.123129 -525.577747) (xy 25.012807 -525.489756)
			(xy 24.897725 -525.408088) (xy 24.778244 -525.333002) (xy 24.654742 -525.264732) (xy 24.527607 -525.203494)
			(xy 24.397238 -525.14948) (xy 24.264046 -525.102861) (xy 24.12845 -525.063783) (xy 23.990875 -525.032368)
			(xy 23.851756 -525.008716) (xy 23.71153 -524.992902) (xy 23.570638 -524.984974) (xy 23.50008 -524.984472)
			(xy 1.514856 -524.984472) (xy 1.481877 -524.984932) (xy 1.416287 -524.977997) (xy 1.352242 -524.962233)
			(xy 1.290926 -524.937933) (xy 1.233471 -524.905544) (xy 1.180938 -524.865664) (xy 1.157224 -524.84274)
			(xy 1.135152 -524.81995) (xy 1.096547 -524.769602) (xy 1.064848 -524.714643) (xy 1.040598 -524.656016)
			(xy 1.02421 -524.594724) (xy 1.015968 -524.531817) (xy 1.015492 -524.500094) (xy 1.015492 -5.514594)
			(xy 1.01507 -5.482255) (xy 0.509222 -5.482255) (xy 0.509016 -5.500116) (xy 0.509016 -524.500094)
			(xy 0.509529 -524.54588) (xy 0.517978 -524.637062) (xy 0.534804 -524.727075) (xy 0.559864 -524.815152)
			(xy 0.592944 -524.900541) (xy 0.633761 -524.982513) (xy 0.681968 -525.06037) (xy 0.737153 -525.133446)
			(xy 0.798845 -525.201119) (xy 0.866518 -525.262811) (xy 0.939594 -525.317996) (xy 1.017451 -525.366203)
			(xy 1.099423 -525.40702) (xy 1.184812 -525.4401) (xy 1.272889 -525.46516) (xy 1.362902 -525.481986)
			(xy 1.454084 -525.490435) (xy 1.49987 -525.490948) (xy 23.50008 -525.490948) (xy 23.563202 -525.491433)
			(xy 23.689196 -525.499359) (xy 23.814444 -525.515182) (xy 23.93845 -525.538839) (xy 24.060727 -525.570236)
			(xy 24.180791 -525.60925) (xy 24.298167 -525.655726) (xy 24.412394 -525.709482) (xy 24.523019 -525.770304)
			(xy 24.629607 -525.837954) (xy 24.731736 -525.912163) (xy 24.829004 -525.992639) (xy 24.921025 -526.079064)
			(xy 25.007438 -526.171097) (xy 25.087902 -526.268376) (xy 25.162097 -526.370515) (xy 25.229732 -526.477111)
			(xy 25.29054 -526.587745) (xy 25.34428 -526.701979) (xy 25.390741 -526.819362) (xy 25.429739 -526.93943)
			(xy 25.46112 -527.061711) (xy 25.48476 -527.185721) (xy 25.500566 -527.310971) (xy 25.508475 -527.436966)
			(xy 25.508966 -527.500088) (xy 25.508966 -528.500086) (xy 25.509507 -528.545875) (xy 25.517982 -528.637061)
			(xy 25.534832 -528.727076) (xy 25.559914 -528.815153) (xy 25.593014 -528.90054) (xy 25.633851 -528.98251)
			(xy 25.682074 -529.060363) (xy 25.737274 -529.133435) (xy 25.79898 -529.201104) (xy 25.866665 -529.262792)
			(xy 25.939752 -529.317973) (xy 26.017618 -529.366176) (xy 26.099598 -529.406991) (xy 26.184994 -529.440069)
			(xy 26.273077 -529.465128) (xy 26.363097 -529.481954) (xy 26.454285 -529.490405) (xy 26.500074 -529.49094)
		)
		(stroke
			(width 0)
			(type solid)
		)
		(fill yes)
		(layer "B.Cu")
		(net "GND")
	)
	(gr_poly
		(pts
			(xy 21.063712 -378.84481) (xy 21.080359 -378.859517) (xy 21.117764 -378.883469) (xy 21.15876 -378.90056)
			(xy 21.202103 -378.910269) (xy 21.246472 -378.912301) (xy 21.290521 -378.906596) (xy 21.332909 -378.893325)
			(xy 21.372347 -378.872893) (xy 21.407636 -378.845921) (xy 21.437703 -378.813229) (xy 21.461635 -378.775811)
			(xy 21.478702 -378.734805) (xy 21.488388 -378.691457) (xy 21.489924 -378.669296) (xy 21.489924 -360.486706)
			(xy 21.056854 -360.053636) (xy 19.670268 -358.667304) (xy 19.670268 -322.326) (xy 24.012652 -317.98387)
			(xy 24.023584 -317.971821) (xy 24.039505 -317.943459) (xy 24.047736 -317.911994) (xy 24.048212 -317.895732)
			(xy 24.048212 -290.856416) (xy 24.047674 -290.839798) (xy 24.039085 -290.80769) (xy 24.022488 -290.778895)
			(xy 24.011128 -290.766754) (xy 18.773648 -285.529528) (xy 18.773648 -281.149806) (xy 14.964156 -277.34006)
			(xy 14.964156 -258.832604) (xy 14.964669 -258.800745) (xy 14.973053 -258.737582) (xy 14.989671 -258.676069)
			(xy 15.014234 -258.617276) (xy 15.046316 -258.562225) (xy 15.085359 -258.51187) (xy 15.130685 -258.467087)
			(xy 15.181507 -258.428654) (xy 15.236941 -258.397239) (xy 15.296026 -258.373386) (xy 15.357734 -258.357511)
			(xy 15.420995 -258.349889) (xy 15.484708 -258.350653) (xy 15.547767 -258.359789) (xy 15.609077 -258.377138)
			(xy 15.667573 -258.4024) (xy 15.695168 -258.41833) (xy 15.723616 -258.436618) (xy 15.738602 -258.447032)
			(xy 15.813786 -258.472178) (xy 15.88262 -258.451604) (xy 15.896844 -258.442968) (xy 15.914311 -258.43256)
			(xy 15.950682 -258.414376) (xy 15.969488 -258.406646) (xy 15.990824 -258.398772) (xy 16.021657 -258.38867)
			(xy 16.085267 -258.375879) (xy 16.150017 -258.371726) (xy 16.214739 -258.376286) (xy 16.278267 -258.389476)
			(xy 16.339455 -258.411059) (xy 16.3972 -258.440645) (xy 16.424148 -258.458716) (xy 16.456914 -258.481322)
			(xy 16.731996 -258.481322) (xy 16.994632 -258.218686) (xy 16.994632 -254.324612) (xy 16.419068 -253.749048)
			(xy 16.07439 -253.404116) (xy 15.559532 -252.889258) (xy 15.559532 -225.461322) (xy 15.559025 -225.438534)
			(xy 15.550901 -225.393687) (xy 15.53491 -225.351007) (xy 15.511564 -225.311864) (xy 15.481611 -225.277511)
			(xy 15.446013 -225.249051) (xy 15.405909 -225.227395) (xy 15.362587 -225.213238) (xy 15.317434 -225.207034)
			(xy 15.271899 -225.208982) (xy 15.227441 -225.219019) (xy 15.185486 -225.236823) (xy 15.147378 -225.261824)
			(xy 15.130526 -225.277172) (xy 15.08855 -225.316384) (xy 14.999904 -225.389453) (xy 14.906322 -225.456083)
			(xy 14.808271 -225.515943) (xy 14.70624 -225.568735) (xy 14.600738 -225.614194) (xy 14.492291 -225.652095)
			(xy 14.38144 -225.682248) (xy 14.268737 -225.704503) (xy 14.154745 -225.718748) (xy 14.040031 -225.724914)
			(xy 13.925168 -225.722969) (xy 13.810729 -225.712922) (xy 13.697285 -225.694825) (xy 13.5854 -225.668766)
			(xy 13.475633 -225.634877) (xy 13.368532 -225.593326) (xy 13.26463 -225.54432) (xy 13.164445 -225.488104)
			(xy 13.068477 -225.424958) (xy 12.977205 -225.355197) (xy 12.891084 -225.279168) (xy 12.810543 -225.197252)
			(xy 12.735984 -225.109855) (xy 12.667778 -225.017415) (xy 12.606266 -224.920392) (xy 12.551754 -224.81927)
			(xy 12.504514 -224.714553) (xy 12.464783 -224.606763) (xy 12.432757 -224.496438) (xy 12.408597 -224.384128)
			(xy 12.392423 -224.270394) (xy 12.384316 -224.155801) (xy 12.384316 -224.040922) (xy 12.392423 -223.926329)
			(xy 12.408596 -223.812594) (xy 12.432756 -223.700284) (xy 12.464782 -223.589959) (xy 12.504513 -223.48217)
			(xy 12.551753 -223.377453) (xy 12.606264 -223.27633) (xy 12.667776 -223.179307) (xy 12.735982 -223.086867)
			(xy 12.810541 -222.999471) (xy 12.891082 -222.917554) (xy 12.977203 -222.841525) (xy 13.068475 -222.771764)
			(xy 13.164443 -222.708617) (xy 13.264627 -222.652401) (xy 13.368529 -222.603395) (xy 13.475631 -222.561844)
			(xy 13.585397 -222.527954) (xy 13.697282 -222.501896) (xy 13.810727 -222.483798) (xy 13.925166 -222.473752)
			(xy 14.040028 -222.471806) (xy 14.154742 -222.477971) (xy 14.268734 -222.492217) (xy 14.381437 -222.514472)
			(xy 14.492289 -222.544624) (xy 14.600736 -222.582525) (xy 14.706238 -222.627984) (xy 14.808269 -222.680775)
			(xy 14.906319 -222.740635) (xy 14.999901 -222.807266) (xy 15.088548 -222.880334) (xy 15.130526 -222.919544)
			(xy 15.147394 -222.934871) (xy 15.185499 -222.959868) (xy 15.227451 -222.977669) (xy 15.271905 -222.987704)
			(xy 15.317435 -222.989651) (xy 15.362583 -222.983448) (xy 15.405901 -222.969292) (xy 15.446001 -222.947639)
			(xy 15.481596 -222.919183) (xy 15.511547 -222.884835) (xy 15.534892 -222.845696) (xy 15.550884 -222.803022)
			(xy 15.55901 -222.75818) (xy 15.559532 -222.735394) (xy 15.559532 -222.00743) (xy 17.53997 -220.026992)
			(xy 17.54505 -219.982796) (xy 17.54911 -219.951872) (xy 17.564532 -219.891439) (xy 17.588018 -219.833661)
			(xy 17.619131 -219.779606) (xy 17.657297 -219.730277) (xy 17.701808 -219.686588) (xy 17.751839 -219.649347)
			(xy 17.806463 -219.619245) (xy 17.864669 -219.59684) (xy 17.925379 -219.582546) (xy 17.987467 -219.576628)
			(xy 18.049783 -219.579197) (xy 18.111174 -219.590203) (xy 18.170502 -219.609444) (xy 18.226667 -219.636563)
			(xy 18.252948 -219.653358) (xy 18.284698 -219.67444) (xy 18.323052 -219.67444) (xy 18.339713 -219.673951)
			(xy 18.371902 -219.665339) (xy 18.400765 -219.648689) (xy 18.424335 -219.625135) (xy 18.441005 -219.596284)
			(xy 18.44964 -219.564101) (xy 18.450052 -219.54744) (xy 18.450052 -219.428568) (xy 18.26641 -219.244926)
			(xy 18.156428 -219.13469) (xy 17.99209 -218.970352) (xy 17.947894 -218.965272) (xy 17.917945 -218.961372)
			(xy 17.85936 -218.946701) (xy 17.803213 -218.92445) (xy 17.750481 -218.895007) (xy 17.70208 -218.858884)
			(xy 17.658852 -218.816707) (xy 17.621547 -218.769211) (xy 17.590814 -218.71722) (xy 17.567188 -218.661638)
			(xy 17.551078 -218.603431) (xy 17.542765 -218.543611) (xy 17.542393 -218.483217) (xy 17.549969 -218.4233)
			(xy 17.565361 -218.364899) (xy 17.588301 -218.30903) (xy 17.618391 -218.256665) (xy 17.655108 -218.208713)
			(xy 17.697814 -218.166007) (xy 17.745766 -218.12929) (xy 17.798132 -218.0992) (xy 17.854001 -218.07626)
			(xy 17.912401 -218.060869) (xy 17.972319 -218.053293) (xy 18.032713 -218.053665) (xy 18.092533 -218.061978)
			(xy 18.15074 -218.078088) (xy 18.206322 -218.101715) (xy 18.258312 -218.132448) (xy 18.305809 -218.169753)
			(xy 18.347985 -218.212981) (xy 18.384108 -218.261382) (xy 18.413551 -218.314114) (xy 18.435801 -218.370261)
			(xy 18.450472 -218.428847) (xy 18.45437 -218.458796) (xy 18.45945 -218.502992) (xy 18.693384 -218.736926)
			(xy 18.850102 -218.89339) (xy 19.111468 -219.154756) (xy 19.111468 -235.59389) (xy 21.23948 -237.721902)
			(xy 21.256907 -237.737614) (xy 21.296354 -237.763009) (xy 21.339795 -237.780726) (xy 21.385751 -237.790162)
			(xy 21.432658 -237.790995) (xy 21.478921 -237.783197) (xy 21.522963 -237.767033) (xy 21.563287 -237.743054)
			(xy 21.59852 -237.712075) (xy 21.627462 -237.675152) (xy 21.638768 -237.654592) (xy 21.638768 -237.014766)
			(xy 22.829012 -235.824522) (xy 22.829012 -235.729272) (xy 22.821646 -235.719112) (xy 22.804553 -235.695407)
			(xy 22.775877 -235.644485) (xy 22.753917 -235.590326) (xy 22.739029 -235.533812) (xy 22.731457 -235.475863)
			(xy 22.731324 -235.417422) (xy 22.738631 -235.359439) (xy 22.753261 -235.302858) (xy 22.774974 -235.2486)
			(xy 22.803418 -235.197547) (xy 22.83813 -235.150531) (xy 22.857968 -235.12907) (xy 22.857968 -233.67873)
			(xy 21.372068 -232.192576) (xy 21.372068 -221.926912) (xy 21.772372 -221.526354) (xy 21.772372 -213.68258)
			(xy 20.63496 -212.545168) (xy 12.7254 -212.545168) (xy 9.990328 -209.810096) (xy 9.978157 -209.798743)
			(xy 9.949318 -209.782154) (xy 9.917174 -209.773569) (xy 9.883904 -209.773569) (xy 9.85176 -209.782154)
			(xy 9.822921 -209.798743) (xy 9.81075 -209.810096) (xy 9.722866 -209.898234) (xy 9.711471 -209.910364)
			(xy 9.694789 -209.939147) (xy 9.686114 -209.971263) (xy 9.685528 -209.987896) (xy 9.685528 -211.130896)
			(xy 8.925814 -211.890864) (xy 8.9109 -211.906424) (xy 8.886009 -211.941606) (xy 8.86741 -211.980483)
			(xy 8.855636 -212.02194) (xy 8.851026 -212.06479) (xy 8.85371 -212.107803) (xy 8.863612 -212.149746)
			(xy 8.880448 -212.189418) (xy 8.903736 -212.225681) (xy 8.91794 -212.241892) (xy 8.941707 -212.268615)
			(xy 8.983727 -212.326488) (xy 9.018985 -212.388712) (xy 9.047034 -212.454502) (xy 9.067519 -212.523024)
			(xy 9.080182 -212.593413) (xy 9.084862 -212.664779) (xy 9.0815 -212.736219) (xy 9.070139 -212.80683)
			(xy 9.050922 -212.875719) (xy 9.024093 -212.942015) (xy 8.98999 -213.00488) (xy 8.949044 -213.063518)
			(xy 8.901775 -213.117189) (xy 8.848778 -213.165214) (xy 8.790725 -213.206985) (xy 8.728349 -213.241974)
			(xy 8.66244 -213.269739) (xy 8.59383 -213.289929) (xy 8.523387 -213.302289) (xy 8.452001 -213.306661)
			(xy 8.380576 -213.302992) (xy 8.310015 -213.291327) (xy 8.24121 -213.271813) (xy 8.17503 -213.244698)
			(xy 8.112312 -213.210325) (xy 8.053851 -213.169128) (xy 8.000384 -213.121627) (xy 7.952588 -213.068424)
			(xy 7.911068 -213.010192) (xy 7.876347 -212.947666) (xy 7.848866 -212.881637) (xy 7.83844 -212.847428)
			(xy 7.831892 -212.826443) (xy 7.812606 -212.786945) (xy 7.78681 -212.751356) (xy 7.755273 -212.720737)
			(xy 7.718938 -212.696003) (xy 7.678887 -212.677891) (xy 7.636318 -212.666942) (xy 7.592499 -212.663483)
			(xy 7.548739 -212.667617) (xy 7.506343 -212.679221) (xy 7.466577 -212.697948) (xy 7.430627 -212.723239)
			(xy 7.414768 -212.738462) (xy 6.994144 -213.159086) (xy 6.982177 -213.171806) (xy 6.965082 -213.202244)
			(xy 6.956879 -213.236178) (xy 6.958183 -213.271065) (xy 6.968897 -213.304291) (xy 6.978142 -213.319106)
			(xy 6.997685 -213.349442) (xy 7.030544 -213.41369) (xy 7.055914 -213.481248) (xy 7.073466 -213.551244)
			(xy 7.082974 -213.622779) (xy 7.084317 -213.69493) (xy 7.077477 -213.766769) (xy 7.062542 -213.837371)
			(xy 7.039704 -213.905825) (xy 7.009258 -213.971252) (xy 6.971596 -214.032808) (xy 6.927202 -214.089701)
			(xy 6.876648 -214.141198) (xy 6.820585 -214.186635) (xy 6.759735 -214.225429) (xy 6.694882 -214.257079)
			(xy 6.626861 -214.281177) (xy 6.556548 -214.297414) (xy 6.484847 -214.30558) (xy 6.412683 -214.305571)
			(xy 6.340985 -214.297385) (xy 6.270676 -214.28113) (xy 6.202661 -214.257013) (xy 6.137817 -214.225346)
			(xy 6.076978 -214.186536) (xy 6.020927 -214.141084) (xy 5.970387 -214.089573) (xy 5.926008 -214.032669)
			(xy 5.888362 -213.971103) (xy 5.857933 -213.905668) (xy 5.835113 -213.837207) (xy 5.820197 -213.766602)
			(xy 5.813376 -213.694761) (xy 5.814739 -213.62261) (xy 5.824266 -213.551078) (xy 5.841837 -213.481086)
			(xy 5.867224 -213.413535) (xy 5.900101 -213.349295) (xy 5.940044 -213.289194) (xy 5.98654 -213.234005)
			(xy 6.038988 -213.184439) (xy 6.067552 -213.162388) (xy 6.118352 -213.124288) (xy 6.118352 -213.100158)
			(xy 6.489446 -212.72881) (xy 6.505546 -212.711966) (xy 6.531931 -212.673567) (xy 6.550876 -212.631002)
			(xy 6.561746 -212.585698) (xy 6.564179 -212.539171) (xy 6.558091 -212.49298) (xy 6.543687 -212.448672)
			(xy 6.52145 -212.407731) (xy 6.492124 -212.371529) (xy 6.456691 -212.341277) (xy 6.416339 -212.317989)
			(xy 6.372418 -212.302445) (xy 6.349492 -212.29828) (xy 6.314166 -212.292192) (xy 6.245071 -212.27309)
			(xy 6.178565 -212.246333) (xy 6.115493 -212.212261) (xy 6.056656 -212.171308) (xy 6.002801 -212.123993)
			(xy 5.954614 -212.070917) (xy 5.912707 -212.012756) (xy 5.877611 -211.950248) (xy 5.849773 -211.884187)
			(xy 5.829547 -211.815412) (xy 5.817189 -211.744799) (xy 5.812857 -211.673243) (xy 5.816605 -211.601654)
			(xy 5.828387 -211.530942) (xy 5.848052 -211.462005) (xy 5.87535 -211.39572) (xy 5.909935 -211.332927)
			(xy 5.951367 -211.274426) (xy 5.999119 -211.220959) (xy 6.052586 -211.173207) (xy 6.111087 -211.131775)
			(xy 6.17388 -211.09719) (xy 6.240165 -211.069892) (xy 6.309102 -211.050227) (xy 6.379814 -211.038445)
			(xy 6.451403 -211.034697) (xy 6.522959 -211.039029) (xy 6.593572 -211.051387) (xy 6.662347 -211.071613)
			(xy 6.728408 -211.099451) (xy 6.790916 -211.134547) (xy 6.849077 -211.176454) (xy 6.902153 -211.224641)
			(xy 6.949468 -211.278496) (xy 6.990421 -211.337333) (xy 7.024493 -211.400405) (xy 7.05125 -211.466911)
			(xy 7.070352 -211.536006) (xy 7.07644 -211.571332) (xy 7.080586 -211.594267) (xy 7.096112 -211.638206)
			(xy 7.11939 -211.678577) (xy 7.149639 -211.714027) (xy 7.185845 -211.743367) (xy 7.226794 -211.765613)
			(xy 7.271113 -211.78002) (xy 7.317316 -211.786104) (xy 7.363853 -211.783661) (xy 7.409165 -211.772774)
			(xy 7.451732 -211.753806) (xy 7.490127 -211.727395) (xy 7.50697 -211.711286) (xy 7.855458 -211.363052)
			(xy 7.88924 -211.363052) (xy 7.954264 -211.318602) (xy 7.992872 -211.218018) (xy 7.998556 -211.201694)
			(xy 8.001893 -211.167305) (xy 7.995873 -211.133282) (xy 7.980939 -211.102126) (xy 7.970012 -211.088732)
			(xy 7.94678 -211.061376) (xy 7.905961 -211.00234) (xy 7.872052 -210.939082) (xy 7.845486 -210.872407)
			(xy 7.826599 -210.803163) (xy 7.815633 -210.732232) (xy 7.812727 -210.660518) (xy 7.817918 -210.588933)
			(xy 7.83114 -210.518388) (xy 7.852225 -210.449782) (xy 7.880904 -210.383987) (xy 7.916812 -210.321842)
			(xy 7.937754 -210.292696) (xy 7.951209 -210.273581) (xy 7.97163 -210.231539) (xy 7.984022 -210.186473)
			(xy 7.987965 -210.1399) (xy 7.983327 -210.093392) (xy 7.970264 -210.048515) (xy 7.949218 -210.006783)
			(xy 7.920896 -209.969602) (xy 7.886254 -209.938226) (xy 7.846459 -209.913711) (xy 7.802854 -209.896886)
			(xy 7.756907 -209.888316) (xy 7.733538 -209.88782) (xy 7.70509 -209.88782) (xy 6.118352 -208.300828)
			(xy 6.118352 -208.280762) (xy 6.117925 -208.266025) (xy 6.111148 -208.237341) (xy 6.097965 -208.21098)
			(xy 6.079081 -208.188351) (xy 6.067552 -208.179162) (xy 6.039154 -208.157253) (xy 5.986977 -208.108035)
			(xy 5.940672 -208.053256) (xy 5.900828 -207.993613) (xy 5.867953 -207.929863) (xy 5.842463 -207.862817)
			(xy 5.824684 -207.793327) (xy 5.814841 -207.722278) (xy 5.81306 -207.650573) (xy 5.819362 -207.579122)
			(xy 5.833668 -207.508836) (xy 5.855796 -207.440607) (xy 5.885465 -207.375303) (xy 5.922297 -207.313754)
			(xy 5.965824 -207.256743) (xy 6.015493 -207.204995) (xy 6.070672 -207.159168) (xy 6.13066 -207.119844)
			(xy 6.194693 -207.087523) (xy 6.261958 -207.062617) (xy 6.331599 -207.045442) (xy 6.402731 -207.036217)
			(xy 6.474449 -207.035058) (xy 6.545842 -207.041981) (xy 6.616002 -207.056897) (xy 6.684036 -207.079617)
			(xy 6.74908 -207.109852) (xy 6.810306 -207.147217) (xy 6.866937 -207.191238) (xy 6.918252 -207.241354)
			(xy 6.941312 -207.268826) (xy 6.958584 -207.289908) (xy 7.058914 -207.3402) (xy 7.670292 -207.3402)
			(xy 7.693358 -207.338986) (xy 7.738505 -207.329252) (xy 7.781151 -207.311521) (xy 7.819891 -207.286377)
			(xy 7.85345 -207.254647) (xy 7.880724 -207.217375) (xy 7.900815 -207.17579) (xy 7.913062 -207.131258)
			(xy 7.917061 -207.085247) (xy 7.912682 -207.03927) (xy 7.900067 -206.994842) (xy 7.890256 -206.973932)
			(xy 7.873903 -206.942828) (xy 7.847387 -206.877746) (xy 7.828213 -206.810137) (xy 7.816614 -206.740825)
			(xy 7.812733 -206.670656) (xy 7.816615 -206.600488) (xy 7.828215 -206.531176) (xy 7.84739 -206.463567)
			(xy 7.873906 -206.398486) (xy 7.890256 -206.36738) (xy 7.899943 -206.346585) (xy 7.912487 -206.302462)
			(xy 7.916918 -206.256805) (xy 7.913092 -206.211094) (xy 7.901132 -206.16681) (xy 7.881426 -206.125387)
			(xy 7.854613 -206.088168) (xy 7.821561 -206.05636) (xy 7.783342 -206.030993) (xy 7.741195 -206.012889)
			(xy 7.696484 -206.002635) (xy 7.673594 -206.001112) (xy 7.05866 -206.001112) (xy 6.958584 -206.051404)
			(xy 6.941312 -206.072486) (xy 6.918485 -206.099688) (xy 6.867739 -206.149364) (xy 6.811772 -206.193076)
			(xy 6.751282 -206.230276) (xy 6.687022 -206.260503) (xy 6.619793 -206.283379) (xy 6.550434 -206.298619)
			(xy 6.479808 -206.306033) (xy 6.408796 -206.305529) (xy 6.338282 -206.297113) (xy 6.269146 -206.28089)
			(xy 6.202249 -206.257062) (xy 6.138425 -206.225926) (xy 6.078469 -206.187871) (xy 6.023128 -206.14337)
			(xy 5.973092 -206.092977) (xy 5.928985 -206.037322) (xy 5.891355 -205.977097) (xy 5.860673 -205.913054)
			(xy 5.837321 -205.845989) (xy 5.821589 -205.77674) (xy 5.813673 -205.706169) (xy 5.813673 -205.635155)
			(xy 5.821588 -205.564583) (xy 5.83732 -205.495334) (xy 5.860672 -205.428269) (xy 5.891354 -205.364225)
			(xy 5.928983 -205.304) (xy 5.97309 -205.248345) (xy 6.023126 -205.197953) (xy 6.078466 -205.153451)
			(xy 6.138422 -205.115395) (xy 6.202247 -205.084259) (xy 6.269143 -205.060431) (xy 6.338279 -205.044208)
			(xy 6.408793 -205.035791) (xy 6.479805 -205.035287) (xy 6.550431 -205.042701) (xy 6.61979 -205.05794)
			(xy 6.687019 -205.080816) (xy 6.751279 -205.111042) (xy 6.811769 -205.148243) (xy 6.867737 -205.191953)
			(xy 6.918483 -205.24163) (xy 6.941312 -205.26883) (xy 6.958584 -205.289912) (xy 7.05866 -205.340204)
			(xy 7.673594 -205.340204) (xy 7.696501 -205.338718) (xy 7.741255 -205.328526) (xy 7.78345 -205.310461)
			(xy 7.821714 -205.28511) (xy 7.854802 -205.253298) (xy 7.881637 -205.216061) (xy 7.901347 -205.174608)
			(xy 7.91329 -205.13029) (xy 7.917079 -205.084546) (xy 7.912589 -205.038867) (xy 7.899966 -204.994737)
			(xy 7.890256 -204.973936) (xy 7.874473 -204.943961) (xy 7.848658 -204.881324) (xy 7.829654 -204.816297)
			(xy 7.817676 -204.749617) (xy 7.812861 -204.682041) (xy 7.815263 -204.614336) (xy 7.819644 -204.580744)
			(xy 7.823962 -204.551026) (xy 7.804912 -204.494384) (xy 7.311644 -204.001116) (xy 7.058914 -204.001116)
			(xy 6.958584 -204.051408) (xy 6.941312 -204.07249) (xy 6.918257 -204.099971) (xy 6.866942 -204.150096)
			(xy 6.81031 -204.194125) (xy 6.74908 -204.231499) (xy 6.684032 -204.261741) (xy 6.615993 -204.284467)
			(xy 6.545828 -204.299388) (xy 6.474428 -204.306315) (xy 6.402703 -204.305159) (xy 6.331565 -204.295935)
			(xy 6.261916 -204.278761) (xy 6.194645 -204.253854) (xy 6.130605 -204.221532) (xy 6.070612 -204.182205)
			(xy 6.015427 -204.136373) (xy 5.965754 -204.08462) (xy 5.922223 -204.027604) (xy 5.885389 -203.966049)
			(xy 5.855718 -203.900738) (xy 5.83359 -203.832502) (xy 5.819285 -203.762208) (xy 5.812985 -203.690751)
			(xy 5.81477 -203.619039) (xy 5.824617 -203.547984) (xy 5.842402 -203.478489) (xy 5.867898 -203.411439)
			(xy 5.900781 -203.347685) (xy 5.940633 -203.288039) (xy 5.986947 -203.233259) (xy 6.039133 -203.184041)
			(xy 6.067552 -203.162154) (xy 6.079081 -203.152969) (xy 6.097952 -203.130335) (xy 6.111119 -203.103972)
			(xy 6.117878 -203.075289) (xy 6.118352 -203.060554) (xy 6.118352 -202.901296) (xy 7.908798 -201.11085)
			(xy 7.919974 -201.025506) (xy 7.898384 -200.988168) (xy 7.880856 -200.956823) (xy 7.852183 -200.890977)
			(xy 7.831117 -200.822318) (xy 7.817925 -200.751721) (xy 7.812776 -200.680088) (xy 7.815736 -200.60833)
			(xy 7.826767 -200.537364) (xy 7.845728 -200.468094) (xy 7.872378 -200.401403) (xy 7.906376 -200.338142)
			(xy 7.94729 -200.279117) (xy 7.994598 -200.22508) (xy 8.047695 -200.176722) (xy 8.105906 -200.134658)
			(xy 8.168488 -200.099425) (xy 8.234644 -200.071473) (xy 8.303529 -200.051156) (xy 8.374265 -200.038735)
			(xy 8.44595 -200.034368) (xy 8.517671 -200.038111) (xy 8.588513 -200.049915) (xy 8.657572 -200.069631)
			(xy 8.723968 -200.097006) (xy 8.786855 -200.131693) (xy 8.84543 -200.173248) (xy 8.898947 -200.221142)
			(xy 8.946723 -200.274764) (xy 8.988149 -200.333431) (xy 9.022697 -200.396393) (xy 9.049927 -200.46285)
			(xy 9.069491 -200.531952) (xy 9.081139 -200.602819) (xy 9.084724 -200.674548) (xy 9.0802 -200.746224)
			(xy 9.074404 -200.781666) (xy 9.070964 -200.803609) (xy 9.070904 -200.848022) (xy 9.078566 -200.891769)
			(xy 9.093718 -200.933518) (xy 9.115898 -200.971996) (xy 9.14443 -201.006031) (xy 9.178446 -201.034588)
			(xy 9.216908 -201.056795) (xy 9.258646 -201.071977) (xy 9.302387 -201.079671) (xy 9.324594 -201.080116)
			(xy 9.571228 -201.080116) (xy 17.087596 -193.564002) (xy 17.098945 -193.551854) (xy 17.115532 -193.523058)
			(xy 17.124122 -193.490956) (xy 17.12468 -193.47434) (xy 17.12468 -141.975078) (xy 18.94332 -140.156438)
			(xy 18.94332 -133.99008) (xy 17.476978 -132.523738) (xy 17.461152 -132.50857) (xy 17.425293 -132.483362)
			(xy 17.385641 -132.464681) (xy 17.343372 -132.45308) (xy 17.299739 -132.448905) (xy 17.256037 -132.452278)
			(xy 17.213561 -132.463099) (xy 17.173573 -132.481049) (xy 17.137257 -132.505593) (xy 17.121124 -132.520436)
			(xy 17.091986 -132.547827) (xy 17.029067 -132.597195) (xy 16.961469 -132.639933) (xy 16.889887 -132.675601)
			(xy 16.81506 -132.703832) (xy 16.737758 -132.724335) (xy 16.658775 -132.736899) (xy 16.578927 -132.741395)
			(xy 16.499033 -132.737776) (xy 16.419918 -132.726079) (xy 16.342394 -132.706426) (xy 16.267262 -132.679019)
			(xy 16.195294 -132.644139) (xy 16.161004 -132.62356) (xy 16.141604 -132.612163) (xy 16.09975 -132.595659)
			(xy 16.055644 -132.586784) (xy 16.010664 -132.585816) (xy 15.966217 -132.592785) (xy 15.923692 -132.607473)
			(xy 15.884418 -132.62942) (xy 15.849624 -132.657942) (xy 15.820396 -132.692145) (xy 15.79765 -132.730961)
			(xy 15.782095 -132.773177) (xy 15.774218 -132.817472) (xy 15.773654 -132.839968) (xy 15.773654 -133.191504)
			(xy 15.223744 -133.741414) (xy 15.207814 -133.758058) (xy 15.181651 -133.795973) (xy 15.16275 -133.837983)
			(xy 15.151729 -133.882712) (xy 15.14895 -133.928694) (xy 15.154503 -133.974424) (xy 15.168206 -134.018405)
			(xy 15.189611 -134.059196) (xy 15.218016 -134.095462) (xy 15.252493 -134.126015) (xy 15.291911 -134.149854)
			(xy 15.33498 -134.166199) (xy 15.380289 -134.174515) (xy 15.403322 -134.174992) (xy 15.809722 -134.174992)
			(xy 15.869158 -134.140194) (xy 15.885922 -134.109968) (xy 15.905747 -134.075363) (xy 15.951361 -134.009937)
			(xy 16.003352 -133.949455) (xy 16.061187 -133.894534) (xy 16.124275 -133.845737) (xy 16.19197 -133.803564)
			(xy 16.263579 -133.768445) (xy 16.338369 -133.740741) (xy 16.415576 -133.720734) (xy 16.494409 -133.708629)
			(xy 16.574062 -133.704551) (xy 16.653719 -133.708541) (xy 16.732566 -133.720558) (xy 16.809795 -133.740479)
			(xy 16.884616 -133.7681) (xy 16.956264 -133.803139) (xy 17.024006 -133.845237) (xy 17.087147 -133.893964)
			(xy 17.145044 -133.94882) (xy 17.197102 -134.009245) (xy 17.242789 -134.07462) (xy 17.281637 -134.144276)
			(xy 17.31325 -134.2175) (xy 17.337303 -134.293544) (xy 17.353551 -134.371628) (xy 17.361827 -134.450955)
			(xy 17.362046 -134.530711) (xy 17.354207 -134.610082) (xy 17.338389 -134.688255) (xy 17.314755 -134.76443)
			(xy 17.299686 -134.801356) (xy 17.29122 -134.822533) (xy 17.281124 -134.867003) (xy 17.279124 -134.912561)
			(xy 17.285285 -134.957745) (xy 17.29941 -135.001104) (xy 17.321044 -135.041248) (xy 17.349495 -135.076886)
			(xy 17.383847 -135.106877) (xy 17.423 -135.130256) (xy 17.465696 -135.146274) (xy 17.510565 -135.154417)
			(xy 17.533366 -135.154924) (xy 17.731486 -135.154924) (xy 18.562828 -135.986266) (xy 18.562828 -137.700766)
			(xy 17.231106 -139.032742) (xy 17.220946 -139.120626) (xy 17.244314 -139.157964) (xy 17.264647 -139.19168)
			(xy 17.299242 -139.262412) (xy 17.326608 -139.336243) (xy 17.346474 -139.412434) (xy 17.35864 -139.490228)
			(xy 17.362986 -139.568847) (xy 17.359469 -139.647507) (xy 17.348122 -139.725425) (xy 17.329061 -139.801822)
			(xy 17.302473 -139.875936) (xy 17.268626 -139.947029) (xy 17.227856 -140.014391) (xy 17.18057 -140.077351)
			(xy 17.12724 -140.13528) (xy 17.068398 -140.1876) (xy 17.00463 -140.23379) (xy 16.936573 -140.273389)
			(xy 16.864906 -140.306003) (xy 16.790343 -140.331304) (xy 16.713627 -140.349042) (xy 16.635526 -140.35904)
			(xy 16.556816 -140.361197) (xy 16.478284 -140.355492) (xy 16.400712 -140.341982) (xy 16.324875 -140.320802)
			(xy 16.251529 -140.292163) (xy 16.181406 -140.256351) (xy 16.14805 -140.235432) (xy 16.133854 -140.226901)
			(xy 16.102354 -140.216714) (xy 16.069293 -140.214979) (xy 16.036899 -140.221815) (xy 16.007358 -140.23676)
			(xy 15.982659 -140.258807) (xy 15.96447 -140.286469) (xy 15.954015 -140.317882) (xy 15.952 -140.350927)
			(xy 15.954756 -140.367258) (xy 15.957634 -140.382718) (xy 15.960683 -140.414018) (xy 15.960852 -140.429742)
			(xy 15.960852 -142.06728) (xy 15.165832 -142.862554) (xy 15.165832 -146.505422) (xy 14.01953 -147.651724)
			(xy 14.01953 -170.861482) (xy 14.019954 -170.883195) (xy 14.027302 -170.925995) (xy 14.04182 -170.966922)
			(xy 14.063085 -171.004784) (xy 14.090479 -171.038479) (xy 14.123204 -171.067025) (xy 14.160306 -171.089591)
			(xy 14.200705 -171.10552) (xy 14.243224 -171.114347) (xy 14.286625 -171.115816) (xy 14.329643 -171.109884)
			(xy 14.350492 -171.103798) (xy 14.370462 -171.096683) (xy 14.411422 -171.085741) (xy 14.43228 -171.081954)
			(xy 14.443769 -171.080042) (xy 14.466894 -171.077246) (xy 14.478508 -171.076366) (xy 14.502293 -171.074188)
			(xy 14.548489 -171.062082) (xy 14.591614 -171.041567) (xy 14.630152 -171.013363) (xy 14.662749 -170.978462)
			(xy 14.688259 -170.93809) (xy 14.705785 -170.893666) (xy 14.714712 -170.846752) (xy 14.715236 -170.822874)
			(xy 14.715236 -170.692064) (xy 14.68755 -170.657266) (xy 14.669165 -170.633352) (xy 14.63817 -170.581605)
			(xy 14.61424 -170.526234) (xy 14.597791 -170.4682) (xy 14.589107 -170.408508) (xy 14.588339 -170.348192)
			(xy 14.595501 -170.288299) (xy 14.610467 -170.229864) (xy 14.63298 -170.173903) (xy 14.662648 -170.121383)
			(xy 14.698957 -170.073215) (xy 14.74128 -170.030234) (xy 14.788881 -169.993184) (xy 14.840936 -169.962708)
			(xy 14.896543 -169.939333) (xy 14.954739 -169.923466) (xy 15.014515 -169.91538) (xy 15.044674 -169.914824)
			(xy 15.0744 -169.915218) (xy 15.13337 -169.922757) (xy 15.190868 -169.937865) (xy 15.245926 -169.96029)
			(xy 15.297618 -169.989653) (xy 15.345074 -170.025461) (xy 15.387495 -170.067112) (xy 15.424167 -170.113903)
			(xy 15.454473 -170.165048) (xy 15.477904 -170.219685) (xy 15.494064 -170.276897) (xy 15.502682 -170.335718)
			(xy 15.503613 -170.395161) (xy 15.496841 -170.454224) (xy 15.48248 -170.511913) (xy 15.460772 -170.567258)
			(xy 15.432082 -170.619326) (xy 15.396893 -170.667243) (xy 15.376652 -170.689016) (xy 15.376652 -187.273184)
			(xy 11.407902 -191.241934) (xy 11.407902 -191.884554) (xy 9.315196 -193.97726) (xy 7.357364 -193.97726)
			(xy 6.92023 -194.414394) (xy 3.385058 -194.414394) (xy 2.789936 -193.819272) (xy 1.769364 -193.819272)
			(xy 1.53416 -194.054476) (xy 1.53416 -195.706339) (xy 3.31393 -195.706339) (xy 3.31393 -195.635017)
			(xy 3.321916 -195.564143) (xy 3.337786 -195.494608) (xy 3.361343 -195.427288) (xy 3.392288 -195.363029)
			(xy 3.430234 -195.302638) (xy 3.474703 -195.246876) (xy 3.525136 -195.196443) (xy 3.580898 -195.151974)
			(xy 3.641289 -195.114028) (xy 3.705548 -195.083083) (xy 3.772868 -195.059526) (xy 3.842403 -195.043656)
			(xy 3.913277 -195.03567) (xy 3.984599 -195.03567) (xy 4.055473 -195.043656) (xy 4.125008 -195.059526)
			(xy 4.192328 -195.083083) (xy 4.256587 -195.114028) (xy 4.316978 -195.151974) (xy 4.37274 -195.196443)
			(xy 4.423173 -195.246876) (xy 4.467642 -195.302638) (xy 4.505588 -195.363029) (xy 4.536533 -195.427288)
			(xy 4.56009 -195.494608) (xy 4.57596 -195.564143) (xy 4.583946 -195.635017) (xy 4.584446 -195.670678)
			(xy 4.583946 -195.706339) (xy 5.813798 -195.706339) (xy 5.813798 -195.635017) (xy 5.821784 -195.564143)
			(xy 5.837654 -195.494608) (xy 5.861211 -195.427288) (xy 5.892156 -195.363029) (xy 5.930102 -195.302638)
			(xy 5.974571 -195.246876) (xy 6.025004 -195.196443) (xy 6.080766 -195.151974) (xy 6.141157 -195.114028)
			(xy 6.205416 -195.083083) (xy 6.272736 -195.059526) (xy 6.342271 -195.043656) (xy 6.413145 -195.03567)
			(xy 6.484467 -195.03567) (xy 6.555341 -195.043656) (xy 6.624876 -195.059526) (xy 6.692196 -195.083083)
			(xy 6.756455 -195.114028) (xy 6.816846 -195.151974) (xy 6.872608 -195.196443) (xy 6.923041 -195.246876)
			(xy 6.96751 -195.302638) (xy 7.005456 -195.363029) (xy 7.036401 -195.427288) (xy 7.059958 -195.494608)
			(xy 7.075828 -195.564143) (xy 7.083814 -195.635017) (xy 7.084314 -195.670678) (xy 7.083814 -195.706339)
			(xy 7.075828 -195.777213) (xy 7.059958 -195.846748) (xy 7.036401 -195.914068) (xy 7.005456 -195.978327)
			(xy 6.96751 -196.038718) (xy 6.923041 -196.09448) (xy 6.872608 -196.144913) (xy 6.816846 -196.189382)
			(xy 6.756455 -196.227328) (xy 6.692196 -196.258273) (xy 6.624876 -196.28183) (xy 6.555341 -196.2977)
			(xy 6.484467 -196.305686) (xy 6.413145 -196.305686) (xy 6.342271 -196.2977) (xy 6.272736 -196.28183)
			(xy 6.205416 -196.258273) (xy 6.141157 -196.227328) (xy 6.080766 -196.189382) (xy 6.025004 -196.144913)
			(xy 5.974571 -196.09448) (xy 5.930102 -196.038718) (xy 5.892156 -195.978327) (xy 5.861211 -195.914068)
			(xy 5.837654 -195.846748) (xy 5.821784 -195.777213) (xy 5.813798 -195.706339) (xy 4.583946 -195.706339)
			(xy 4.57596 -195.777213) (xy 4.56009 -195.846748) (xy 4.536533 -195.914068) (xy 4.505588 -195.978327)
			(xy 4.467642 -196.038718) (xy 4.423173 -196.09448) (xy 4.37274 -196.144913) (xy 4.316978 -196.189382)
			(xy 4.256587 -196.227328) (xy 4.192328 -196.258273) (xy 4.125008 -196.28183) (xy 4.055473 -196.2977)
			(xy 3.984599 -196.305686) (xy 3.913277 -196.305686) (xy 3.842403 -196.2977) (xy 3.772868 -196.28183)
			(xy 3.705548 -196.258273) (xy 3.641289 -196.227328) (xy 3.580898 -196.189382) (xy 3.525136 -196.144913)
			(xy 3.474703 -196.09448) (xy 3.430234 -196.038718) (xy 3.392288 -195.978327) (xy 3.361343 -195.914068)
			(xy 3.337786 -195.846748) (xy 3.321916 -195.777213) (xy 3.31393 -195.706339) (xy 1.53416 -195.706339)
			(xy 1.53416 -195.795646) (xy 1.534617 -195.817923) (xy 1.542377 -195.861795) (xy 1.557673 -195.90364)
			(xy 1.580036 -195.942173) (xy 1.608781 -195.976214) (xy 1.643024 -196.004716) (xy 1.681715 -196.026806)
			(xy 1.723667 -196.041805) (xy 1.767593 -196.049254) (xy 1.812145 -196.048923) (xy 1.834134 -196.045328)
			(xy 1.869571 -196.039325) (xy 1.941277 -196.0344) (xy 2.013082 -196.037596) (xy 2.084068 -196.048872)
			(xy 2.153329 -196.068085) (xy 2.219979 -196.09499) (xy 2.283169 -196.129242) (xy 2.342091 -196.170405)
			(xy 2.395992 -196.217952) (xy 2.444186 -196.271277) (xy 2.486055 -196.329698) (xy 2.521067 -196.392471)
			(xy 2.548772 -196.458792) (xy 2.568819 -196.527816) (xy 2.58095 -196.598661) (xy 2.585011 -196.670422)
			(xy 2.582993 -196.706083) (xy 7.813794 -196.706083) (xy 7.813794 -196.634761) (xy 7.82178 -196.563887)
			(xy 7.83765 -196.494352) (xy 7.861207 -196.427032) (xy 7.892152 -196.362773) (xy 7.930098 -196.302382)
			(xy 7.974567 -196.24662) (xy 8.025 -196.196187) (xy 8.080762 -196.151718) (xy 8.141153 -196.113772)
			(xy 8.205412 -196.082827) (xy 8.272732 -196.05927) (xy 8.342267 -196.0434) (xy 8.413141 -196.035414)
			(xy 8.484463 -196.035414) (xy 8.555337 -196.0434) (xy 8.624872 -196.05927) (xy 8.692192 -196.082827)
			(xy 8.756451 -196.113772) (xy 8.816842 -196.151718) (xy 8.872604 -196.196187) (xy 8.923037 -196.24662)
			(xy 8.967506 -196.302382) (xy 9.005452 -196.362773) (xy 9.036397 -196.427032) (xy 9.059954 -196.494352)
			(xy 9.075824 -196.563887) (xy 9.08381 -196.634761) (xy 9.08431 -196.670422) (xy 9.08381 -196.706083)
			(xy 9.075824 -196.776957) (xy 9.059954 -196.846492) (xy 9.036397 -196.913812) (xy 9.005452 -196.978071)
			(xy 8.967506 -197.038462) (xy 8.923037 -197.094224) (xy 8.872604 -197.144657) (xy 8.816842 -197.189126)
			(xy 8.756451 -197.227072) (xy 8.692192 -197.258017) (xy 8.624872 -197.281574) (xy 8.555337 -197.297444)
			(xy 8.484463 -197.30543) (xy 8.413141 -197.30543) (xy 8.342267 -197.297444) (xy 8.272732 -197.281574)
			(xy 8.205412 -197.258017) (xy 8.141153 -197.227072) (xy 8.080762 -197.189126) (xy 8.025 -197.144657)
			(xy 7.974567 -197.094224) (xy 7.930098 -197.038462) (xy 7.892152 -196.978071) (xy 7.861207 -196.913812)
			(xy 7.83765 -196.846492) (xy 7.82178 -196.776957) (xy 7.813794 -196.706083) (xy 2.582993 -196.706083)
			(xy 2.58095 -196.742183) (xy 2.568819 -196.813028) (xy 2.548772 -196.882052) (xy 2.521067 -196.948373)
			(xy 2.486055 -197.011146) (xy 2.444186 -197.069567) (xy 2.395992 -197.122892) (xy 2.342091 -197.170439)
			(xy 2.283169 -197.211602) (xy 2.219979 -197.245854) (xy 2.153329 -197.272759) (xy 2.084068 -197.291972)
			(xy 2.013082 -197.303248) (xy 1.941277 -197.306444) (xy 1.869571 -197.301519) (xy 1.834134 -197.295516)
			(xy 1.812147 -197.291945) (xy 1.767607 -197.29165) (xy 1.723697 -197.299123) (xy 1.681762 -197.314134)
			(xy 1.643085 -197.336224) (xy 1.60885 -197.364716) (xy 1.580104 -197.39874) (xy 1.557728 -197.437252)
			(xy 1.542407 -197.479075) (xy 1.534609 -197.522928) (xy 1.53416 -197.545198) (xy 1.53416 -197.706335)
			(xy 3.31393 -197.706335) (xy 3.31393 -197.635013) (xy 3.321916 -197.564139) (xy 3.337786 -197.494604)
			(xy 3.361343 -197.427284) (xy 3.392288 -197.363025) (xy 3.430234 -197.302634) (xy 3.474703 -197.246872)
			(xy 3.525136 -197.196439) (xy 3.580898 -197.15197) (xy 3.641289 -197.114024) (xy 3.705548 -197.083079)
			(xy 3.772868 -197.059522) (xy 3.842403 -197.043652) (xy 3.913277 -197.035666) (xy 3.984599 -197.035666)
			(xy 4.055473 -197.043652) (xy 4.125008 -197.059522) (xy 4.192328 -197.083079) (xy 4.256587 -197.114024)
			(xy 4.316978 -197.15197) (xy 4.37274 -197.196439) (xy 4.423173 -197.246872) (xy 4.467642 -197.302634)
			(xy 4.505588 -197.363025) (xy 4.536533 -197.427284) (xy 4.56009 -197.494604) (xy 4.57596 -197.564139)
			(xy 4.583946 -197.635013) (xy 4.584446 -197.670674) (xy 4.583946 -197.706335) (xy 5.813798 -197.706335)
			(xy 5.813798 -197.635013) (xy 5.821784 -197.564139) (xy 5.837654 -197.494604) (xy 5.861211 -197.427284)
			(xy 5.892156 -197.363025) (xy 5.930102 -197.302634) (xy 5.974571 -197.246872) (xy 6.025004 -197.196439)
			(xy 6.080766 -197.15197) (xy 6.141157 -197.114024) (xy 6.205416 -197.083079) (xy 6.272736 -197.059522)
			(xy 6.342271 -197.043652) (xy 6.413145 -197.035666) (xy 6.484467 -197.035666) (xy 6.555341 -197.043652)
			(xy 6.624876 -197.059522) (xy 6.692196 -197.083079) (xy 6.756455 -197.114024) (xy 6.816846 -197.15197)
			(xy 6.872608 -197.196439) (xy 6.923041 -197.246872) (xy 6.96751 -197.302634) (xy 7.005456 -197.363025)
			(xy 7.036401 -197.427284) (xy 7.059958 -197.494604) (xy 7.075828 -197.564139) (xy 7.083814 -197.635013)
			(xy 7.084314 -197.670674) (xy 7.083814 -197.706335) (xy 7.075828 -197.777209) (xy 7.059958 -197.846744)
			(xy 7.036401 -197.914064) (xy 7.005456 -197.978323) (xy 6.96751 -198.038714) (xy 6.923041 -198.094476)
			(xy 6.872608 -198.144909) (xy 6.816846 -198.189378) (xy 6.756455 -198.227324) (xy 6.692196 -198.258269)
			(xy 6.624876 -198.281826) (xy 6.555341 -198.297696) (xy 6.484467 -198.305682) (xy 6.413145 -198.305682)
			(xy 6.342271 -198.297696) (xy 6.272736 -198.281826) (xy 6.205416 -198.258269) (xy 6.141157 -198.227324)
			(xy 6.080766 -198.189378) (xy 6.025004 -198.144909) (xy 5.974571 -198.094476) (xy 5.930102 -198.038714)
			(xy 5.892156 -197.978323) (xy 5.861211 -197.914064) (xy 5.837654 -197.846744) (xy 5.821784 -197.777209)
			(xy 5.813798 -197.706335) (xy 4.583946 -197.706335) (xy 4.57596 -197.777209) (xy 4.56009 -197.846744)
			(xy 4.536533 -197.914064) (xy 4.505588 -197.978323) (xy 4.467642 -198.038714) (xy 4.423173 -198.094476)
			(xy 4.37274 -198.144909) (xy 4.316978 -198.189378) (xy 4.256587 -198.227324) (xy 4.192328 -198.258269)
			(xy 4.125008 -198.281826) (xy 4.055473 -198.297696) (xy 3.984599 -198.305682) (xy 3.913277 -198.305682)
			(xy 3.842403 -198.297696) (xy 3.772868 -198.281826) (xy 3.705548 -198.258269) (xy 3.641289 -198.227324)
			(xy 3.580898 -198.189378) (xy 3.525136 -198.144909) (xy 3.474703 -198.094476) (xy 3.430234 -198.038714)
			(xy 3.392288 -197.978323) (xy 3.361343 -197.914064) (xy 3.337786 -197.846744) (xy 3.321916 -197.777209)
			(xy 3.31393 -197.706335) (xy 1.53416 -197.706335) (xy 1.53416 -197.795642) (xy 1.534618 -197.817918)
			(xy 1.542378 -197.861789) (xy 1.557675 -197.903633) (xy 1.580038 -197.942166) (xy 1.608783 -197.976206)
			(xy 1.643025 -198.004707) (xy 1.681716 -198.026796) (xy 1.723668 -198.041795) (xy 1.767593 -198.049244)
			(xy 1.812144 -198.048914) (xy 1.834134 -198.045324) (xy 1.869571 -198.039321) (xy 1.941277 -198.034396)
			(xy 2.013082 -198.037592) (xy 2.084068 -198.048868) (xy 2.153329 -198.068081) (xy 2.219979 -198.094986)
			(xy 2.283169 -198.129238) (xy 2.342091 -198.170401) (xy 2.395992 -198.217948) (xy 2.444186 -198.271273)
			(xy 2.486055 -198.329694) (xy 2.521067 -198.392467) (xy 2.548772 -198.458788) (xy 2.568819 -198.527812)
			(xy 2.58095 -198.598657) (xy 2.585011 -198.670418) (xy 2.582993 -198.706079) (xy 7.813794 -198.706079)
			(xy 7.813794 -198.634757) (xy 7.82178 -198.563883) (xy 7.83765 -198.494348) (xy 7.861207 -198.427028)
			(xy 7.892152 -198.362769) (xy 7.930098 -198.302378) (xy 7.974567 -198.246616) (xy 8.025 -198.196183)
			(xy 8.080762 -198.151714) (xy 8.141153 -198.113768) (xy 8.205412 -198.082823) (xy 8.272732 -198.059266)
			(xy 8.342267 -198.043396) (xy 8.413141 -198.03541) (xy 8.484463 -198.03541) (xy 8.555337 -198.043396)
			(xy 8.624872 -198.059266) (xy 8.692192 -198.082823) (xy 8.756451 -198.113768) (xy 8.816842 -198.151714)
			(xy 8.872604 -198.196183) (xy 8.923037 -198.246616) (xy 8.967506 -198.302378) (xy 9.005452 -198.362769)
			(xy 9.036397 -198.427028) (xy 9.059954 -198.494348) (xy 9.075824 -198.563883) (xy 9.08381 -198.634757)
			(xy 9.08431 -198.670418) (xy 9.08381 -198.706079) (xy 9.075824 -198.776953) (xy 9.059954 -198.846488)
			(xy 9.036397 -198.913808) (xy 9.005452 -198.978067) (xy 8.967506 -199.038458) (xy 8.923037 -199.09422)
			(xy 8.872604 -199.144653) (xy 8.816842 -199.189122) (xy 8.756451 -199.227068) (xy 8.692192 -199.258013)
			(xy 8.624872 -199.28157) (xy 8.555337 -199.29744) (xy 8.484463 -199.305426) (xy 8.413141 -199.305426)
			(xy 8.342267 -199.29744) (xy 8.272732 -199.28157) (xy 8.205412 -199.258013) (xy 8.141153 -199.227068)
			(xy 8.080762 -199.189122) (xy 8.025 -199.144653) (xy 7.974567 -199.09422) (xy 7.930098 -199.038458)
			(xy 7.892152 -198.978067) (xy 7.861207 -198.913808) (xy 7.83765 -198.846488) (xy 7.82178 -198.776953)
			(xy 7.813794 -198.706079) (xy 2.582993 -198.706079) (xy 2.58095 -198.742179) (xy 2.568819 -198.813024)
			(xy 2.548772 -198.882048) (xy 2.521067 -198.948369) (xy 2.486055 -199.011142) (xy 2.444186 -199.069563)
			(xy 2.395992 -199.122888) (xy 2.342091 -199.170435) (xy 2.283169 -199.211598) (xy 2.219979 -199.24585)
			(xy 2.153329 -199.272755) (xy 2.084068 -199.291968) (xy 2.013082 -199.303244) (xy 1.941277 -199.30644)
			(xy 1.869571 -199.301515) (xy 1.834134 -199.295512) (xy 1.812147 -199.291941) (xy 1.767607 -199.291646)
			(xy 1.723697 -199.299119) (xy 1.681761 -199.31413) (xy 1.643084 -199.336219) (xy 1.608848 -199.364712)
			(xy 1.580102 -199.398735) (xy 1.557726 -199.437248) (xy 1.542404 -199.479071) (xy 1.534606 -199.522924)
			(xy 1.53416 -199.545194) (xy 1.53416 -199.706331) (xy 3.31393 -199.706331) (xy 3.31393 -199.635009)
			(xy 3.321916 -199.564135) (xy 3.337786 -199.4946) (xy 3.361343 -199.42728) (xy 3.392288 -199.363021)
			(xy 3.430234 -199.30263) (xy 3.474703 -199.246868) (xy 3.525136 -199.196435) (xy 3.580898 -199.151966)
			(xy 3.641289 -199.11402) (xy 3.705548 -199.083075) (xy 3.772868 -199.059518) (xy 3.842403 -199.043648)
			(xy 3.913277 -199.035662) (xy 3.984599 -199.035662) (xy 4.055473 -199.043648) (xy 4.125008 -199.059518)
			(xy 4.192328 -199.083075) (xy 4.256587 -199.11402) (xy 4.316978 -199.151966) (xy 4.37274 -199.196435)
			(xy 4.423173 -199.246868) (xy 4.467642 -199.30263) (xy 4.505588 -199.363021) (xy 4.536533 -199.42728)
			(xy 4.56009 -199.4946) (xy 4.57596 -199.564135) (xy 4.583946 -199.635009) (xy 4.584446 -199.67067)
			(xy 4.583946 -199.706331) (xy 5.813798 -199.706331) (xy 5.813798 -199.635009) (xy 5.821784 -199.564135)
			(xy 5.837654 -199.4946) (xy 5.861211 -199.42728) (xy 5.892156 -199.363021) (xy 5.930102 -199.30263)
			(xy 5.974571 -199.246868) (xy 6.025004 -199.196435) (xy 6.080766 -199.151966) (xy 6.141157 -199.11402)
			(xy 6.205416 -199.083075) (xy 6.272736 -199.059518) (xy 6.342271 -199.043648) (xy 6.413145 -199.035662)
			(xy 6.484467 -199.035662) (xy 6.555341 -199.043648) (xy 6.624876 -199.059518) (xy 6.692196 -199.083075)
			(xy 6.756455 -199.11402) (xy 6.816846 -199.151966) (xy 6.872608 -199.196435) (xy 6.923041 -199.246868)
			(xy 6.96751 -199.30263) (xy 7.005456 -199.363021) (xy 7.036401 -199.42728) (xy 7.059958 -199.4946)
			(xy 7.075828 -199.564135) (xy 7.083814 -199.635009) (xy 7.084314 -199.67067) (xy 7.083814 -199.706331)
			(xy 7.075828 -199.777205) (xy 7.059958 -199.84674) (xy 7.036401 -199.91406) (xy 7.005456 -199.978319)
			(xy 6.96751 -200.03871) (xy 6.923041 -200.094472) (xy 6.872608 -200.144905) (xy 6.816846 -200.189374)
			(xy 6.756455 -200.22732) (xy 6.692196 -200.258265) (xy 6.624876 -200.281822) (xy 6.555341 -200.297692)
			(xy 6.484467 -200.305678) (xy 6.413145 -200.305678) (xy 6.342271 -200.297692) (xy 6.272736 -200.281822)
			(xy 6.205416 -200.258265) (xy 6.141157 -200.22732) (xy 6.080766 -200.189374) (xy 6.025004 -200.144905)
			(xy 5.974571 -200.094472) (xy 5.930102 -200.03871) (xy 5.892156 -199.978319) (xy 5.861211 -199.91406)
			(xy 5.837654 -199.84674) (xy 5.821784 -199.777205) (xy 5.813798 -199.706331) (xy 4.583946 -199.706331)
			(xy 4.57596 -199.777205) (xy 4.56009 -199.84674) (xy 4.536533 -199.91406) (xy 4.505588 -199.978319)
			(xy 4.467642 -200.03871) (xy 4.423173 -200.094472) (xy 4.37274 -200.144905) (xy 4.316978 -200.189374)
			(xy 4.256587 -200.22732) (xy 4.192328 -200.258265) (xy 4.125008 -200.281822) (xy 4.055473 -200.297692)
			(xy 3.984599 -200.305678) (xy 3.913277 -200.305678) (xy 3.842403 -200.297692) (xy 3.772868 -200.281822)
			(xy 3.705548 -200.258265) (xy 3.641289 -200.22732) (xy 3.580898 -200.189374) (xy 3.525136 -200.144905)
			(xy 3.474703 -200.094472) (xy 3.430234 -200.03871) (xy 3.392288 -199.978319) (xy 3.361343 -199.91406)
			(xy 3.337786 -199.84674) (xy 3.321916 -199.777205) (xy 3.31393 -199.706331) (xy 1.53416 -199.706331)
			(xy 1.53416 -199.795638) (xy 1.534617 -199.817915) (xy 1.542377 -199.861786) (xy 1.557674 -199.903631)
			(xy 1.580037 -199.942164) (xy 1.608781 -199.976204) (xy 1.643024 -200.004706) (xy 1.681715 -200.026796)
			(xy 1.723667 -200.041795) (xy 1.767593 -200.049244) (xy 1.812144 -200.048913) (xy 1.834134 -200.04532)
			(xy 1.869571 -200.039317) (xy 1.941277 -200.034392) (xy 2.013082 -200.037588) (xy 2.084068 -200.048864)
			(xy 2.153329 -200.068077) (xy 2.219979 -200.094982) (xy 2.283169 -200.129234) (xy 2.342091 -200.170397)
			(xy 2.395992 -200.217944) (xy 2.444186 -200.271269) (xy 2.486055 -200.32969) (xy 2.521067 -200.392463)
			(xy 2.548772 -200.458784) (xy 2.568819 -200.527808) (xy 2.58095 -200.598653) (xy 2.585011 -200.670414)
			(xy 2.58095 -200.742175) (xy 2.568819 -200.81302) (xy 2.548772 -200.882044) (xy 2.521067 -200.948365)
			(xy 2.486055 -201.011138) (xy 2.444186 -201.069559) (xy 2.395992 -201.122884) (xy 2.342091 -201.170431)
			(xy 2.283169 -201.211594) (xy 2.219979 -201.245846) (xy 2.153329 -201.272751) (xy 2.084068 -201.291964)
			(xy 2.013082 -201.30324) (xy 1.941277 -201.306436) (xy 1.869571 -201.301511) (xy 1.834134 -201.295508)
			(xy 1.812147 -201.291937) (xy 1.767606 -201.291642) (xy 1.723696 -201.299115) (xy 1.681761 -201.314126)
			(xy 1.643083 -201.336215) (xy 1.608847 -201.364708) (xy 1.580101 -201.398731) (xy 1.557724 -201.437244)
			(xy 1.542401 -201.479066) (xy 1.534602 -201.52292) (xy 1.53416 -201.54519) (xy 1.53416 -201.795634)
			(xy 1.534618 -201.81791) (xy 1.542379 -201.861781) (xy 1.557675 -201.903625) (xy 1.580039 -201.942157)
			(xy 1.608783 -201.976196) (xy 1.643026 -202.004698) (xy 1.681717 -202.026786) (xy 1.723668 -202.041785)
			(xy 1.767593 -202.049234) (xy 1.812144 -202.048904) (xy 1.834134 -202.045316) (xy 1.869571 -202.039313)
			(xy 1.941277 -202.034388) (xy 2.013082 -202.037584) (xy 2.084068 -202.04886) (xy 2.153329 -202.068073)
			(xy 2.219979 -202.094978) (xy 2.283169 -202.12923) (xy 2.342091 -202.170393) (xy 2.395992 -202.21794)
			(xy 2.444186 -202.271265) (xy 2.486055 -202.329686) (xy 2.521067 -202.392459) (xy 2.548772 -202.45878)
			(xy 2.568819 -202.527804) (xy 2.58095 -202.598649) (xy 2.585011 -202.67041) (xy 2.58095 -202.742171)
			(xy 2.568819 -202.813016) (xy 2.548772 -202.88204) (xy 2.521067 -202.948361) (xy 2.486055 -203.011134)
			(xy 2.444186 -203.069555) (xy 2.395992 -203.12288) (xy 2.342091 -203.170427) (xy 2.283169 -203.21159)
			(xy 2.219979 -203.245842) (xy 2.153329 -203.272747) (xy 2.084068 -203.29196) (xy 2.013082 -203.303236)
			(xy 1.941277 -203.306432) (xy 1.869571 -203.301507) (xy 1.834134 -203.295504) (xy 1.812147 -203.291933)
			(xy 1.767606 -203.291638) (xy 1.723696 -203.299111) (xy 1.68176 -203.314122) (xy 1.643082 -203.336211)
			(xy 1.608845 -203.364704) (xy 1.580099 -203.398727) (xy 1.557721 -203.437239) (xy 1.542398 -203.479062)
			(xy 1.534599 -203.522916) (xy 1.53416 -203.545186) (xy 1.53416 -203.706323) (xy 3.31393 -203.706323)
			(xy 3.31393 -203.635001) (xy 3.321916 -203.564127) (xy 3.337786 -203.494592) (xy 3.361343 -203.427272)
			(xy 3.392288 -203.363013) (xy 3.430234 -203.302622) (xy 3.474703 -203.24686) (xy 3.525136 -203.196427)
			(xy 3.580898 -203.151958) (xy 3.641289 -203.114012) (xy 3.705548 -203.083067) (xy 3.772868 -203.05951)
			(xy 3.842403 -203.04364) (xy 3.913277 -203.035654) (xy 3.984599 -203.035654) (xy 4.055473 -203.04364)
			(xy 4.125008 -203.05951) (xy 4.192328 -203.083067) (xy 4.256587 -203.114012) (xy 4.316978 -203.151958)
			(xy 4.37274 -203.196427) (xy 4.423173 -203.24686) (xy 4.467642 -203.302622) (xy 4.505588 -203.363013)
			(xy 4.536533 -203.427272) (xy 4.56009 -203.494592) (xy 4.57596 -203.564127) (xy 4.583946 -203.635001)
			(xy 4.584446 -203.670662) (xy 4.583946 -203.706323) (xy 4.57596 -203.777197) (xy 4.56009 -203.846732)
			(xy 4.536533 -203.914052) (xy 4.505588 -203.978311) (xy 4.467642 -204.038702) (xy 4.423173 -204.094464)
			(xy 4.37274 -204.144897) (xy 4.316978 -204.189366) (xy 4.256587 -204.227312) (xy 4.192328 -204.258257)
			(xy 4.125008 -204.281814) (xy 4.055473 -204.297684) (xy 3.984599 -204.30567) (xy 3.913277 -204.30567)
			(xy 3.842403 -204.297684) (xy 3.772868 -204.281814) (xy 3.705548 -204.258257) (xy 3.641289 -204.227312)
			(xy 3.580898 -204.189366) (xy 3.525136 -204.144897) (xy 3.474703 -204.094464) (xy 3.430234 -204.038702)
			(xy 3.392288 -203.978311) (xy 3.361343 -203.914052) (xy 3.337786 -203.846732) (xy 3.321916 -203.777197)
			(xy 3.31393 -203.706323) (xy 1.53416 -203.706323) (xy 1.53416 -203.795884) (xy 1.534618 -203.81816)
			(xy 1.542379 -203.862031) (xy 1.557675 -203.903875) (xy 1.580039 -203.942407) (xy 1.608783 -203.976446)
			(xy 1.643026 -204.004948) (xy 1.681717 -204.027036) (xy 1.723668 -204.042035) (xy 1.767593 -204.049484)
			(xy 1.812144 -204.049154) (xy 1.834134 -204.045566) (xy 1.869571 -204.039563) (xy 1.941277 -204.034638)
			(xy 2.013082 -204.037834) (xy 2.084068 -204.04911) (xy 2.153329 -204.068323) (xy 2.219979 -204.095228)
			(xy 2.283169 -204.12948) (xy 2.342091 -204.170643) (xy 2.395992 -204.21819) (xy 2.444186 -204.271515)
			(xy 2.486055 -204.329936) (xy 2.521067 -204.392709) (xy 2.548772 -204.45903) (xy 2.568819 -204.528054)
			(xy 2.58095 -204.598899) (xy 2.585011 -204.67066) (xy 2.58095 -204.742421) (xy 2.568819 -204.813266)
			(xy 2.548772 -204.88229) (xy 2.521067 -204.948611) (xy 2.486055 -205.011384) (xy 2.444186 -205.069805)
			(xy 2.395992 -205.12313) (xy 2.342091 -205.170677) (xy 2.283169 -205.21184) (xy 2.219979 -205.246092)
			(xy 2.153329 -205.272997) (xy 2.084068 -205.29221) (xy 2.013082 -205.303486) (xy 1.941277 -205.306682)
			(xy 1.869571 -205.301757) (xy 1.834134 -205.295754) (xy 1.812148 -205.292182) (xy 1.76761 -205.291887)
			(xy 1.723703 -205.29936) (xy 1.68177 -205.314371) (xy 1.643095 -205.336462) (xy 1.608863 -205.364955)
			(xy 1.580122 -205.398979) (xy 1.557751 -205.437492) (xy 1.542435 -205.479315) (xy 1.534644 -205.523167)
			(xy 1.53416 -205.545436) (xy 1.53416 -205.706319) (xy 3.31393 -205.706319) (xy 3.31393 -205.634997)
			(xy 3.321916 -205.564123) (xy 3.337786 -205.494588) (xy 3.361343 -205.427268) (xy 3.392288 -205.363009)
			(xy 3.430234 -205.302618) (xy 3.474703 -205.246856) (xy 3.525136 -205.196423) (xy 3.580898 -205.151954)
			(xy 3.641289 -205.114008) (xy 3.705548 -205.083063) (xy 3.772868 -205.059506) (xy 3.842403 -205.043636)
			(xy 3.913277 -205.03565) (xy 3.984599 -205.03565) (xy 4.055473 -205.043636) (xy 4.125008 -205.059506)
			(xy 4.192328 -205.083063) (xy 4.256587 -205.114008) (xy 4.316978 -205.151954) (xy 4.37274 -205.196423)
			(xy 4.423173 -205.246856) (xy 4.467642 -205.302618) (xy 4.505588 -205.363009) (xy 4.536533 -205.427268)
			(xy 4.56009 -205.494588) (xy 4.57596 -205.564123) (xy 4.583946 -205.634997) (xy 4.584446 -205.670658)
			(xy 4.583946 -205.706319) (xy 4.57596 -205.777193) (xy 4.56009 -205.846728) (xy 4.536533 -205.914048)
			(xy 4.505588 -205.978307) (xy 4.467642 -206.038698) (xy 4.423173 -206.09446) (xy 4.37274 -206.144893)
			(xy 4.316978 -206.189362) (xy 4.256587 -206.227308) (xy 4.192328 -206.258253) (xy 4.125008 -206.28181)
			(xy 4.055473 -206.29768) (xy 3.984599 -206.305666) (xy 3.913277 -206.305666) (xy 3.842403 -206.29768)
			(xy 3.772868 -206.28181) (xy 3.705548 -206.258253) (xy 3.641289 -206.227308) (xy 3.580898 -206.189362)
			(xy 3.525136 -206.144893) (xy 3.474703 -206.09446) (xy 3.430234 -206.038698) (xy 3.392288 -205.978307)
			(xy 3.361343 -205.914048) (xy 3.337786 -205.846728) (xy 3.321916 -205.777193) (xy 3.31393 -205.706319)
			(xy 1.53416 -205.706319) (xy 1.53416 -205.79588) (xy 1.534617 -205.818156) (xy 1.542378 -205.862028)
			(xy 1.557674 -205.903872) (xy 1.580038 -205.942405) (xy 1.608782 -205.976445) (xy 1.643025 -206.004947)
			(xy 1.681716 -206.027036) (xy 1.723667 -206.042035) (xy 1.767593 -206.049484) (xy 1.812144 -206.049153)
			(xy 1.834134 -206.045562) (xy 1.869571 -206.039559) (xy 1.941277 -206.034634) (xy 2.013082 -206.03783)
			(xy 2.084068 -206.049106) (xy 2.153329 -206.068319) (xy 2.219979 -206.095224) (xy 2.283169 -206.129476)
			(xy 2.342091 -206.170639) (xy 2.395992 -206.218186) (xy 2.444186 -206.271511) (xy 2.486055 -206.329932)
			(xy 2.521067 -206.392705) (xy 2.548772 -206.459026) (xy 2.568819 -206.52805) (xy 2.58095 -206.598895)
			(xy 2.585011 -206.670656) (xy 2.58095 -206.742417) (xy 2.568819 -206.813262) (xy 2.548772 -206.882286)
			(xy 2.521067 -206.948607) (xy 2.486055 -207.01138) (xy 2.444186 -207.069801) (xy 2.395992 -207.123126)
			(xy 2.342091 -207.170673) (xy 2.283169 -207.211836) (xy 2.219979 -207.246088) (xy 2.153329 -207.272993)
			(xy 2.084068 -207.292206) (xy 2.013082 -207.303482) (xy 1.941277 -207.306678) (xy 1.869571 -207.301753)
			(xy 1.834134 -207.29575) (xy 1.812148 -207.292178) (xy 1.76761 -207.291883) (xy 1.723702 -207.299356)
			(xy 1.681769 -207.314367) (xy 1.643094 -207.336458) (xy 1.608862 -207.364951) (xy 1.58012 -207.398975)
			(xy 1.557748 -207.437488) (xy 1.542432 -207.479311) (xy 1.53464 -207.523163) (xy 1.53416 -207.545432)
			(xy 1.53416 -207.706315) (xy 3.31393 -207.706315) (xy 3.31393 -207.634993) (xy 3.321916 -207.564119)
			(xy 3.337786 -207.494584) (xy 3.361343 -207.427264) (xy 3.392288 -207.363005) (xy 3.430234 -207.302614)
			(xy 3.474703 -207.246852) (xy 3.525136 -207.196419) (xy 3.580898 -207.15195) (xy 3.641289 -207.114004)
			(xy 3.705548 -207.083059) (xy 3.772868 -207.059502) (xy 3.842403 -207.043632) (xy 3.913277 -207.035646)
			(xy 3.984599 -207.035646) (xy 4.055473 -207.043632) (xy 4.125008 -207.059502) (xy 4.192328 -207.083059)
			(xy 4.256587 -207.114004) (xy 4.316978 -207.15195) (xy 4.37274 -207.196419) (xy 4.423173 -207.246852)
			(xy 4.467642 -207.302614) (xy 4.505588 -207.363005) (xy 4.536533 -207.427264) (xy 4.56009 -207.494584)
			(xy 4.57596 -207.564119) (xy 4.583946 -207.634993) (xy 4.584446 -207.670654) (xy 4.583946 -207.706315)
			(xy 4.57596 -207.777189) (xy 4.56009 -207.846724) (xy 4.536533 -207.914044) (xy 4.505588 -207.978303)
			(xy 4.467642 -208.038694) (xy 4.423173 -208.094456) (xy 4.37274 -208.144889) (xy 4.316978 -208.189358)
			(xy 4.256587 -208.227304) (xy 4.192328 -208.258249) (xy 4.125008 -208.281806) (xy 4.055473 -208.297676)
			(xy 3.984599 -208.305662) (xy 3.913277 -208.305662) (xy 3.842403 -208.297676) (xy 3.772868 -208.281806)
			(xy 3.705548 -208.258249) (xy 3.641289 -208.227304) (xy 3.580898 -208.189358) (xy 3.525136 -208.144889)
			(xy 3.474703 -208.094456) (xy 3.430234 -208.038694) (xy 3.392288 -207.978303) (xy 3.361343 -207.914044)
			(xy 3.337786 -207.846724) (xy 3.321916 -207.777189) (xy 3.31393 -207.706315) (xy 1.53416 -207.706315)
			(xy 1.53416 -207.795876) (xy 1.534617 -207.818153) (xy 1.542377 -207.862025) (xy 1.557673 -207.90387)
			(xy 1.580036 -207.942403) (xy 1.608781 -207.976444) (xy 1.643024 -208.004946) (xy 1.681715 -208.027036)
			(xy 1.723667 -208.042035) (xy 1.767593 -208.049484) (xy 1.812145 -208.049153) (xy 1.834134 -208.045558)
			(xy 1.869571 -208.039555) (xy 1.941277 -208.03463) (xy 2.013082 -208.037826) (xy 2.084068 -208.049102)
			(xy 2.153329 -208.068315) (xy 2.219979 -208.09522) (xy 2.283169 -208.129472) (xy 2.342091 -208.170635)
			(xy 2.395992 -208.218182) (xy 2.444186 -208.271507) (xy 2.486055 -208.329928) (xy 2.521067 -208.392701)
			(xy 2.548772 -208.459022) (xy 2.568819 -208.528046) (xy 2.58095 -208.598891) (xy 2.585011 -208.670652)
			(xy 2.58095 -208.742413) (xy 2.568819 -208.813258) (xy 2.548772 -208.882282) (xy 2.521067 -208.948603)
			(xy 2.486055 -209.011376) (xy 2.444186 -209.069797) (xy 2.395992 -209.123122) (xy 2.342091 -209.170669)
			(xy 2.283169 -209.211832) (xy 2.219979 -209.246084) (xy 2.153329 -209.272989) (xy 2.084068 -209.292202)
			(xy 2.013082 -209.303478) (xy 1.941277 -209.306674) (xy 1.869571 -209.301749) (xy 1.834134 -209.295746)
			(xy 1.812148 -209.292174) (xy 1.76761 -209.291879) (xy 1.723702 -209.299352) (xy 1.681768 -209.314363)
			(xy 1.643093 -209.336454) (xy 1.608861 -209.364947) (xy 1.580118 -209.398971) (xy 1.557746 -209.437484)
			(xy 1.542429 -209.479306) (xy 1.534636 -209.523159) (xy 1.53416 -209.545428) (xy 1.53416 -209.795872)
			(xy 1.534618 -209.818148) (xy 1.542378 -209.862019) (xy 1.557675 -209.903863) (xy 1.580038 -209.942396)
			(xy 1.608783 -209.976436) (xy 1.643025 -210.004937) (xy 1.681716 -210.027026) (xy 1.723668 -210.042025)
			(xy 1.767593 -210.049474) (xy 1.812144 -210.049144) (xy 1.834134 -210.045554) (xy 1.869571 -210.039551)
			(xy 1.941277 -210.034626) (xy 2.013082 -210.037822) (xy 2.084068 -210.049098) (xy 2.153329 -210.068311)
			(xy 2.219979 -210.095216) (xy 2.283169 -210.129468) (xy 2.342091 -210.170631) (xy 2.395992 -210.218178)
			(xy 2.444186 -210.271503) (xy 2.486055 -210.329924) (xy 2.521067 -210.392697) (xy 2.548772 -210.459018)
			(xy 2.568819 -210.528042) (xy 2.58095 -210.598887) (xy 2.585011 -210.670648) (xy 2.58095 -210.742409)
			(xy 2.568819 -210.813254) (xy 2.548772 -210.882278) (xy 2.521067 -210.948599) (xy 2.486055 -211.011372)
			(xy 2.444186 -211.069793) (xy 2.395992 -211.123118) (xy 2.342091 -211.170665) (xy 2.283169 -211.211828)
			(xy 2.219979 -211.24608) (xy 2.153329 -211.272985) (xy 2.084068 -211.292198) (xy 2.013082 -211.303474)
			(xy 1.941277 -211.30667) (xy 1.869571 -211.301745) (xy 1.834134 -211.295742) (xy 1.812148 -211.29217)
			(xy 1.767609 -211.291875) (xy 1.723701 -211.299348) (xy 1.681767 -211.314359) (xy 1.643092 -211.33645)
			(xy 1.608859 -211.364943) (xy 1.580116 -211.398967) (xy 1.557744 -211.43748) (xy 1.542426 -211.479302)
			(xy 1.534633 -211.523155) (xy 1.53416 -211.545424) (xy 1.53416 -211.706307) (xy 3.31393 -211.706307)
			(xy 3.31393 -211.634985) (xy 3.321916 -211.564111) (xy 3.337786 -211.494576) (xy 3.361343 -211.427256)
			(xy 3.392288 -211.362997) (xy 3.430234 -211.302606) (xy 3.474703 -211.246844) (xy 3.525136 -211.196411)
			(xy 3.580898 -211.151942) (xy 3.641289 -211.113996) (xy 3.705548 -211.083051) (xy 3.772868 -211.059494)
			(xy 3.842403 -211.043624) (xy 3.913277 -211.035638) (xy 3.984599 -211.035638) (xy 4.055473 -211.043624)
			(xy 4.125008 -211.059494) (xy 4.192328 -211.083051) (xy 4.256587 -211.113996) (xy 4.316978 -211.151942)
			(xy 4.37274 -211.196411) (xy 4.423173 -211.246844) (xy 4.467642 -211.302606) (xy 4.505588 -211.362997)
			(xy 4.536533 -211.427256) (xy 4.56009 -211.494576) (xy 4.57596 -211.564111) (xy 4.583946 -211.634985)
			(xy 4.584446 -211.670646) (xy 4.583946 -211.706307) (xy 4.57596 -211.777181) (xy 4.56009 -211.846716)
			(xy 4.536533 -211.914036) (xy 4.505588 -211.978295) (xy 4.467642 -212.038686) (xy 4.423173 -212.094448)
			(xy 4.37274 -212.144881) (xy 4.316978 -212.18935) (xy 4.256587 -212.227296) (xy 4.192328 -212.258241)
			(xy 4.125008 -212.281798) (xy 4.055473 -212.297668) (xy 3.984599 -212.305654) (xy 3.913277 -212.305654)
			(xy 3.842403 -212.297668) (xy 3.772868 -212.281798) (xy 3.705548 -212.258241) (xy 3.641289 -212.227296)
			(xy 3.580898 -212.18935) (xy 3.525136 -212.144881) (xy 3.474703 -212.094448) (xy 3.430234 -212.038686)
			(xy 3.392288 -211.978295) (xy 3.361343 -211.914036) (xy 3.337786 -211.846716) (xy 3.321916 -211.777181)
			(xy 3.31393 -211.706307) (xy 1.53416 -211.706307) (xy 1.53416 -211.795868) (xy 1.534617 -211.818145)
			(xy 1.542377 -211.862016) (xy 1.557674 -211.903861) (xy 1.580037 -211.942394) (xy 1.608781 -211.976434)
			(xy 1.643024 -212.004936) (xy 1.681715 -212.027026) (xy 1.723667 -212.042025) (xy 1.767593 -212.049474)
			(xy 1.812144 -212.049143) (xy 1.834134 -212.04555) (xy 1.869571 -212.039547) (xy 1.941277 -212.034622)
			(xy 2.013082 -212.037818) (xy 2.084068 -212.049094) (xy 2.153329 -212.068307) (xy 2.219979 -212.095212)
			(xy 2.283169 -212.129464) (xy 2.342091 -212.170627) (xy 2.395992 -212.218174) (xy 2.444186 -212.271499)
			(xy 2.486055 -212.32992) (xy 2.521067 -212.392693) (xy 2.548772 -212.459014) (xy 2.568819 -212.528038)
			(xy 2.58095 -212.598883) (xy 2.585011 -212.670644) (xy 2.58095 -212.742405) (xy 2.568819 -212.81325)
			(xy 2.548772 -212.882274) (xy 2.521067 -212.948595) (xy 2.486055 -213.011368) (xy 2.444186 -213.069789)
			(xy 2.395992 -213.123114) (xy 2.342091 -213.170661) (xy 2.283169 -213.211824) (xy 2.219979 -213.246076)
			(xy 2.153329 -213.272981) (xy 2.084068 -213.292194) (xy 2.013082 -213.30347) (xy 1.941277 -213.306666)
			(xy 1.869571 -213.301741) (xy 1.834134 -213.295738) (xy 1.812148 -213.292166) (xy 1.767609 -213.291872)
			(xy 1.7237 -213.299344) (xy 1.681767 -213.314355) (xy 1.643091 -213.336446) (xy 1.608858 -213.364939)
			(xy 1.580114 -213.398963) (xy 1.557741 -213.437475) (xy 1.542423 -213.479298) (xy 1.534629 -213.52315)
			(xy 1.53416 -213.54542) (xy 1.53416 -213.706303) (xy 3.31393 -213.706303) (xy 3.31393 -213.634981)
			(xy 3.321916 -213.564107) (xy 3.337786 -213.494572) (xy 3.361343 -213.427252) (xy 3.392288 -213.362993)
			(xy 3.430234 -213.302602) (xy 3.474703 -213.24684) (xy 3.525136 -213.196407) (xy 3.580898 -213.151938)
			(xy 3.641289 -213.113992) (xy 3.705548 -213.083047) (xy 3.772868 -213.05949) (xy 3.842403 -213.04362)
			(xy 3.913277 -213.035634) (xy 3.984599 -213.035634) (xy 4.055473 -213.04362) (xy 4.125008 -213.05949)
			(xy 4.192328 -213.083047) (xy 4.256587 -213.113992) (xy 4.316978 -213.151938) (xy 4.37274 -213.196407)
			(xy 4.423173 -213.24684) (xy 4.467642 -213.302602) (xy 4.505588 -213.362993) (xy 4.536533 -213.427252)
			(xy 4.56009 -213.494572) (xy 4.57596 -213.564107) (xy 4.583946 -213.634981) (xy 4.584446 -213.670642)
			(xy 4.583946 -213.706303) (xy 4.57596 -213.777177) (xy 4.56009 -213.846712) (xy 4.536533 -213.914032)
			(xy 4.505588 -213.978291) (xy 4.467642 -214.038682) (xy 4.423173 -214.094444) (xy 4.37274 -214.144877)
			(xy 4.316978 -214.189346) (xy 4.256587 -214.227292) (xy 4.192328 -214.258237) (xy 4.125008 -214.281794)
			(xy 4.055473 -214.297664) (xy 3.984599 -214.30565) (xy 3.913277 -214.30565) (xy 3.842403 -214.297664)
			(xy 3.772868 -214.281794) (xy 3.705548 -214.258237) (xy 3.641289 -214.227292) (xy 3.580898 -214.189346)
			(xy 3.525136 -214.144877) (xy 3.474703 -214.094444) (xy 3.430234 -214.038682) (xy 3.392288 -213.978291)
			(xy 3.361343 -213.914032) (xy 3.337786 -213.846712) (xy 3.321916 -213.777177) (xy 3.31393 -213.706303)
			(xy 1.53416 -213.706303) (xy 1.53416 -213.795864) (xy 1.534618 -213.81814) (xy 1.542379 -213.862011)
			(xy 1.557675 -213.903855) (xy 1.580039 -213.942387) (xy 1.608783 -213.976426) (xy 1.643026 -214.004928)
			(xy 1.681717 -214.027016) (xy 1.723668 -214.042015) (xy 1.767593 -214.049464) (xy 1.812144 -214.049134)
			(xy 1.834134 -214.045546) (xy 1.869571 -214.039543) (xy 1.941277 -214.034618) (xy 2.013082 -214.037814)
			(xy 2.084068 -214.04909) (xy 2.153329 -214.068303) (xy 2.219979 -214.095208) (xy 2.283169 -214.12946)
			(xy 2.342091 -214.170623) (xy 2.395992 -214.21817) (xy 2.444186 -214.271495) (xy 2.486055 -214.329916)
			(xy 2.521067 -214.392689) (xy 2.548772 -214.45901) (xy 2.568819 -214.528034) (xy 2.58095 -214.598879)
			(xy 2.585011 -214.67064) (xy 2.582993 -214.706301) (xy 7.813794 -214.706301) (xy 7.813794 -214.634979)
			(xy 7.82178 -214.564105) (xy 7.83765 -214.49457) (xy 7.861207 -214.42725) (xy 7.892152 -214.362991)
			(xy 7.930098 -214.3026) (xy 7.974567 -214.246838) (xy 8.025 -214.196405) (xy 8.080762 -214.151936)
			(xy 8.141153 -214.11399) (xy 8.205412 -214.083045) (xy 8.272732 -214.059488) (xy 8.342267 -214.043618)
			(xy 8.413141 -214.035632) (xy 8.484463 -214.035632) (xy 8.555337 -214.043618) (xy 8.624872 -214.059488)
			(xy 8.692192 -214.083045) (xy 8.756451 -214.11399) (xy 8.816842 -214.151936) (xy 8.872604 -214.196405)
			(xy 8.923037 -214.246838) (xy 8.967506 -214.3026) (xy 9.005452 -214.362991) (xy 9.036397 -214.42725)
			(xy 9.059954 -214.49457) (xy 9.075824 -214.564105) (xy 9.08381 -214.634979) (xy 9.08431 -214.67064)
			(xy 9.08381 -214.706301) (xy 9.075824 -214.777175) (xy 9.059954 -214.84671) (xy 9.036397 -214.91403)
			(xy 9.005452 -214.978289) (xy 8.967506 -215.03868) (xy 8.923037 -215.094442) (xy 8.872604 -215.144875)
			(xy 8.816842 -215.189344) (xy 8.756451 -215.22729) (xy 8.692192 -215.258235) (xy 8.624872 -215.281792)
			(xy 8.555337 -215.297662) (xy 8.484463 -215.305648) (xy 8.413141 -215.305648) (xy 8.342267 -215.297662)
			(xy 8.272732 -215.281792) (xy 8.205412 -215.258235) (xy 8.141153 -215.22729) (xy 8.080762 -215.189344)
			(xy 8.025 -215.144875) (xy 7.974567 -215.094442) (xy 7.930098 -215.03868) (xy 7.892152 -214.978289)
			(xy 7.861207 -214.91403) (xy 7.83765 -214.84671) (xy 7.82178 -214.777175) (xy 7.813794 -214.706301)
			(xy 2.582993 -214.706301) (xy 2.58095 -214.742401) (xy 2.568819 -214.813246) (xy 2.548772 -214.88227)
			(xy 2.521067 -214.948591) (xy 2.486055 -215.011364) (xy 2.444186 -215.069785) (xy 2.395992 -215.12311)
			(xy 2.342091 -215.170657) (xy 2.283169 -215.21182) (xy 2.219979 -215.246072) (xy 2.153329 -215.272977)
			(xy 2.084068 -215.29219) (xy 2.013082 -215.303466) (xy 1.941277 -215.306662) (xy 1.869571 -215.301737)
			(xy 1.834134 -215.295734) (xy 1.812147 -215.292162) (xy 1.767609 -215.291868) (xy 1.7237 -215.29934)
			(xy 1.681766 -215.314351) (xy 1.64309 -215.336442) (xy 1.608856 -215.364935) (xy 1.580113 -215.398958)
			(xy 1.557739 -215.437471) (xy 1.54242 -215.479294) (xy 1.534626 -215.523146) (xy 1.53416 -215.545416)
			(xy 1.53416 -215.706299) (xy 3.31393 -215.706299) (xy 3.31393 -215.634977) (xy 3.321916 -215.564103)
			(xy 3.337786 -215.494568) (xy 3.361343 -215.427248) (xy 3.392288 -215.362989) (xy 3.430234 -215.302598)
			(xy 3.474703 -215.246836) (xy 3.525136 -215.196403) (xy 3.580898 -215.151934) (xy 3.641289 -215.113988)
			(xy 3.705548 -215.083043) (xy 3.772868 -215.059486) (xy 3.842403 -215.043616) (xy 3.913277 -215.03563)
			(xy 3.984599 -215.03563) (xy 4.055473 -215.043616) (xy 4.125008 -215.059486) (xy 4.192328 -215.083043)
			(xy 4.256587 -215.113988) (xy 4.316978 -215.151934) (xy 4.37274 -215.196403) (xy 4.423173 -215.246836)
			(xy 4.467642 -215.302598) (xy 4.505588 -215.362989) (xy 4.536533 -215.427248) (xy 4.56009 -215.494568)
			(xy 4.57596 -215.564103) (xy 4.583946 -215.634977) (xy 4.584446 -215.670638) (xy 4.583946 -215.706299)
			(xy 5.813798 -215.706299) (xy 5.813798 -215.634977) (xy 5.821784 -215.564103) (xy 5.837654 -215.494568)
			(xy 5.861211 -215.427248) (xy 5.892156 -215.362989) (xy 5.930102 -215.302598) (xy 5.974571 -215.246836)
			(xy 6.025004 -215.196403) (xy 6.080766 -215.151934) (xy 6.141157 -215.113988) (xy 6.205416 -215.083043)
			(xy 6.272736 -215.059486) (xy 6.342271 -215.043616) (xy 6.413145 -215.03563) (xy 6.484467 -215.03563)
			(xy 6.555341 -215.043616) (xy 6.624876 -215.059486) (xy 6.692196 -215.083043) (xy 6.756455 -215.113988)
			(xy 6.816846 -215.151934) (xy 6.872608 -215.196403) (xy 6.923041 -215.246836) (xy 6.96751 -215.302598)
			(xy 7.005456 -215.362989) (xy 7.036401 -215.427248) (xy 7.059958 -215.494568) (xy 7.075828 -215.564103)
			(xy 7.083814 -215.634977) (xy 7.084314 -215.670638) (xy 7.083814 -215.706299) (xy 7.075828 -215.777173)
			(xy 7.059958 -215.846708) (xy 7.036401 -215.914028) (xy 7.005456 -215.978287) (xy 6.96751 -216.038678)
			(xy 6.923041 -216.09444) (xy 6.872608 -216.144873) (xy 6.816846 -216.189342) (xy 6.756455 -216.227288)
			(xy 6.692196 -216.258233) (xy 6.624876 -216.28179) (xy 6.555341 -216.29766) (xy 6.484467 -216.305646)
			(xy 6.413145 -216.305646) (xy 6.342271 -216.29766) (xy 6.272736 -216.28179) (xy 6.205416 -216.258233)
			(xy 6.141157 -216.227288) (xy 6.080766 -216.189342) (xy 6.025004 -216.144873) (xy 5.974571 -216.09444)
			(xy 5.930102 -216.038678) (xy 5.892156 -215.978287) (xy 5.861211 -215.914028) (xy 5.837654 -215.846708)
			(xy 5.821784 -215.777173) (xy 5.813798 -215.706299) (xy 4.583946 -215.706299) (xy 4.57596 -215.777173)
			(xy 4.56009 -215.846708) (xy 4.536533 -215.914028) (xy 4.505588 -215.978287) (xy 4.467642 -216.038678)
			(xy 4.423173 -216.09444) (xy 4.37274 -216.144873) (xy 4.316978 -216.189342) (xy 4.256587 -216.227288)
			(xy 4.192328 -216.258233) (xy 4.125008 -216.28179) (xy 4.055473 -216.29766) (xy 3.984599 -216.305646)
			(xy 3.913277 -216.305646) (xy 3.842403 -216.29766) (xy 3.772868 -216.28179) (xy 3.705548 -216.258233)
			(xy 3.641289 -216.227288) (xy 3.580898 -216.189342) (xy 3.525136 -216.144873) (xy 3.474703 -216.09444)
			(xy 3.430234 -216.038678) (xy 3.392288 -215.978287) (xy 3.361343 -215.914028) (xy 3.337786 -215.846708)
			(xy 3.321916 -215.777173) (xy 3.31393 -215.706299) (xy 1.53416 -215.706299) (xy 1.53416 -217.706295)
			(xy 3.31393 -217.706295) (xy 3.31393 -217.634973) (xy 3.321916 -217.564099) (xy 3.337786 -217.494564)
			(xy 3.361343 -217.427244) (xy 3.392288 -217.362985) (xy 3.430234 -217.302594) (xy 3.474703 -217.246832)
			(xy 3.525136 -217.196399) (xy 3.580898 -217.15193) (xy 3.641289 -217.113984) (xy 3.705548 -217.083039)
			(xy 3.772868 -217.059482) (xy 3.842403 -217.043612) (xy 3.913277 -217.035626) (xy 3.984599 -217.035626)
			(xy 4.055473 -217.043612) (xy 4.125008 -217.059482) (xy 4.192328 -217.083039) (xy 4.256587 -217.113984)
			(xy 4.316978 -217.15193) (xy 4.37274 -217.196399) (xy 4.423173 -217.246832) (xy 4.467642 -217.302594)
			(xy 4.505588 -217.362985) (xy 4.536533 -217.427244) (xy 4.56009 -217.494564) (xy 4.57596 -217.564099)
			(xy 4.583946 -217.634973) (xy 4.584446 -217.670634) (xy 4.583946 -217.706295) (xy 5.813798 -217.706295)
			(xy 5.813798 -217.634973) (xy 5.821784 -217.564099) (xy 5.837654 -217.494564) (xy 5.861211 -217.427244)
			(xy 5.892156 -217.362985) (xy 5.930102 -217.302594) (xy 5.974571 -217.246832) (xy 6.025004 -217.196399)
			(xy 6.080766 -217.15193) (xy 6.141157 -217.113984) (xy 6.205416 -217.083039) (xy 6.272736 -217.059482)
			(xy 6.342271 -217.043612) (xy 6.413145 -217.035626) (xy 6.484467 -217.035626) (xy 6.555341 -217.043612)
			(xy 6.624876 -217.059482) (xy 6.692196 -217.083039) (xy 6.756455 -217.113984) (xy 6.816846 -217.15193)
			(xy 6.872608 -217.196399) (xy 6.923041 -217.246832) (xy 6.96751 -217.302594) (xy 7.005456 -217.362985)
			(xy 7.036401 -217.427244) (xy 7.059958 -217.494564) (xy 7.075828 -217.564099) (xy 7.083814 -217.634973)
			(xy 7.084314 -217.670634) (xy 7.083814 -217.706295) (xy 7.075828 -217.777169) (xy 7.059958 -217.846704)
			(xy 7.036401 -217.914024) (xy 7.005456 -217.978283) (xy 6.96751 -218.038674) (xy 6.923041 -218.094436)
			(xy 6.872608 -218.144869) (xy 6.816846 -218.189338) (xy 6.756455 -218.227284) (xy 6.692196 -218.258229)
			(xy 6.624876 -218.281786) (xy 6.555341 -218.297656) (xy 6.484467 -218.305642) (xy 6.413145 -218.305642)
			(xy 6.342271 -218.297656) (xy 6.272736 -218.281786) (xy 6.205416 -218.258229) (xy 6.141157 -218.227284)
			(xy 6.080766 -218.189338) (xy 6.025004 -218.144869) (xy 5.974571 -218.094436) (xy 5.930102 -218.038674)
			(xy 5.892156 -217.978283) (xy 5.861211 -217.914024) (xy 5.837654 -217.846704) (xy 5.821784 -217.777169)
			(xy 5.813798 -217.706295) (xy 4.583946 -217.706295) (xy 4.57596 -217.777169) (xy 4.56009 -217.846704)
			(xy 4.536533 -217.914024) (xy 4.505588 -217.978283) (xy 4.467642 -218.038674) (xy 4.423173 -218.094436)
			(xy 4.37274 -218.144869) (xy 4.316978 -218.189338) (xy 4.256587 -218.227284) (xy 4.192328 -218.258229)
			(xy 4.125008 -218.281786) (xy 4.055473 -218.297656) (xy 3.984599 -218.305642) (xy 3.913277 -218.305642)
			(xy 3.842403 -218.297656) (xy 3.772868 -218.281786) (xy 3.705548 -218.258229) (xy 3.641289 -218.227284)
			(xy 3.580898 -218.189338) (xy 3.525136 -218.144869) (xy 3.474703 -218.094436) (xy 3.430234 -218.038674)
			(xy 3.392288 -217.978283) (xy 3.361343 -217.914024) (xy 3.337786 -217.846704) (xy 3.321916 -217.777169)
			(xy 3.31393 -217.706295) (xy 1.53416 -217.706295) (xy 1.53416 -217.795856) (xy 1.534617 -217.818133)
			(xy 1.542377 -217.862005) (xy 1.557673 -217.90385) (xy 1.580036 -217.942383) (xy 1.608781 -217.976424)
			(xy 1.643024 -218.004926) (xy 1.681715 -218.027016) (xy 1.723667 -218.042015) (xy 1.767593 -218.049464)
			(xy 1.812145 -218.049133) (xy 1.834134 -218.045538) (xy 1.869571 -218.039535) (xy 1.941277 -218.03461)
			(xy 2.013082 -218.037806) (xy 2.084068 -218.049082) (xy 2.153329 -218.068295) (xy 2.219979 -218.0952)
			(xy 2.283169 -218.129452) (xy 2.342091 -218.170615) (xy 2.395992 -218.218162) (xy 2.444186 -218.271487)
			(xy 2.486055 -218.329908) (xy 2.521067 -218.392681) (xy 2.548772 -218.459002) (xy 2.568819 -218.528026)
			(xy 2.58095 -218.598871) (xy 2.585011 -218.670632) (xy 2.582993 -218.706293) (xy 7.813794 -218.706293)
			(xy 7.813794 -218.634971) (xy 7.82178 -218.564097) (xy 7.83765 -218.494562) (xy 7.861207 -218.427242)
			(xy 7.892152 -218.362983) (xy 7.930098 -218.302592) (xy 7.974567 -218.24683) (xy 8.025 -218.196397)
			(xy 8.080762 -218.151928) (xy 8.141153 -218.113982) (xy 8.205412 -218.083037) (xy 8.272732 -218.05948)
			(xy 8.342267 -218.04361) (xy 8.413141 -218.035624) (xy 8.484463 -218.035624) (xy 8.555337 -218.04361)
			(xy 8.624872 -218.05948) (xy 8.692192 -218.083037) (xy 8.756451 -218.113982) (xy 8.816842 -218.151928)
			(xy 8.872604 -218.196397) (xy 8.923037 -218.24683) (xy 8.967506 -218.302592) (xy 9.005452 -218.362983)
			(xy 9.036397 -218.427242) (xy 9.059954 -218.494562) (xy 9.075824 -218.564097) (xy 9.08381 -218.634971)
			(xy 9.08431 -218.670632) (xy 9.08381 -218.706293) (xy 9.075824 -218.777167) (xy 9.059954 -218.846702)
			(xy 9.036397 -218.914022) (xy 9.005452 -218.978281) (xy 8.967506 -219.038672) (xy 8.923037 -219.094434)
			(xy 8.872604 -219.144867) (xy 8.816842 -219.189336) (xy 8.756451 -219.227282) (xy 8.692192 -219.258227)
			(xy 8.624872 -219.281784) (xy 8.555337 -219.297654) (xy 8.484463 -219.30564) (xy 8.413141 -219.30564)
			(xy 8.342267 -219.297654) (xy 8.272732 -219.281784) (xy 8.205412 -219.258227) (xy 8.141153 -219.227282)
			(xy 8.080762 -219.189336) (xy 8.025 -219.144867) (xy 7.974567 -219.094434) (xy 7.930098 -219.038672)
			(xy 7.892152 -218.978281) (xy 7.861207 -218.914022) (xy 7.83765 -218.846702) (xy 7.82178 -218.777167)
			(xy 7.813794 -218.706293) (xy 2.582993 -218.706293) (xy 2.58095 -218.742393) (xy 2.568819 -218.813238)
			(xy 2.548772 -218.882262) (xy 2.521067 -218.948583) (xy 2.486055 -219.011356) (xy 2.444186 -219.069777)
			(xy 2.395992 -219.123102) (xy 2.342091 -219.170649) (xy 2.283169 -219.211812) (xy 2.219979 -219.246064)
			(xy 2.153329 -219.272969) (xy 2.084068 -219.292182) (xy 2.013082 -219.303458) (xy 1.941277 -219.306654)
			(xy 1.869571 -219.301729) (xy 1.834134 -219.295726) (xy 1.812147 -219.292154) (xy 1.767608 -219.29186)
			(xy 1.723699 -219.299332) (xy 1.681764 -219.314344) (xy 1.643088 -219.336434) (xy 1.608853 -219.364927)
			(xy 1.580109 -219.39895) (xy 1.557734 -219.437463) (xy 1.542415 -219.479285) (xy 1.534618 -219.523138)
			(xy 1.53416 -219.545408) (xy 1.53416 -219.706291) (xy 5.813798 -219.706291) (xy 5.813798 -219.634969)
			(xy 5.821784 -219.564095) (xy 5.837654 -219.49456) (xy 5.861211 -219.42724) (xy 5.892156 -219.362981)
			(xy 5.930102 -219.30259) (xy 5.974571 -219.246828) (xy 6.025004 -219.196395) (xy 6.080766 -219.151926)
			(xy 6.141157 -219.11398) (xy 6.205416 -219.083035) (xy 6.272736 -219.059478) (xy 6.342271 -219.043608)
			(xy 6.413145 -219.035622) (xy 6.484467 -219.035622) (xy 6.555341 -219.043608) (xy 6.624876 -219.059478)
			(xy 6.692196 -219.083035) (xy 6.756455 -219.11398) (xy 6.816846 -219.151926) (xy 6.872608 -219.196395)
			(xy 6.923041 -219.246828) (xy 6.96751 -219.30259) (xy 7.005456 -219.362981) (xy 7.036401 -219.42724)
			(xy 7.059958 -219.49456) (xy 7.075828 -219.564095) (xy 7.083814 -219.634969) (xy 7.084314 -219.67063)
			(xy 7.083814 -219.706291) (xy 7.075828 -219.777165) (xy 7.059958 -219.8467) (xy 7.036401 -219.91402)
			(xy 7.005456 -219.978279) (xy 6.978893 -220.020554) (xy 11.920116 -220.020554) (xy 11.9225 -219.965491)
			(xy 11.932784 -219.911344) (xy 11.950754 -219.859241) (xy 11.976036 -219.810267) (xy 12.008103 -219.765441)
			(xy 12.046288 -219.725698) (xy 12.089795 -219.691863) (xy 12.137719 -219.664643) (xy 12.189062 -219.644604)
			(xy 12.242754 -219.632163) (xy 12.297678 -219.627579) (xy 12.35269 -219.630948) (xy 12.406644 -219.642199)
			(xy 12.458417 -219.661098) (xy 12.506931 -219.687252) (xy 12.551176 -219.720116) (xy 12.59023 -219.759006)
			(xy 12.62328 -219.803111) (xy 12.649638 -219.851515) (xy 12.668756 -219.903207) (xy 12.680235 -219.957114)
			(xy 12.683835 -220.012111) (xy 12.679483 -220.067053) (xy 12.667269 -220.120798) (xy 12.647446 -220.172224)
			(xy 12.620429 -220.220263) (xy 12.603988 -220.242384) (xy 12.591394 -220.259473) (xy 12.571441 -220.296938)
			(xy 12.557987 -220.337196) (xy 12.551407 -220.37913) (xy 12.551884 -220.421575) (xy 12.559405 -220.46335)
			(xy 12.57376 -220.503296) (xy 12.594551 -220.540303) (xy 12.607544 -220.55709) (xy 12.624466 -220.578844)
			(xy 12.652536 -220.626273) (xy 12.673489 -220.677247) (xy 12.686886 -220.730707) (xy 12.69245 -220.785538)
			(xy 12.690064 -220.840599) (xy 12.679779 -220.894744) (xy 12.661808 -220.946844) (xy 12.636526 -220.995816)
			(xy 12.604458 -221.040639) (xy 12.566274 -221.08038) (xy 12.522767 -221.114211) (xy 12.474844 -221.141429)
			(xy 12.423502 -221.161465) (xy 12.369812 -221.173904) (xy 12.31489 -221.178486) (xy 12.25988 -221.175116)
			(xy 12.205928 -221.163864) (xy 12.154158 -221.144963) (xy 12.105646 -221.118809) (xy 12.061404 -221.085945)
			(xy 12.022353 -221.047055) (xy 11.989305 -221.00295) (xy 11.962949 -220.954547) (xy 11.943834 -220.902856)
			(xy 11.932358 -220.848951) (xy 11.928759 -220.793956) (xy 11.933113 -220.739015) (xy 11.945329 -220.685274)
			(xy 11.965153 -220.633849) (xy 11.992171 -220.585814) (xy 12.008612 -220.563694) (xy 12.021227 -220.54662)
			(xy 12.041179 -220.509152) (xy 12.054631 -220.46889) (xy 12.061208 -220.426953) (xy 12.060728 -220.384507)
			(xy 12.053204 -220.34273) (xy 12.038845 -220.302782) (xy 12.01805 -220.265775) (xy 12.005056 -220.248988)
			(xy 11.988109 -220.227253) (xy 11.960036 -220.179824) (xy 11.939081 -220.128848) (xy 11.925681 -220.075387)
			(xy 11.920116 -220.020554) (xy 6.978893 -220.020554) (xy 6.96751 -220.03867) (xy 6.923041 -220.094432)
			(xy 6.872608 -220.144865) (xy 6.816846 -220.189334) (xy 6.756455 -220.22728) (xy 6.692196 -220.258225)
			(xy 6.624876 -220.281782) (xy 6.555341 -220.297652) (xy 6.484467 -220.305638) (xy 6.413145 -220.305638)
			(xy 6.342271 -220.297652) (xy 6.272736 -220.281782) (xy 6.205416 -220.258225) (xy 6.141157 -220.22728)
			(xy 6.080766 -220.189334) (xy 6.025004 -220.144865) (xy 5.974571 -220.094432) (xy 5.930102 -220.03867)
			(xy 5.892156 -219.978279) (xy 5.861211 -219.91402) (xy 5.837654 -219.8467) (xy 5.821784 -219.777165)
			(xy 5.813798 -219.706291) (xy 1.53416 -219.706291) (xy 1.53416 -219.795852) (xy 1.534618 -219.818128)
			(xy 1.542378 -219.861999) (xy 1.557675 -219.903843) (xy 1.580038 -219.942376) (xy 1.608783 -219.976416)
			(xy 1.643025 -220.004917) (xy 1.681716 -220.027006) (xy 1.723668 -220.042005) (xy 1.767593 -220.049454)
			(xy 1.812144 -220.049124) (xy 1.834134 -220.045534) (xy 1.869571 -220.039531) (xy 1.941277 -220.034606)
			(xy 2.013082 -220.037802) (xy 2.084068 -220.049078) (xy 2.153329 -220.068291) (xy 2.219979 -220.095196)
			(xy 2.283169 -220.129448) (xy 2.342091 -220.170611) (xy 2.395992 -220.218158) (xy 2.444186 -220.271483)
			(xy 2.486055 -220.329904) (xy 2.521067 -220.392677) (xy 2.548772 -220.458998) (xy 2.568819 -220.528022)
			(xy 2.58095 -220.598867) (xy 2.585011 -220.670628) (xy 2.582993 -220.706289) (xy 7.813794 -220.706289)
			(xy 7.813794 -220.634967) (xy 7.82178 -220.564093) (xy 7.83765 -220.494558) (xy 7.861207 -220.427238)
			(xy 7.892152 -220.362979) (xy 7.930098 -220.302588) (xy 7.974567 -220.246826) (xy 8.025 -220.196393)
			(xy 8.080762 -220.151924) (xy 8.141153 -220.113978) (xy 8.205412 -220.083033) (xy 8.272732 -220.059476)
			(xy 8.342267 -220.043606) (xy 8.413141 -220.03562) (xy 8.484463 -220.03562) (xy 8.555337 -220.043606)
			(xy 8.624872 -220.059476) (xy 8.692192 -220.083033) (xy 8.756451 -220.113978) (xy 8.816842 -220.151924)
			(xy 8.872604 -220.196393) (xy 8.923037 -220.246826) (xy 8.967506 -220.302588) (xy 9.005452 -220.362979)
			(xy 9.036397 -220.427238) (xy 9.059954 -220.494558) (xy 9.075824 -220.564093) (xy 9.08381 -220.634967)
			(xy 9.08431 -220.670628) (xy 9.08381 -220.706289) (xy 9.075824 -220.777163) (xy 9.059954 -220.846698)
			(xy 9.036397 -220.914018) (xy 9.005452 -220.978277) (xy 8.967506 -221.038668) (xy 8.923037 -221.09443)
			(xy 8.872604 -221.144863) (xy 8.816842 -221.189332) (xy 8.756451 -221.227278) (xy 8.692192 -221.258223)
			(xy 8.624872 -221.28178) (xy 8.555337 -221.29765) (xy 8.484463 -221.305636) (xy 8.413141 -221.305636)
			(xy 8.342267 -221.29765) (xy 8.272732 -221.28178) (xy 8.205412 -221.258223) (xy 8.141153 -221.227278)
			(xy 8.080762 -221.189332) (xy 8.025 -221.144863) (xy 7.974567 -221.09443) (xy 7.930098 -221.038668)
			(xy 7.892152 -220.978277) (xy 7.861207 -220.914018) (xy 7.83765 -220.846698) (xy 7.82178 -220.777163)
			(xy 7.813794 -220.706289) (xy 2.582993 -220.706289) (xy 2.58095 -220.742389) (xy 2.568819 -220.813234)
			(xy 2.548772 -220.882258) (xy 2.521067 -220.948579) (xy 2.486055 -221.011352) (xy 2.444186 -221.069773)
			(xy 2.395992 -221.123098) (xy 2.342091 -221.170645) (xy 2.283169 -221.211808) (xy 2.219979 -221.24606)
			(xy 2.153329 -221.272965) (xy 2.084068 -221.292178) (xy 2.013082 -221.303454) (xy 1.941277 -221.30665)
			(xy 1.869571 -221.301725) (xy 1.834134 -221.295722) (xy 1.812147 -221.29215) (xy 1.767608 -221.291856)
			(xy 1.723698 -221.299328) (xy 1.681763 -221.31434) (xy 1.643087 -221.33643) (xy 1.608852 -221.364922)
			(xy 1.580107 -221.398946) (xy 1.557732 -221.437458) (xy 1.542412 -221.479281) (xy 1.534615 -221.523134)
			(xy 1.53416 -221.545404) (xy 1.53416 -221.706287) (xy 3.31393 -221.706287) (xy 3.31393 -221.634965)
			(xy 3.321916 -221.564091) (xy 3.337786 -221.494556) (xy 3.361343 -221.427236) (xy 3.392288 -221.362977)
			(xy 3.430234 -221.302586) (xy 3.474703 -221.246824) (xy 3.525136 -221.196391) (xy 3.580898 -221.151922)
			(xy 3.641289 -221.113976) (xy 3.705548 -221.083031) (xy 3.772868 -221.059474) (xy 3.842403 -221.043604)
			(xy 3.913277 -221.035618) (xy 3.984599 -221.035618) (xy 4.055473 -221.043604) (xy 4.125008 -221.059474)
			(xy 4.192328 -221.083031) (xy 4.256587 -221.113976) (xy 4.316978 -221.151922) (xy 4.37274 -221.196391)
			(xy 4.423173 -221.246824) (xy 4.467642 -221.302586) (xy 4.505588 -221.362977) (xy 4.536533 -221.427236)
			(xy 4.56009 -221.494556) (xy 4.57596 -221.564091) (xy 4.583946 -221.634965) (xy 4.584446 -221.670626)
			(xy 4.583946 -221.706287) (xy 4.57596 -221.777161) (xy 4.56009 -221.846696) (xy 4.536533 -221.914016)
			(xy 4.505588 -221.978275) (xy 4.467642 -222.038666) (xy 4.423173 -222.094428) (xy 4.37274 -222.144861)
			(xy 4.316978 -222.18933) (xy 4.256587 -222.227276) (xy 4.192328 -222.258221) (xy 4.125008 -222.281778)
			(xy 4.055473 -222.297648) (xy 3.984599 -222.305634) (xy 3.913277 -222.305634) (xy 3.842403 -222.297648)
			(xy 3.772868 -222.281778) (xy 3.705548 -222.258221) (xy 3.641289 -222.227276) (xy 3.580898 -222.18933)
			(xy 3.525136 -222.144861) (xy 3.474703 -222.094428) (xy 3.430234 -222.038666) (xy 3.392288 -221.978275)
			(xy 3.361343 -221.914016) (xy 3.337786 -221.846696) (xy 3.321916 -221.777161) (xy 3.31393 -221.706287)
			(xy 1.53416 -221.706287) (xy 1.53416 -221.795848) (xy 1.534617 -221.818125) (xy 1.542377 -221.861996)
			(xy 1.557674 -221.903841) (xy 1.580037 -221.942374) (xy 1.608781 -221.976414) (xy 1.643024 -222.004916)
			(xy 1.681715 -222.027006) (xy 1.723667 -222.042005) (xy 1.767593 -222.049454) (xy 1.812144 -222.049123)
			(xy 1.834134 -222.04553) (xy 1.869571 -222.039527) (xy 1.941277 -222.034602) (xy 2.013082 -222.037798)
			(xy 2.084068 -222.049074) (xy 2.153329 -222.068287) (xy 2.219979 -222.095192) (xy 2.283169 -222.129444)
			(xy 2.342091 -222.170607) (xy 2.395992 -222.218154) (xy 2.444186 -222.271479) (xy 2.486055 -222.3299)
			(xy 2.521067 -222.392673) (xy 2.548772 -222.458994) (xy 2.568819 -222.528018) (xy 2.58095 -222.598863)
			(xy 2.585011 -222.670624) (xy 2.582993 -222.706285) (xy 7.813794 -222.706285) (xy 7.813794 -222.634963)
			(xy 7.82178 -222.564089) (xy 7.83765 -222.494554) (xy 7.861207 -222.427234) (xy 7.892152 -222.362975)
			(xy 7.930098 -222.302584) (xy 7.974567 -222.246822) (xy 8.025 -222.196389) (xy 8.080762 -222.15192)
			(xy 8.141153 -222.113974) (xy 8.205412 -222.083029) (xy 8.272732 -222.059472) (xy 8.342267 -222.043602)
			(xy 8.413141 -222.035616) (xy 8.484463 -222.035616) (xy 8.555337 -222.043602) (xy 8.624872 -222.059472)
			(xy 8.692192 -222.083029) (xy 8.756451 -222.113974) (xy 8.816842 -222.15192) (xy 8.872604 -222.196389)
			(xy 8.923037 -222.246822) (xy 8.967506 -222.302584) (xy 9.005452 -222.362975) (xy 9.036397 -222.427234)
			(xy 9.059954 -222.494554) (xy 9.075824 -222.564089) (xy 9.08381 -222.634963) (xy 9.08431 -222.670624)
			(xy 9.08381 -222.706285) (xy 9.075824 -222.777159) (xy 9.059954 -222.846694) (xy 9.036397 -222.914014)
			(xy 9.005452 -222.978273) (xy 8.967506 -223.038664) (xy 8.923037 -223.094426) (xy 8.872604 -223.144859)
			(xy 8.816842 -223.189328) (xy 8.756451 -223.227274) (xy 8.692192 -223.258219) (xy 8.624872 -223.281776)
			(xy 8.555337 -223.297646) (xy 8.484463 -223.305632) (xy 8.413141 -223.305632) (xy 8.342267 -223.297646)
			(xy 8.272732 -223.281776) (xy 8.205412 -223.258219) (xy 8.141153 -223.227274) (xy 8.080762 -223.189328)
			(xy 8.025 -223.144859) (xy 7.974567 -223.094426) (xy 7.930098 -223.038664) (xy 7.892152 -222.978273)
			(xy 7.861207 -222.914014) (xy 7.83765 -222.846694) (xy 7.82178 -222.777159) (xy 7.813794 -222.706285)
			(xy 2.582993 -222.706285) (xy 2.58095 -222.742385) (xy 2.568819 -222.81323) (xy 2.548772 -222.882254)
			(xy 2.521067 -222.948575) (xy 2.486055 -223.011348) (xy 2.444186 -223.069769) (xy 2.395992 -223.123094)
			(xy 2.342091 -223.170641) (xy 2.283169 -223.211804) (xy 2.219979 -223.246056) (xy 2.153329 -223.272961)
			(xy 2.084068 -223.292174) (xy 2.013082 -223.30345) (xy 1.941277 -223.306646) (xy 1.869571 -223.301721)
			(xy 1.834134 -223.295718) (xy 1.812147 -223.292146) (xy 1.767607 -223.291852) (xy 1.723698 -223.299325)
			(xy 1.681763 -223.314336) (xy 1.643086 -223.336426) (xy 1.60885 -223.364918) (xy 1.580105 -223.398942)
			(xy 1.55773 -223.437454) (xy 1.542409 -223.479277) (xy 1.534611 -223.52313) (xy 1.53416 -223.5454)
			(xy 1.53416 -223.706283) (xy 3.31393 -223.706283) (xy 3.31393 -223.634961) (xy 3.321916 -223.564087)
			(xy 3.337786 -223.494552) (xy 3.361343 -223.427232) (xy 3.392288 -223.362973) (xy 3.430234 -223.302582)
			(xy 3.474703 -223.24682) (xy 3.525136 -223.196387) (xy 3.580898 -223.151918) (xy 3.641289 -223.113972)
			(xy 3.705548 -223.083027) (xy 3.772868 -223.05947) (xy 3.842403 -223.0436) (xy 3.913277 -223.035614)
			(xy 3.984599 -223.035614) (xy 4.055473 -223.0436) (xy 4.125008 -223.05947) (xy 4.192328 -223.083027)
			(xy 4.256587 -223.113972) (xy 4.316978 -223.151918) (xy 4.37274 -223.196387) (xy 4.423173 -223.24682)
			(xy 4.467642 -223.302582) (xy 4.505588 -223.362973) (xy 4.536533 -223.427232) (xy 4.56009 -223.494552)
			(xy 4.57596 -223.564087) (xy 4.583946 -223.634961) (xy 4.584446 -223.670622) (xy 4.583946 -223.706283)
			(xy 5.813798 -223.706283) (xy 5.813798 -223.634961) (xy 5.821784 -223.564087) (xy 5.837654 -223.494552)
			(xy 5.861211 -223.427232) (xy 5.892156 -223.362973) (xy 5.930102 -223.302582) (xy 5.974571 -223.24682)
			(xy 6.025004 -223.196387) (xy 6.080766 -223.151918) (xy 6.141157 -223.113972) (xy 6.205416 -223.083027)
			(xy 6.272736 -223.05947) (xy 6.342271 -223.0436) (xy 6.413145 -223.035614) (xy 6.484467 -223.035614)
			(xy 6.555341 -223.0436) (xy 6.624876 -223.05947) (xy 6.692196 -223.083027) (xy 6.756455 -223.113972)
			(xy 6.816846 -223.151918) (xy 6.872608 -223.196387) (xy 6.923041 -223.24682) (xy 6.96751 -223.302582)
			(xy 7.005456 -223.362973) (xy 7.036401 -223.427232) (xy 7.059958 -223.494552) (xy 7.075828 -223.564087)
			(xy 7.083814 -223.634961) (xy 7.084314 -223.670622) (xy 7.083814 -223.706283) (xy 7.075828 -223.777157)
			(xy 7.059958 -223.846692) (xy 7.036401 -223.914012) (xy 7.005456 -223.978271) (xy 6.96751 -224.038662)
			(xy 6.923041 -224.094424) (xy 6.872608 -224.144857) (xy 6.816846 -224.189326) (xy 6.756455 -224.227272)
			(xy 6.692196 -224.258217) (xy 6.624876 -224.281774) (xy 6.555341 -224.297644) (xy 6.484467 -224.30563)
			(xy 6.413145 -224.30563) (xy 6.342271 -224.297644) (xy 6.272736 -224.281774) (xy 6.205416 -224.258217)
			(xy 6.141157 -224.227272) (xy 6.080766 -224.189326) (xy 6.025004 -224.144857) (xy 5.974571 -224.094424)
			(xy 5.930102 -224.038662) (xy 5.892156 -223.978271) (xy 5.861211 -223.914012) (xy 5.837654 -223.846692)
			(xy 5.821784 -223.777157) (xy 5.813798 -223.706283) (xy 4.583946 -223.706283) (xy 4.57596 -223.777157)
			(xy 4.56009 -223.846692) (xy 4.536533 -223.914012) (xy 4.505588 -223.978271) (xy 4.467642 -224.038662)
			(xy 4.423173 -224.094424) (xy 4.37274 -224.144857) (xy 4.316978 -224.189326) (xy 4.256587 -224.227272)
			(xy 4.192328 -224.258217) (xy 4.125008 -224.281774) (xy 4.055473 -224.297644) (xy 3.984599 -224.30563)
			(xy 3.913277 -224.30563) (xy 3.842403 -224.297644) (xy 3.772868 -224.281774) (xy 3.705548 -224.258217)
			(xy 3.641289 -224.227272) (xy 3.580898 -224.189326) (xy 3.525136 -224.144857) (xy 3.474703 -224.094424)
			(xy 3.430234 -224.038662) (xy 3.392288 -223.978271) (xy 3.361343 -223.914012) (xy 3.337786 -223.846692)
			(xy 3.321916 -223.777157) (xy 3.31393 -223.706283) (xy 1.53416 -223.706283) (xy 1.53416 -224.706281)
			(xy 7.813794 -224.706281) (xy 7.813794 -224.634959) (xy 7.82178 -224.564085) (xy 7.83765 -224.49455)
			(xy 7.861207 -224.42723) (xy 7.892152 -224.362971) (xy 7.930098 -224.30258) (xy 7.974567 -224.246818)
			(xy 8.025 -224.196385) (xy 8.080762 -224.151916) (xy 8.141153 -224.11397) (xy 8.205412 -224.083025)
			(xy 8.272732 -224.059468) (xy 8.342267 -224.043598) (xy 8.413141 -224.035612) (xy 8.484463 -224.035612)
			(xy 8.555337 -224.043598) (xy 8.624872 -224.059468) (xy 8.692192 -224.083025) (xy 8.756451 -224.11397)
			(xy 8.816842 -224.151916) (xy 8.872604 -224.196385) (xy 8.923037 -224.246818) (xy 8.967506 -224.30258)
			(xy 9.005452 -224.362971) (xy 9.036397 -224.42723) (xy 9.059954 -224.49455) (xy 9.075824 -224.564085)
			(xy 9.08381 -224.634959) (xy 9.08431 -224.67062) (xy 9.08381 -224.706281) (xy 9.075824 -224.777155)
			(xy 9.059954 -224.84669) (xy 9.036397 -224.91401) (xy 9.005452 -224.978269) (xy 8.967506 -225.03866)
			(xy 8.923037 -225.094422) (xy 8.872604 -225.144855) (xy 8.816842 -225.189324) (xy 8.756451 -225.22727)
			(xy 8.692192 -225.258215) (xy 8.624872 -225.281772) (xy 8.555337 -225.297642) (xy 8.484463 -225.305628)
			(xy 8.413141 -225.305628) (xy 8.342267 -225.297642) (xy 8.272732 -225.281772) (xy 8.205412 -225.258215)
			(xy 8.141153 -225.22727) (xy 8.080762 -225.189324) (xy 8.025 -225.144855) (xy 7.974567 -225.094422)
			(xy 7.930098 -225.03866) (xy 7.892152 -224.978269) (xy 7.861207 -224.91401) (xy 7.83765 -224.84669)
			(xy 7.82178 -224.777155) (xy 7.813794 -224.706281) (xy 1.53416 -224.706281) (xy 1.53416 -225.706279)
			(xy 3.31393 -225.706279) (xy 3.31393 -225.634957) (xy 3.321916 -225.564083) (xy 3.337786 -225.494548)
			(xy 3.361343 -225.427228) (xy 3.392288 -225.362969) (xy 3.430234 -225.302578) (xy 3.474703 -225.246816)
			(xy 3.525136 -225.196383) (xy 3.580898 -225.151914) (xy 3.641289 -225.113968) (xy 3.705548 -225.083023)
			(xy 3.772868 -225.059466) (xy 3.842403 -225.043596) (xy 3.913277 -225.03561) (xy 3.984599 -225.03561)
			(xy 4.055473 -225.043596) (xy 4.125008 -225.059466) (xy 4.192328 -225.083023) (xy 4.256587 -225.113968)
			(xy 4.316978 -225.151914) (xy 4.37274 -225.196383) (xy 4.423173 -225.246816) (xy 4.467642 -225.302578)
			(xy 4.505588 -225.362969) (xy 4.536533 -225.427228) (xy 4.56009 -225.494548) (xy 4.57596 -225.564083)
			(xy 4.583946 -225.634957) (xy 4.584446 -225.670618) (xy 4.583946 -225.706279) (xy 5.813798 -225.706279)
			(xy 5.813798 -225.634957) (xy 5.821784 -225.564083) (xy 5.837654 -225.494548) (xy 5.861211 -225.427228)
			(xy 5.892156 -225.362969) (xy 5.930102 -225.302578) (xy 5.974571 -225.246816) (xy 6.025004 -225.196383)
			(xy 6.080766 -225.151914) (xy 6.141157 -225.113968) (xy 6.205416 -225.083023) (xy 6.272736 -225.059466)
			(xy 6.342271 -225.043596) (xy 6.413145 -225.03561) (xy 6.484467 -225.03561) (xy 6.555341 -225.043596)
			(xy 6.624876 -225.059466) (xy 6.692196 -225.083023) (xy 6.756455 -225.113968) (xy 6.816846 -225.151914)
			(xy 6.872608 -225.196383) (xy 6.923041 -225.246816) (xy 6.96751 -225.302578) (xy 7.005456 -225.362969)
			(xy 7.036401 -225.427228) (xy 7.059958 -225.494548) (xy 7.075828 -225.564083) (xy 7.083814 -225.634957)
			(xy 7.084314 -225.670618) (xy 7.083814 -225.706279) (xy 7.075828 -225.777153) (xy 7.059958 -225.846688)
			(xy 7.036401 -225.914008) (xy 7.005456 -225.978267) (xy 6.96751 -226.038658) (xy 6.923041 -226.09442)
			(xy 6.872608 -226.144853) (xy 6.816846 -226.189322) (xy 6.756455 -226.227268) (xy 6.692196 -226.258213)
			(xy 6.624876 -226.28177) (xy 6.555341 -226.29764) (xy 6.484467 -226.305626) (xy 6.413145 -226.305626)
			(xy 6.342271 -226.29764) (xy 6.272736 -226.28177) (xy 6.205416 -226.258213) (xy 6.141157 -226.227268)
			(xy 6.080766 -226.189322) (xy 6.025004 -226.144853) (xy 5.974571 -226.09442) (xy 5.930102 -226.038658)
			(xy 5.892156 -225.978267) (xy 5.861211 -225.914008) (xy 5.837654 -225.846688) (xy 5.821784 -225.777153)
			(xy 5.813798 -225.706279) (xy 4.583946 -225.706279) (xy 4.57596 -225.777153) (xy 4.56009 -225.846688)
			(xy 4.536533 -225.914008) (xy 4.505588 -225.978267) (xy 4.467642 -226.038658) (xy 4.423173 -226.09442)
			(xy 4.37274 -226.144853) (xy 4.316978 -226.189322) (xy 4.256587 -226.227268) (xy 4.192328 -226.258213)
			(xy 4.125008 -226.28177) (xy 4.055473 -226.29764) (xy 3.984599 -226.305626) (xy 3.913277 -226.305626)
			(xy 3.842403 -226.29764) (xy 3.772868 -226.28177) (xy 3.705548 -226.258213) (xy 3.641289 -226.227268)
			(xy 3.580898 -226.189322) (xy 3.525136 -226.144853) (xy 3.474703 -226.09442) (xy 3.430234 -226.038658)
			(xy 3.392288 -225.978267) (xy 3.361343 -225.914008) (xy 3.337786 -225.846688) (xy 3.321916 -225.777153)
			(xy 3.31393 -225.706279) (xy 1.53416 -225.706279) (xy 1.53416 -225.79584) (xy 1.534617 -225.818116)
			(xy 1.542378 -225.861988) (xy 1.557674 -225.903832) (xy 1.580038 -225.942365) (xy 1.608782 -225.976405)
			(xy 1.643025 -226.004907) (xy 1.681716 -226.026996) (xy 1.723667 -226.041995) (xy 1.767593 -226.049444)
			(xy 1.812144 -226.049113) (xy 1.834134 -226.045522) (xy 1.869571 -226.039519) (xy 1.941277 -226.034594)
			(xy 2.013082 -226.03779) (xy 2.084068 -226.049066) (xy 2.153329 -226.068279) (xy 2.219979 -226.095184)
			(xy 2.283169 -226.129436) (xy 2.342091 -226.170599) (xy 2.395992 -226.218146) (xy 2.444186 -226.271471)
			(xy 2.486055 -226.329892) (xy 2.521067 -226.392665) (xy 2.548772 -226.458986) (xy 2.568819 -226.52801)
			(xy 2.58095 -226.598855) (xy 2.585011 -226.670616) (xy 2.58095 -226.742377) (xy 2.568819 -226.813222)
			(xy 2.548772 -226.882246) (xy 2.521067 -226.948567) (xy 2.486055 -227.01134) (xy 2.444186 -227.069761)
			(xy 2.395992 -227.123086) (xy 2.342091 -227.170633) (xy 2.283169 -227.211796) (xy 2.219979 -227.246048)
			(xy 2.153329 -227.272953) (xy 2.084068 -227.292166) (xy 2.013082 -227.303442) (xy 1.941277 -227.306638)
			(xy 1.869571 -227.301713) (xy 1.834134 -227.29571) (xy 1.812147 -227.292139) (xy 1.767607 -227.291844)
			(xy 1.723697 -227.299317) (xy 1.681761 -227.314328) (xy 1.643083 -227.336417) (xy 1.608848 -227.36491)
			(xy 1.580101 -227.398933) (xy 1.557725 -227.437446) (xy 1.542403 -227.479269) (xy 1.534604 -227.523122)
			(xy 1.53416 -227.545392) (xy 1.53416 -227.706275) (xy 3.31393 -227.706275) (xy 3.31393 -227.634953)
			(xy 3.321916 -227.564079) (xy 3.337786 -227.494544) (xy 3.361343 -227.427224) (xy 3.392288 -227.362965)
			(xy 3.430234 -227.302574) (xy 3.474703 -227.246812) (xy 3.525136 -227.196379) (xy 3.580898 -227.15191)
			(xy 3.641289 -227.113964) (xy 3.705548 -227.083019) (xy 3.772868 -227.059462) (xy 3.842403 -227.043592)
			(xy 3.913277 -227.035606) (xy 3.984599 -227.035606) (xy 4.055473 -227.043592) (xy 4.125008 -227.059462)
			(xy 4.192328 -227.083019) (xy 4.256587 -227.113964) (xy 4.316978 -227.15191) (xy 4.37274 -227.196379)
			(xy 4.423173 -227.246812) (xy 4.467642 -227.302574) (xy 4.505588 -227.362965) (xy 4.536533 -227.427224)
			(xy 4.56009 -227.494544) (xy 4.57596 -227.564079) (xy 4.583946 -227.634953) (xy 4.584446 -227.670614)
			(xy 4.583946 -227.706275) (xy 5.813798 -227.706275) (xy 5.813798 -227.634953) (xy 5.821784 -227.564079)
			(xy 5.837654 -227.494544) (xy 5.861211 -227.427224) (xy 5.892156 -227.362965) (xy 5.930102 -227.302574)
			(xy 5.974571 -227.246812) (xy 6.025004 -227.196379) (xy 6.080766 -227.15191) (xy 6.141157 -227.113964)
			(xy 6.205416 -227.083019) (xy 6.272736 -227.059462) (xy 6.342271 -227.043592) (xy 6.413145 -227.035606)
			(xy 6.484467 -227.035606) (xy 6.555341 -227.043592) (xy 6.624876 -227.059462) (xy 6.692196 -227.083019)
			(xy 6.756455 -227.113964) (xy 6.816846 -227.15191) (xy 6.872608 -227.196379) (xy 6.923041 -227.246812)
			(xy 6.96751 -227.302574) (xy 7.005456 -227.362965) (xy 7.036401 -227.427224) (xy 7.059958 -227.494544)
			(xy 7.075828 -227.564079) (xy 7.083814 -227.634953) (xy 7.084314 -227.670614) (xy 7.083814 -227.706275)
			(xy 7.075828 -227.777149) (xy 7.059958 -227.846684) (xy 7.036401 -227.914004) (xy 7.005456 -227.978263)
			(xy 6.96751 -228.038654) (xy 6.923041 -228.094416) (xy 6.872608 -228.144849) (xy 6.816846 -228.189318)
			(xy 6.756455 -228.227264) (xy 6.692196 -228.258209) (xy 6.624876 -228.281766) (xy 6.555341 -228.297636)
			(xy 6.484467 -228.305622) (xy 6.413145 -228.305622) (xy 6.342271 -228.297636) (xy 6.272736 -228.281766)
			(xy 6.205416 -228.258209) (xy 6.141157 -228.227264) (xy 6.080766 -228.189318) (xy 6.025004 -228.144849)
			(xy 5.974571 -228.094416) (xy 5.930102 -228.038654) (xy 5.892156 -227.978263) (xy 5.861211 -227.914004)
			(xy 5.837654 -227.846684) (xy 5.821784 -227.777149) (xy 5.813798 -227.706275) (xy 4.583946 -227.706275)
			(xy 4.57596 -227.777149) (xy 4.56009 -227.846684) (xy 4.536533 -227.914004) (xy 4.505588 -227.978263)
			(xy 4.467642 -228.038654) (xy 4.423173 -228.094416) (xy 4.37274 -228.144849) (xy 4.316978 -228.189318)
			(xy 4.256587 -228.227264) (xy 4.192328 -228.258209) (xy 4.125008 -228.281766) (xy 4.055473 -228.297636)
			(xy 3.984599 -228.305622) (xy 3.913277 -228.305622) (xy 3.842403 -228.297636) (xy 3.772868 -228.281766)
			(xy 3.705548 -228.258209) (xy 3.641289 -228.227264) (xy 3.580898 -228.189318) (xy 3.525136 -228.144849)
			(xy 3.474703 -228.094416) (xy 3.430234 -228.038654) (xy 3.392288 -227.978263) (xy 3.361343 -227.914004)
			(xy 3.337786 -227.846684) (xy 3.321916 -227.777149) (xy 3.31393 -227.706275) (xy 1.53416 -227.706275)
			(xy 1.53416 -227.795836) (xy 1.534617 -227.818113) (xy 1.542377 -227.861985) (xy 1.557673 -227.90383)
			(xy 1.580036 -227.942363) (xy 1.608781 -227.976404) (xy 1.643024 -228.004906) (xy 1.681715 -228.026996)
			(xy 1.723667 -228.041995) (xy 1.767593 -228.049444) (xy 1.812145 -228.049113) (xy 1.834134 -228.045518)
			(xy 1.869571 -228.039515) (xy 1.941277 -228.03459) (xy 2.013082 -228.037786) (xy 2.084068 -228.049062)
			(xy 2.153329 -228.068275) (xy 2.219979 -228.09518) (xy 2.283169 -228.129432) (xy 2.342091 -228.170595)
			(xy 2.395992 -228.218142) (xy 2.444186 -228.271467) (xy 2.486055 -228.329888) (xy 2.521067 -228.392661)
			(xy 2.548772 -228.458982) (xy 2.568819 -228.528006) (xy 2.58095 -228.598851) (xy 2.585011 -228.670612)
			(xy 2.582993 -228.706273) (xy 7.813794 -228.706273) (xy 7.813794 -228.634951) (xy 7.82178 -228.564077)
			(xy 7.83765 -228.494542) (xy 7.861207 -228.427222) (xy 7.892152 -228.362963) (xy 7.930098 -228.302572)
			(xy 7.974567 -228.24681) (xy 8.025 -228.196377) (xy 8.080762 -228.151908) (xy 8.141153 -228.113962)
			(xy 8.205412 -228.083017) (xy 8.272732 -228.05946) (xy 8.342267 -228.04359) (xy 8.413141 -228.035604)
			(xy 8.484463 -228.035604) (xy 8.555337 -228.04359) (xy 8.624872 -228.05946) (xy 8.692192 -228.083017)
			(xy 8.756451 -228.113962) (xy 8.816842 -228.151908) (xy 8.872604 -228.196377) (xy 8.923037 -228.24681)
			(xy 8.967506 -228.302572) (xy 9.005452 -228.362963) (xy 9.036397 -228.427222) (xy 9.059954 -228.494542)
			(xy 9.075824 -228.564077) (xy 9.08381 -228.634951) (xy 9.08431 -228.670612) (xy 9.08381 -228.706273)
			(xy 9.075824 -228.777147) (xy 9.059954 -228.846682) (xy 9.036397 -228.914002) (xy 9.005452 -228.978261)
			(xy 8.967506 -229.038652) (xy 8.923037 -229.094414) (xy 8.872604 -229.144847) (xy 8.816842 -229.189316)
			(xy 8.756451 -229.227262) (xy 8.692192 -229.258207) (xy 8.624872 -229.281764) (xy 8.555337 -229.297634)
			(xy 8.484463 -229.30562) (xy 8.413141 -229.30562) (xy 8.342267 -229.297634) (xy 8.272732 -229.281764)
			(xy 8.205412 -229.258207) (xy 8.141153 -229.227262) (xy 8.080762 -229.189316) (xy 8.025 -229.144847)
			(xy 7.974567 -229.094414) (xy 7.930098 -229.038652) (xy 7.892152 -228.978261) (xy 7.861207 -228.914002)
			(xy 7.83765 -228.846682) (xy 7.82178 -228.777147) (xy 7.813794 -228.706273) (xy 2.582993 -228.706273)
			(xy 2.58095 -228.742373) (xy 2.568819 -228.813218) (xy 2.548772 -228.882242) (xy 2.521067 -228.948563)
			(xy 2.486055 -229.011336) (xy 2.444186 -229.069757) (xy 2.395992 -229.123082) (xy 2.342091 -229.170629)
			(xy 2.283169 -229.211792) (xy 2.219979 -229.246044) (xy 2.153329 -229.272949) (xy 2.084068 -229.292162)
			(xy 2.013082 -229.303438) (xy 1.941277 -229.306634) (xy 1.869571 -229.301709) (xy 1.834134 -229.295706)
			(xy 1.812147 -229.292135) (xy 1.767606 -229.29184) (xy 1.723696 -229.299313) (xy 1.68176 -229.314324)
			(xy 1.643082 -229.336413) (xy 1.608846 -229.364906) (xy 1.5801 -229.398929) (xy 1.557722 -229.437441)
			(xy 1.5424 -229.479264) (xy 1.534601 -229.523118) (xy 1.53416 -229.545388) (xy 1.53416 -229.706271)
			(xy 5.813798 -229.706271) (xy 5.813798 -229.634949) (xy 5.821784 -229.564075) (xy 5.837654 -229.49454)
			(xy 5.861211 -229.42722) (xy 5.892156 -229.362961) (xy 5.930102 -229.30257) (xy 5.974571 -229.246808)
			(xy 6.025004 -229.196375) (xy 6.080766 -229.151906) (xy 6.141157 -229.11396) (xy 6.205416 -229.083015)
			(xy 6.272736 -229.059458) (xy 6.342271 -229.043588) (xy 6.413145 -229.035602) (xy 6.484467 -229.035602)
			(xy 6.555341 -229.043588) (xy 6.624876 -229.059458) (xy 6.692196 -229.083015) (xy 6.756455 -229.11396)
			(xy 6.816846 -229.151906) (xy 6.872608 -229.196375) (xy 6.923041 -229.246808) (xy 6.96751 -229.30257)
			(xy 7.005456 -229.362961) (xy 7.036401 -229.42722) (xy 7.059958 -229.49454) (xy 7.075828 -229.564075)
			(xy 7.083814 -229.634949) (xy 7.084314 -229.67061) (xy 7.083814 -229.706271) (xy 7.075828 -229.777145)
			(xy 7.059958 -229.84668) (xy 7.036401 -229.914) (xy 7.005456 -229.978259) (xy 6.96751 -230.03865)
			(xy 6.923041 -230.094412) (xy 6.872608 -230.144845) (xy 6.816846 -230.189314) (xy 6.756455 -230.22726)
			(xy 6.692196 -230.258205) (xy 6.624876 -230.281762) (xy 6.555341 -230.297632) (xy 6.484467 -230.305618)
			(xy 6.413145 -230.305618) (xy 6.342271 -230.297632) (xy 6.272736 -230.281762) (xy 6.205416 -230.258205)
			(xy 6.141157 -230.22726) (xy 6.080766 -230.189314) (xy 6.025004 -230.144845) (xy 5.974571 -230.094412)
			(xy 5.930102 -230.03865) (xy 5.892156 -229.978259) (xy 5.861211 -229.914) (xy 5.837654 -229.84668)
			(xy 5.821784 -229.777145) (xy 5.813798 -229.706271) (xy 1.53416 -229.706271) (xy 1.53416 -229.795832)
			(xy 1.534618 -229.818108) (xy 1.542378 -229.861979) (xy 1.557675 -229.903823) (xy 1.580038 -229.942356)
			(xy 1.608783 -229.976396) (xy 1.643025 -230.004897) (xy 1.681716 -230.026986) (xy 1.723668 -230.041985)
			(xy 1.767593 -230.049434) (xy 1.812144 -230.049104) (xy 1.834134 -230.045514) (xy 1.869571 -230.039511)
			(xy 1.941277 -230.034586) (xy 2.013082 -230.037782) (xy 2.084068 -230.049058) (xy 2.153329 -230.068271)
			(xy 2.219979 -230.095176) (xy 2.283169 -230.129428) (xy 2.342091 -230.170591) (xy 2.395992 -230.218138)
			(xy 2.444186 -230.271463) (xy 2.486055 -230.329884) (xy 2.521067 -230.392657) (xy 2.548772 -230.458978)
			(xy 2.568819 -230.528002) (xy 2.58095 -230.598847) (xy 2.585011 -230.670608) (xy 2.582993 -230.706269)
			(xy 7.813794 -230.706269) (xy 7.813794 -230.634947) (xy 7.82178 -230.564073) (xy 7.83765 -230.494538)
			(xy 7.861207 -230.427218) (xy 7.892152 -230.362959) (xy 7.930098 -230.302568) (xy 7.974567 -230.246806)
			(xy 8.025 -230.196373) (xy 8.080762 -230.151904) (xy 8.141153 -230.113958) (xy 8.205412 -230.083013)
			(xy 8.272732 -230.059456) (xy 8.342267 -230.043586) (xy 8.413141 -230.0356) (xy 8.484463 -230.0356)
			(xy 8.555337 -230.043586) (xy 8.624872 -230.059456) (xy 8.692192 -230.083013) (xy 8.756451 -230.113958)
			(xy 8.816842 -230.151904) (xy 8.872604 -230.196373) (xy 8.923037 -230.246806) (xy 8.967506 -230.302568)
			(xy 9.005452 -230.362959) (xy 9.036397 -230.427218) (xy 9.059954 -230.494538) (xy 9.075824 -230.564073)
			(xy 9.08381 -230.634947) (xy 9.08431 -230.670608) (xy 9.08381 -230.706269) (xy 9.075824 -230.777143)
			(xy 9.059954 -230.846678) (xy 9.036397 -230.913998) (xy 9.005452 -230.978257) (xy 8.967506 -231.038648)
			(xy 8.923037 -231.09441) (xy 8.872604 -231.144843) (xy 8.816842 -231.189312) (xy 8.756451 -231.227258)
			(xy 8.692192 -231.258203) (xy 8.624872 -231.28176) (xy 8.555337 -231.29763) (xy 8.484463 -231.305616)
			(xy 8.413141 -231.305616) (xy 8.342267 -231.29763) (xy 8.272732 -231.28176) (xy 8.205412 -231.258203)
			(xy 8.141153 -231.227258) (xy 8.080762 -231.189312) (xy 8.025 -231.144843) (xy 7.974567 -231.09441)
			(xy 7.930098 -231.038648) (xy 7.892152 -230.978257) (xy 7.861207 -230.913998) (xy 7.83765 -230.846678)
			(xy 7.82178 -230.777143) (xy 7.813794 -230.706269) (xy 2.582993 -230.706269) (xy 2.58095 -230.742369)
			(xy 2.568819 -230.813214) (xy 2.548772 -230.882238) (xy 2.521067 -230.948559) (xy 2.486055 -231.011332)
			(xy 2.444186 -231.069753) (xy 2.395992 -231.123078) (xy 2.342091 -231.170625) (xy 2.283169 -231.211788)
			(xy 2.219979 -231.24604) (xy 2.153329 -231.272945) (xy 2.084068 -231.292158) (xy 2.013082 -231.303434)
			(xy 1.941277 -231.30663) (xy 1.869571 -231.301705) (xy 1.834134 -231.295702) (xy 1.812147 -231.292131)
			(xy 1.767606 -231.291836) (xy 1.723696 -231.299309) (xy 1.681759 -231.31432) (xy 1.643081 -231.336409)
			(xy 1.608845 -231.364902) (xy 1.580098 -231.398925) (xy 1.55772 -231.437437) (xy 1.542397 -231.47926)
			(xy 1.534597 -231.523114) (xy 1.53416 -231.545384) (xy 1.53416 -231.706267) (xy 3.31393 -231.706267)
			(xy 3.31393 -231.634945) (xy 3.321916 -231.564071) (xy 3.337786 -231.494536) (xy 3.361343 -231.427216)
			(xy 3.392288 -231.362957) (xy 3.430234 -231.302566) (xy 3.474703 -231.246804) (xy 3.525136 -231.196371)
			(xy 3.580898 -231.151902) (xy 3.641289 -231.113956) (xy 3.705548 -231.083011) (xy 3.772868 -231.059454)
			(xy 3.842403 -231.043584) (xy 3.913277 -231.035598) (xy 3.984599 -231.035598) (xy 4.055473 -231.043584)
			(xy 4.125008 -231.059454) (xy 4.192328 -231.083011) (xy 4.256587 -231.113956) (xy 4.316978 -231.151902)
			(xy 4.37274 -231.196371) (xy 4.423173 -231.246804) (xy 4.467642 -231.302566) (xy 4.505588 -231.362957)
			(xy 4.536533 -231.427216) (xy 4.56009 -231.494536) (xy 4.57596 -231.564071) (xy 4.583946 -231.634945)
			(xy 4.584446 -231.670606) (xy 4.583946 -231.706267) (xy 4.57596 -231.777141) (xy 4.56009 -231.846676)
			(xy 4.536533 -231.913996) (xy 4.505588 -231.978255) (xy 4.467642 -232.038646) (xy 4.423173 -232.094408)
			(xy 4.37274 -232.144841) (xy 4.316978 -232.18931) (xy 4.256587 -232.227256) (xy 4.192328 -232.258201)
			(xy 4.125008 -232.281758) (xy 4.055473 -232.297628) (xy 3.984599 -232.305614) (xy 3.913277 -232.305614)
			(xy 3.842403 -232.297628) (xy 3.772868 -232.281758) (xy 3.705548 -232.258201) (xy 3.641289 -232.227256)
			(xy 3.580898 -232.18931) (xy 3.525136 -232.144841) (xy 3.474703 -232.094408) (xy 3.430234 -232.038646)
			(xy 3.392288 -231.978255) (xy 3.361343 -231.913996) (xy 3.337786 -231.846676) (xy 3.321916 -231.777141)
			(xy 3.31393 -231.706267) (xy 1.53416 -231.706267) (xy 1.53416 -231.795828) (xy 1.534618 -231.818104)
			(xy 1.542379 -231.861975) (xy 1.557677 -231.903819) (xy 1.58004 -231.942352) (xy 1.608784 -231.976392)
			(xy 1.643027 -232.004893) (xy 1.681717 -232.026983) (xy 1.723669 -232.041983) (xy 1.767594 -232.049433)
			(xy 1.812145 -232.049104) (xy 1.834134 -232.04551) (xy 1.869571 -232.039507) (xy 1.941277 -232.034582)
			(xy 2.013082 -232.037778) (xy 2.084068 -232.049054) (xy 2.153329 -232.068267) (xy 2.219979 -232.095172)
			(xy 2.283169 -232.129424) (xy 2.342091 -232.170587) (xy 2.395992 -232.218134) (xy 2.444186 -232.271459)
			(xy 2.486055 -232.32988) (xy 2.521067 -232.392653) (xy 2.548772 -232.458974) (xy 2.568819 -232.527998)
			(xy 2.58095 -232.598843) (xy 2.585011 -232.670604) (xy 2.582993 -232.706265) (xy 7.813794 -232.706265)
			(xy 7.813794 -232.634943) (xy 7.82178 -232.564069) (xy 7.83765 -232.494534) (xy 7.861207 -232.427214)
			(xy 7.892152 -232.362955) (xy 7.930098 -232.302564) (xy 7.974567 -232.246802) (xy 8.025 -232.196369)
			(xy 8.080762 -232.1519) (xy 8.141153 -232.113954) (xy 8.205412 -232.083009) (xy 8.272732 -232.059452)
			(xy 8.342267 -232.043582) (xy 8.413141 -232.035596) (xy 8.484463 -232.035596) (xy 8.555337 -232.043582)
			(xy 8.624872 -232.059452) (xy 8.692192 -232.083009) (xy 8.756451 -232.113954) (xy 8.816842 -232.1519)
			(xy 8.872604 -232.196369) (xy 8.923037 -232.246802) (xy 8.967506 -232.302564) (xy 9.005452 -232.362955)
			(xy 9.036397 -232.427214) (xy 9.059954 -232.494534) (xy 9.075824 -232.564069) (xy 9.08381 -232.634943)
			(xy 9.08431 -232.670604) (xy 9.08381 -232.706265) (xy 9.075824 -232.777139) (xy 9.059954 -232.846674)
			(xy 9.036397 -232.913994) (xy 9.005452 -232.978253) (xy 8.967506 -233.038644) (xy 8.923037 -233.094406)
			(xy 8.872604 -233.144839) (xy 8.816842 -233.189308) (xy 8.756451 -233.227254) (xy 8.692192 -233.258199)
			(xy 8.624872 -233.281756) (xy 8.555337 -233.297626) (xy 8.484463 -233.305612) (xy 8.413141 -233.305612)
			(xy 8.342267 -233.297626) (xy 8.272732 -233.281756) (xy 8.205412 -233.258199) (xy 8.141153 -233.227254)
			(xy 8.080762 -233.189308) (xy 8.025 -233.144839) (xy 7.974567 -233.094406) (xy 7.930098 -233.038644)
			(xy 7.892152 -232.978253) (xy 7.861207 -232.913994) (xy 7.83765 -232.846674) (xy 7.82178 -232.777139)
			(xy 7.813794 -232.706265) (xy 2.582993 -232.706265) (xy 2.58095 -232.742365) (xy 2.568819 -232.81321)
			(xy 2.548772 -232.882234) (xy 2.521067 -232.948555) (xy 2.486055 -233.011328) (xy 2.444186 -233.069749)
			(xy 2.395992 -233.123074) (xy 2.342091 -233.170621) (xy 2.283169 -233.211784) (xy 2.219979 -233.246036)
			(xy 2.153329 -233.272941) (xy 2.084068 -233.292154) (xy 2.013082 -233.30343) (xy 1.941277 -233.306626)
			(xy 1.869571 -233.301701) (xy 1.834134 -233.295698) (xy 1.812146 -233.292127) (xy 1.767606 -233.291832)
			(xy 1.723695 -233.299305) (xy 1.681759 -233.314316) (xy 1.64308 -233.336405) (xy 1.608843 -233.364898)
			(xy 1.580096 -233.398921) (xy 1.557718 -233.437433) (xy 1.542394 -233.479256) (xy 1.534593 -233.523109)
			(xy 1.53416 -233.54538) (xy 1.53416 -233.706263) (xy 3.31393 -233.706263) (xy 3.31393 -233.634941)
			(xy 3.321916 -233.564067) (xy 3.337786 -233.494532) (xy 3.361343 -233.427212) (xy 3.392288 -233.362953)
			(xy 3.430234 -233.302562) (xy 3.474703 -233.2468) (xy 3.525136 -233.196367) (xy 3.580898 -233.151898)
			(xy 3.641289 -233.113952) (xy 3.705548 -233.083007) (xy 3.772868 -233.05945) (xy 3.842403 -233.04358)
			(xy 3.913277 -233.035594) (xy 3.984599 -233.035594) (xy 4.055473 -233.04358) (xy 4.125008 -233.05945)
			(xy 4.192328 -233.083007) (xy 4.256587 -233.113952) (xy 4.316978 -233.151898) (xy 4.37274 -233.196367)
			(xy 4.423173 -233.2468) (xy 4.467642 -233.302562) (xy 4.505588 -233.362953) (xy 4.536533 -233.427212)
			(xy 4.56009 -233.494532) (xy 4.57596 -233.564067) (xy 4.583946 -233.634941) (xy 4.584446 -233.670602)
			(xy 4.583946 -233.706263) (xy 5.813798 -233.706263) (xy 5.813798 -233.634941) (xy 5.821784 -233.564067)
			(xy 5.837654 -233.494532) (xy 5.861211 -233.427212) (xy 5.892156 -233.362953) (xy 5.930102 -233.302562)
			(xy 5.974571 -233.2468) (xy 6.025004 -233.196367) (xy 6.080766 -233.151898) (xy 6.141157 -233.113952)
			(xy 6.205416 -233.083007) (xy 6.272736 -233.05945) (xy 6.342271 -233.04358) (xy 6.413145 -233.035594)
			(xy 6.484467 -233.035594) (xy 6.555341 -233.04358) (xy 6.624876 -233.05945) (xy 6.692196 -233.083007)
			(xy 6.756455 -233.113952) (xy 6.816846 -233.151898) (xy 6.872608 -233.196367) (xy 6.923041 -233.2468)
			(xy 6.96751 -233.302562) (xy 7.005456 -233.362953) (xy 7.036401 -233.427212) (xy 7.059958 -233.494532)
			(xy 7.075828 -233.564067) (xy 7.083814 -233.634941) (xy 7.084314 -233.670602) (xy 7.083814 -233.706263)
			(xy 7.075828 -233.777137) (xy 7.059958 -233.846672) (xy 7.036401 -233.913992) (xy 7.005456 -233.978251)
			(xy 6.96751 -234.038642) (xy 6.923041 -234.094404) (xy 6.872608 -234.144837) (xy 6.816846 -234.189306)
			(xy 6.756455 -234.227252) (xy 6.692196 -234.258197) (xy 6.624876 -234.281754) (xy 6.555341 -234.297624)
			(xy 6.484467 -234.30561) (xy 6.413145 -234.30561) (xy 6.342271 -234.297624) (xy 6.272736 -234.281754)
			(xy 6.205416 -234.258197) (xy 6.141157 -234.227252) (xy 6.080766 -234.189306) (xy 6.025004 -234.144837)
			(xy 5.974571 -234.094404) (xy 5.930102 -234.038642) (xy 5.892156 -233.978251) (xy 5.861211 -233.913992)
			(xy 5.837654 -233.846672) (xy 5.821784 -233.777137) (xy 5.813798 -233.706263) (xy 4.583946 -233.706263)
			(xy 4.57596 -233.777137) (xy 4.56009 -233.846672) (xy 4.536533 -233.913992) (xy 4.505588 -233.978251)
			(xy 4.467642 -234.038642) (xy 4.423173 -234.094404) (xy 4.37274 -234.144837) (xy 4.316978 -234.189306)
			(xy 4.256587 -234.227252) (xy 4.192328 -234.258197) (xy 4.125008 -234.281754) (xy 4.055473 -234.297624)
			(xy 3.984599 -234.30561) (xy 3.913277 -234.30561) (xy 3.842403 -234.297624) (xy 3.772868 -234.281754)
			(xy 3.705548 -234.258197) (xy 3.641289 -234.227252) (xy 3.580898 -234.189306) (xy 3.525136 -234.144837)
			(xy 3.474703 -234.094404) (xy 3.430234 -234.038642) (xy 3.392288 -233.978251) (xy 3.361343 -233.913992)
			(xy 3.337786 -233.846672) (xy 3.321916 -233.777137) (xy 3.31393 -233.706263) (xy 1.53416 -233.706263)
			(xy 1.53416 -234.706261) (xy 7.813794 -234.706261) (xy 7.813794 -234.634939) (xy 7.82178 -234.564065)
			(xy 7.83765 -234.49453) (xy 7.861207 -234.42721) (xy 7.892152 -234.362951) (xy 7.930098 -234.30256)
			(xy 7.974567 -234.246798) (xy 8.025 -234.196365) (xy 8.080762 -234.151896) (xy 8.141153 -234.11395)
			(xy 8.205412 -234.083005) (xy 8.272732 -234.059448) (xy 8.342267 -234.043578) (xy 8.413141 -234.035592)
			(xy 8.484463 -234.035592) (xy 8.555337 -234.043578) (xy 8.624872 -234.059448) (xy 8.692192 -234.083005)
			(xy 8.756451 -234.11395) (xy 8.816842 -234.151896) (xy 8.872604 -234.196365) (xy 8.923037 -234.246798)
			(xy 8.967506 -234.30256) (xy 9.005452 -234.362951) (xy 9.036397 -234.42721) (xy 9.059954 -234.49453)
			(xy 9.075824 -234.564065) (xy 9.08381 -234.634939) (xy 9.08431 -234.6706) (xy 9.08381 -234.706261)
			(xy 9.075824 -234.777135) (xy 9.059954 -234.84667) (xy 9.036397 -234.91399) (xy 9.005452 -234.978249)
			(xy 8.967506 -235.03864) (xy 8.923037 -235.094402) (xy 8.872604 -235.144835) (xy 8.816842 -235.189304)
			(xy 8.756451 -235.22725) (xy 8.692192 -235.258195) (xy 8.624872 -235.281752) (xy 8.555337 -235.297622)
			(xy 8.484463 -235.305608) (xy 8.413141 -235.305608) (xy 8.342267 -235.297622) (xy 8.272732 -235.281752)
			(xy 8.205412 -235.258195) (xy 8.141153 -235.22725) (xy 8.080762 -235.189304) (xy 8.025 -235.144835)
			(xy 7.974567 -235.094402) (xy 7.930098 -235.03864) (xy 7.892152 -234.978249) (xy 7.861207 -234.91399)
			(xy 7.83765 -234.84667) (xy 7.82178 -234.777135) (xy 7.813794 -234.706261) (xy 1.53416 -234.706261)
			(xy 1.53416 -235.706259) (xy 3.31393 -235.706259) (xy 3.31393 -235.634937) (xy 3.321916 -235.564063)
			(xy 3.337786 -235.494528) (xy 3.361343 -235.427208) (xy 3.392288 -235.362949) (xy 3.430234 -235.302558)
			(xy 3.474703 -235.246796) (xy 3.525136 -235.196363) (xy 3.580898 -235.151894) (xy 3.641289 -235.113948)
			(xy 3.705548 -235.083003) (xy 3.772868 -235.059446) (xy 3.842403 -235.043576) (xy 3.913277 -235.03559)
			(xy 3.984599 -235.03559) (xy 4.055473 -235.043576) (xy 4.125008 -235.059446) (xy 4.192328 -235.083003)
			(xy 4.256587 -235.113948) (xy 4.316978 -235.151894) (xy 4.37274 -235.196363) (xy 4.423173 -235.246796)
			(xy 4.467642 -235.302558) (xy 4.505588 -235.362949) (xy 4.536533 -235.427208) (xy 4.56009 -235.494528)
			(xy 4.57596 -235.564063) (xy 4.583946 -235.634937) (xy 4.584446 -235.670598) (xy 4.583946 -235.706259)
			(xy 5.813798 -235.706259) (xy 5.813798 -235.634937) (xy 5.821784 -235.564063) (xy 5.837654 -235.494528)
			(xy 5.861211 -235.427208) (xy 5.892156 -235.362949) (xy 5.930102 -235.302558) (xy 5.974571 -235.246796)
			(xy 6.025004 -235.196363) (xy 6.080766 -235.151894) (xy 6.141157 -235.113948) (xy 6.205416 -235.083003)
			(xy 6.272736 -235.059446) (xy 6.342271 -235.043576) (xy 6.413145 -235.03559) (xy 6.484467 -235.03559)
			(xy 6.555341 -235.043576) (xy 6.624876 -235.059446) (xy 6.692196 -235.083003) (xy 6.756455 -235.113948)
			(xy 6.816846 -235.151894) (xy 6.872608 -235.196363) (xy 6.923041 -235.246796) (xy 6.96751 -235.302558)
			(xy 7.005456 -235.362949) (xy 7.036401 -235.427208) (xy 7.059958 -235.494528) (xy 7.075828 -235.564063)
			(xy 7.083814 -235.634937) (xy 7.084314 -235.670598) (xy 7.083814 -235.706259) (xy 7.075828 -235.777133)
			(xy 7.059958 -235.846668) (xy 7.036401 -235.913988) (xy 7.005456 -235.978247) (xy 6.96751 -236.038638)
			(xy 6.923041 -236.0944) (xy 6.872608 -236.144833) (xy 6.816846 -236.189302) (xy 6.756455 -236.227248)
			(xy 6.692196 -236.258193) (xy 6.624876 -236.28175) (xy 6.555341 -236.29762) (xy 6.484467 -236.305606)
			(xy 6.413145 -236.305606) (xy 6.342271 -236.29762) (xy 6.272736 -236.28175) (xy 6.205416 -236.258193)
			(xy 6.141157 -236.227248) (xy 6.080766 -236.189302) (xy 6.025004 -236.144833) (xy 5.974571 -236.0944)
			(xy 5.930102 -236.038638) (xy 5.892156 -235.978247) (xy 5.861211 -235.913988) (xy 5.837654 -235.846668)
			(xy 5.821784 -235.777133) (xy 5.813798 -235.706259) (xy 4.583946 -235.706259) (xy 4.57596 -235.777133)
			(xy 4.56009 -235.846668) (xy 4.536533 -235.913988) (xy 4.505588 -235.978247) (xy 4.467642 -236.038638)
			(xy 4.423173 -236.0944) (xy 4.37274 -236.144833) (xy 4.316978 -236.189302) (xy 4.256587 -236.227248)
			(xy 4.192328 -236.258193) (xy 4.125008 -236.28175) (xy 4.055473 -236.29762) (xy 3.984599 -236.305606)
			(xy 3.913277 -236.305606) (xy 3.842403 -236.29762) (xy 3.772868 -236.28175) (xy 3.705548 -236.258193)
			(xy 3.641289 -236.227248) (xy 3.580898 -236.189302) (xy 3.525136 -236.144833) (xy 3.474703 -236.0944)
			(xy 3.430234 -236.038638) (xy 3.392288 -235.978247) (xy 3.361343 -235.913988) (xy 3.337786 -235.846668)
			(xy 3.321916 -235.777133) (xy 3.31393 -235.706259) (xy 1.53416 -235.706259) (xy 1.53416 -235.79582)
			(xy 1.534617 -235.818097) (xy 1.542378 -235.861969) (xy 1.557674 -235.903814) (xy 1.580038 -235.942348)
			(xy 1.608782 -235.976389) (xy 1.643025 -236.004892) (xy 1.681716 -236.026982) (xy 1.723668 -236.041983)
			(xy 1.767594 -236.049433) (xy 1.812146 -236.049104) (xy 1.834134 -236.045502) (xy 1.869571 -236.039499)
			(xy 1.941277 -236.034574) (xy 2.013082 -236.03777) (xy 2.084068 -236.049046) (xy 2.153329 -236.068259)
			(xy 2.219979 -236.095164) (xy 2.283169 -236.129416) (xy 2.342091 -236.170579) (xy 2.395992 -236.218126)
			(xy 2.444186 -236.271451) (xy 2.486055 -236.329872) (xy 2.521067 -236.392645) (xy 2.548772 -236.458966)
			(xy 2.568819 -236.52799) (xy 2.58095 -236.598835) (xy 2.585011 -236.670596) (xy 2.58095 -236.742357)
			(xy 2.568819 -236.813202) (xy 2.548772 -236.882226) (xy 2.521067 -236.948547) (xy 2.486055 -237.01132)
			(xy 2.444186 -237.069741) (xy 2.395992 -237.123066) (xy 2.342091 -237.170613) (xy 2.283169 -237.211776)
			(xy 2.219979 -237.246028) (xy 2.153329 -237.272933) (xy 2.084068 -237.292146) (xy 2.013082 -237.303422)
			(xy 1.941277 -237.306618) (xy 1.869571 -237.301693) (xy 1.834134 -237.29569) (xy 1.812146 -237.292119)
			(xy 1.767605 -237.291825) (xy 1.723694 -237.299297) (xy 1.681757 -237.314308) (xy 1.643078 -237.336397)
			(xy 1.60884 -237.364889) (xy 1.580092 -237.398912) (xy 1.557713 -237.437425) (xy 1.542388 -237.479248)
			(xy 1.534586 -237.523101) (xy 1.53416 -237.545372) (xy 1.53416 -237.706255) (xy 3.31393 -237.706255)
			(xy 3.31393 -237.634933) (xy 3.321916 -237.564059) (xy 3.337786 -237.494524) (xy 3.361343 -237.427204)
			(xy 3.392288 -237.362945) (xy 3.430234 -237.302554) (xy 3.474703 -237.246792) (xy 3.525136 -237.196359)
			(xy 3.580898 -237.15189) (xy 3.641289 -237.113944) (xy 3.705548 -237.082999) (xy 3.772868 -237.059442)
			(xy 3.842403 -237.043572) (xy 3.913277 -237.035586) (xy 3.984599 -237.035586) (xy 4.055473 -237.043572)
			(xy 4.125008 -237.059442) (xy 4.192328 -237.082999) (xy 4.256587 -237.113944) (xy 4.316978 -237.15189)
			(xy 4.37274 -237.196359) (xy 4.423173 -237.246792) (xy 4.467642 -237.302554) (xy 4.505588 -237.362945)
			(xy 4.536533 -237.427204) (xy 4.56009 -237.494524) (xy 4.57596 -237.564059) (xy 4.583946 -237.634933)
			(xy 4.584446 -237.670594) (xy 4.583946 -237.706255) (xy 5.813798 -237.706255) (xy 5.813798 -237.634933)
			(xy 5.821784 -237.564059) (xy 5.837654 -237.494524) (xy 5.861211 -237.427204) (xy 5.892156 -237.362945)
			(xy 5.930102 -237.302554) (xy 5.974571 -237.246792) (xy 6.025004 -237.196359) (xy 6.080766 -237.15189)
			(xy 6.141157 -237.113944) (xy 6.205416 -237.082999) (xy 6.272736 -237.059442) (xy 6.342271 -237.043572)
			(xy 6.413145 -237.035586) (xy 6.484467 -237.035586) (xy 6.555341 -237.043572) (xy 6.624876 -237.059442)
			(xy 6.692196 -237.082999) (xy 6.756455 -237.113944) (xy 6.816846 -237.15189) (xy 6.872608 -237.196359)
			(xy 6.923041 -237.246792) (xy 6.96751 -237.302554) (xy 7.005456 -237.362945) (xy 7.036401 -237.427204)
			(xy 7.059958 -237.494524) (xy 7.075828 -237.564059) (xy 7.083814 -237.634933) (xy 7.084314 -237.670594)
			(xy 7.083814 -237.706255) (xy 7.075828 -237.777129) (xy 7.059958 -237.846664) (xy 7.036401 -237.913984)
			(xy 7.005456 -237.978243) (xy 6.96751 -238.038634) (xy 6.923041 -238.094396) (xy 6.872608 -238.144829)
			(xy 6.816846 -238.189298) (xy 6.756455 -238.227244) (xy 6.692196 -238.258189) (xy 6.624876 -238.281746)
			(xy 6.555341 -238.297616) (xy 6.484467 -238.305602) (xy 6.413145 -238.305602) (xy 6.342271 -238.297616)
			(xy 6.272736 -238.281746) (xy 6.205416 -238.258189) (xy 6.141157 -238.227244) (xy 6.080766 -238.189298)
			(xy 6.025004 -238.144829) (xy 5.974571 -238.094396) (xy 5.930102 -238.038634) (xy 5.892156 -237.978243)
			(xy 5.861211 -237.913984) (xy 5.837654 -237.846664) (xy 5.821784 -237.777129) (xy 5.813798 -237.706255)
			(xy 4.583946 -237.706255) (xy 4.57596 -237.777129) (xy 4.56009 -237.846664) (xy 4.536533 -237.913984)
			(xy 4.505588 -237.978243) (xy 4.467642 -238.038634) (xy 4.423173 -238.094396) (xy 4.37274 -238.144829)
			(xy 4.316978 -238.189298) (xy 4.256587 -238.227244) (xy 4.192328 -238.258189) (xy 4.125008 -238.281746)
			(xy 4.055473 -238.297616) (xy 3.984599 -238.305602) (xy 3.913277 -238.305602) (xy 3.842403 -238.297616)
			(xy 3.772868 -238.281746) (xy 3.705548 -238.258189) (xy 3.641289 -238.227244) (xy 3.580898 -238.189298)
			(xy 3.525136 -238.144829) (xy 3.474703 -238.094396) (xy 3.430234 -238.038634) (xy 3.392288 -237.978243)
			(xy 3.361343 -237.913984) (xy 3.337786 -237.846664) (xy 3.321916 -237.777129) (xy 3.31393 -237.706255)
			(xy 1.53416 -237.706255) (xy 1.53416 -237.795816) (xy 1.534617 -237.818093) (xy 1.542377 -237.861966)
			(xy 1.557673 -237.903812) (xy 1.580036 -237.942346) (xy 1.60878 -237.976388) (xy 1.643023 -238.004891)
			(xy 1.681715 -238.026982) (xy 1.723667 -238.041983) (xy 1.767594 -238.049433) (xy 1.812146 -238.049104)
			(xy 1.834134 -238.045498) (xy 1.869571 -238.039495) (xy 1.941277 -238.03457) (xy 2.013082 -238.037766)
			(xy 2.084068 -238.049042) (xy 2.153329 -238.068255) (xy 2.219979 -238.09516) (xy 2.283169 -238.129412)
			(xy 2.342091 -238.170575) (xy 2.395992 -238.218122) (xy 2.444186 -238.271447) (xy 2.486055 -238.329868)
			(xy 2.521067 -238.392641) (xy 2.548772 -238.458962) (xy 2.568819 -238.527986) (xy 2.58095 -238.598831)
			(xy 2.585011 -238.670592) (xy 2.582993 -238.706253) (xy 7.813794 -238.706253) (xy 7.813794 -238.634931)
			(xy 7.82178 -238.564057) (xy 7.83765 -238.494522) (xy 7.861207 -238.427202) (xy 7.892152 -238.362943)
			(xy 7.930098 -238.302552) (xy 7.974567 -238.24679) (xy 8.025 -238.196357) (xy 8.080762 -238.151888)
			(xy 8.141153 -238.113942) (xy 8.205412 -238.082997) (xy 8.272732 -238.05944) (xy 8.342267 -238.04357)
			(xy 8.413141 -238.035584) (xy 8.484463 -238.035584) (xy 8.555337 -238.04357) (xy 8.624872 -238.05944)
			(xy 8.692192 -238.082997) (xy 8.756451 -238.113942) (xy 8.816842 -238.151888) (xy 8.872604 -238.196357)
			(xy 8.923037 -238.24679) (xy 8.967506 -238.302552) (xy 9.005452 -238.362943) (xy 9.036397 -238.427202)
			(xy 9.059954 -238.494522) (xy 9.075824 -238.564057) (xy 9.08381 -238.634931) (xy 9.08431 -238.670592)
			(xy 9.08381 -238.706253) (xy 9.075824 -238.777127) (xy 9.059954 -238.846662) (xy 9.036397 -238.913982)
			(xy 9.005452 -238.978241) (xy 8.967506 -239.038632) (xy 8.923037 -239.094394) (xy 8.872604 -239.144827)
			(xy 8.816842 -239.189296) (xy 8.756451 -239.227242) (xy 8.692192 -239.258187) (xy 8.624872 -239.281744)
			(xy 8.555337 -239.297614) (xy 8.484463 -239.3056) (xy 8.413141 -239.3056) (xy 8.342267 -239.297614)
			(xy 8.272732 -239.281744) (xy 8.205412 -239.258187) (xy 8.141153 -239.227242) (xy 8.080762 -239.189296)
			(xy 8.025 -239.144827) (xy 7.974567 -239.094394) (xy 7.930098 -239.038632) (xy 7.892152 -238.978241)
			(xy 7.861207 -238.913982) (xy 7.83765 -238.846662) (xy 7.82178 -238.777127) (xy 7.813794 -238.706253)
			(xy 2.582993 -238.706253) (xy 2.58095 -238.742353) (xy 2.568819 -238.813198) (xy 2.548772 -238.882222)
			(xy 2.521067 -238.948543) (xy 2.486055 -239.011316) (xy 2.444186 -239.069737) (xy 2.395992 -239.123062)
			(xy 2.342091 -239.170609) (xy 2.283169 -239.211772) (xy 2.219979 -239.246024) (xy 2.153329 -239.272929)
			(xy 2.084068 -239.292142) (xy 2.013082 -239.303418) (xy 1.941277 -239.306614) (xy 1.869571 -239.301689)
			(xy 1.834134 -239.295686) (xy 1.812149 -239.292114) (xy 1.767613 -239.291819) (xy 1.723707 -239.299291)
			(xy 1.681776 -239.314303) (xy 1.643104 -239.336394) (xy 1.608875 -239.364888) (xy 1.580137 -239.398913)
			(xy 1.55777 -239.437426) (xy 1.542459 -239.479249) (xy 1.534672 -239.5231) (xy 1.53416 -239.545368)
			(xy 1.53416 -239.706251) (xy 5.813798 -239.706251) (xy 5.813798 -239.634929) (xy 5.821784 -239.564055)
			(xy 5.837654 -239.49452) (xy 5.861211 -239.4272) (xy 5.892156 -239.362941) (xy 5.930102 -239.30255)
			(xy 5.974571 -239.246788) (xy 6.025004 -239.196355) (xy 6.080766 -239.151886) (xy 6.141157 -239.11394)
			(xy 6.205416 -239.082995) (xy 6.272736 -239.059438) (xy 6.342271 -239.043568) (xy 6.413145 -239.035582)
			(xy 6.484467 -239.035582) (xy 6.555341 -239.043568) (xy 6.624876 -239.059438) (xy 6.692196 -239.082995)
			(xy 6.756455 -239.11394) (xy 6.816846 -239.151886) (xy 6.872608 -239.196355) (xy 6.923041 -239.246788)
			(xy 6.96751 -239.30255) (xy 7.005456 -239.362941) (xy 7.036401 -239.4272) (xy 7.059958 -239.49452)
			(xy 7.075828 -239.564055) (xy 7.083814 -239.634929) (xy 7.084314 -239.67059) (xy 7.083814 -239.706251)
			(xy 7.075828 -239.777125) (xy 7.059958 -239.84666) (xy 7.036401 -239.91398) (xy 7.005456 -239.978239)
			(xy 6.96751 -240.03863) (xy 6.923041 -240.094392) (xy 6.872608 -240.144825) (xy 6.816846 -240.189294)
			(xy 6.756455 -240.22724) (xy 6.692196 -240.258185) (xy 6.624876 -240.281742) (xy 6.555341 -240.297612)
			(xy 6.484467 -240.305598) (xy 6.413145 -240.305598) (xy 6.342271 -240.297612) (xy 6.272736 -240.281742)
			(xy 6.205416 -240.258185) (xy 6.141157 -240.22724) (xy 6.080766 -240.189294) (xy 6.025004 -240.144825)
			(xy 5.974571 -240.094392) (xy 5.930102 -240.03863) (xy 5.892156 -239.978239) (xy 5.861211 -239.91398)
			(xy 5.837654 -239.84666) (xy 5.821784 -239.777125) (xy 5.813798 -239.706251) (xy 1.53416 -239.706251)
			(xy 1.53416 -239.795812) (xy 1.534618 -239.818088) (xy 1.542378 -239.861959) (xy 1.557675 -239.903803)
			(xy 1.580038 -239.942336) (xy 1.608783 -239.976376) (xy 1.643025 -240.004877) (xy 1.681716 -240.026966)
			(xy 1.723668 -240.041965) (xy 1.767593 -240.049414) (xy 1.812144 -240.049084) (xy 1.834134 -240.045494)
			(xy 1.869571 -240.039491) (xy 1.941277 -240.034566) (xy 2.013082 -240.037762) (xy 2.084068 -240.049038)
			(xy 2.153329 -240.068251) (xy 2.219979 -240.095156) (xy 2.283169 -240.129408) (xy 2.342091 -240.170571)
			(xy 2.395992 -240.218118) (xy 2.444186 -240.271443) (xy 2.486055 -240.329864) (xy 2.521067 -240.392637)
			(xy 2.548772 -240.458958) (xy 2.568819 -240.527982) (xy 2.58095 -240.598827) (xy 2.585011 -240.670588)
			(xy 2.582993 -240.706249) (xy 7.813794 -240.706249) (xy 7.813794 -240.634927) (xy 7.82178 -240.564053)
			(xy 7.83765 -240.494518) (xy 7.861207 -240.427198) (xy 7.892152 -240.362939) (xy 7.930098 -240.302548)
			(xy 7.974567 -240.246786) (xy 8.025 -240.196353) (xy 8.080762 -240.151884) (xy 8.141153 -240.113938)
			(xy 8.205412 -240.082993) (xy 8.272732 -240.059436) (xy 8.342267 -240.043566) (xy 8.413141 -240.03558)
			(xy 8.484463 -240.03558) (xy 8.555337 -240.043566) (xy 8.624872 -240.059436) (xy 8.692192 -240.082993)
			(xy 8.756451 -240.113938) (xy 8.816842 -240.151884) (xy 8.872604 -240.196353) (xy 8.923037 -240.246786)
			(xy 8.967506 -240.302548) (xy 9.005452 -240.362939) (xy 9.036397 -240.427198) (xy 9.059954 -240.494518)
			(xy 9.075824 -240.564053) (xy 9.08381 -240.634927) (xy 9.08431 -240.670588) (xy 9.08381 -240.706249)
			(xy 9.075824 -240.777123) (xy 9.059954 -240.846658) (xy 9.036397 -240.913978) (xy 9.005452 -240.978237)
			(xy 8.967506 -241.038628) (xy 8.923037 -241.09439) (xy 8.872604 -241.144823) (xy 8.816842 -241.189292)
			(xy 8.756451 -241.227238) (xy 8.692192 -241.258183) (xy 8.624872 -241.28174) (xy 8.555337 -241.29761)
			(xy 8.484463 -241.305596) (xy 8.413141 -241.305596) (xy 8.342267 -241.29761) (xy 8.272732 -241.28174)
			(xy 8.205412 -241.258183) (xy 8.141153 -241.227238) (xy 8.080762 -241.189292) (xy 8.025 -241.144823)
			(xy 7.974567 -241.09439) (xy 7.930098 -241.038628) (xy 7.892152 -240.978237) (xy 7.861207 -240.913978)
			(xy 7.83765 -240.846658) (xy 7.82178 -240.777123) (xy 7.813794 -240.706249) (xy 2.582993 -240.706249)
			(xy 2.58095 -240.742349) (xy 2.568819 -240.813194) (xy 2.548772 -240.882218) (xy 2.521067 -240.948539)
			(xy 2.486055 -241.011312) (xy 2.444186 -241.069733) (xy 2.395992 -241.123058) (xy 2.342091 -241.170605)
			(xy 2.283169 -241.211768) (xy 2.219979 -241.24602) (xy 2.153329 -241.272925) (xy 2.084068 -241.292138)
			(xy 2.013082 -241.303414) (xy 1.941277 -241.30661) (xy 1.869571 -241.301685) (xy 1.834134 -241.295682)
			(xy 1.812149 -241.29211) (xy 1.767613 -241.291815) (xy 1.723707 -241.299287) (xy 1.681775 -241.314299)
			(xy 1.643103 -241.33639) (xy 1.608873 -241.364884) (xy 1.580135 -241.398909) (xy 1.557767 -241.437422)
			(xy 1.542456 -241.479244) (xy 1.534669 -241.523096) (xy 1.53416 -241.545364) (xy 1.53416 -241.706247)
			(xy 3.31393 -241.706247) (xy 3.31393 -241.634925) (xy 3.321916 -241.564051) (xy 3.337786 -241.494516)
			(xy 3.361343 -241.427196) (xy 3.392288 -241.362937) (xy 3.430234 -241.302546) (xy 3.474703 -241.246784)
			(xy 3.525136 -241.196351) (xy 3.580898 -241.151882) (xy 3.641289 -241.113936) (xy 3.705548 -241.082991)
			(xy 3.772868 -241.059434) (xy 3.842403 -241.043564) (xy 3.913277 -241.035578) (xy 3.984599 -241.035578)
			(xy 4.055473 -241.043564) (xy 4.125008 -241.059434) (xy 4.192328 -241.082991) (xy 4.256587 -241.113936)
			(xy 4.316978 -241.151882) (xy 4.37274 -241.196351) (xy 4.423173 -241.246784) (xy 4.467642 -241.302546)
			(xy 4.505588 -241.362937) (xy 4.536533 -241.427196) (xy 4.56009 -241.494516) (xy 4.57596 -241.564051)
			(xy 4.583946 -241.634925) (xy 4.584446 -241.670586) (xy 4.583946 -241.706247) (xy 4.57596 -241.777121)
			(xy 4.56009 -241.846656) (xy 4.536533 -241.913976) (xy 4.505588 -241.978235) (xy 4.467642 -242.038626)
			(xy 4.423173 -242.094388) (xy 4.37274 -242.144821) (xy 4.316978 -242.18929) (xy 4.256587 -242.227236)
			(xy 4.192328 -242.258181) (xy 4.125008 -242.281738) (xy 4.055473 -242.297608) (xy 3.984599 -242.305594)
			(xy 3.913277 -242.305594) (xy 3.842403 -242.297608) (xy 3.772868 -242.281738) (xy 3.705548 -242.258181)
			(xy 3.641289 -242.227236) (xy 3.580898 -242.18929) (xy 3.525136 -242.144821) (xy 3.474703 -242.094388)
			(xy 3.430234 -242.038626) (xy 3.392288 -241.978235) (xy 3.361343 -241.913976) (xy 3.337786 -241.846656)
			(xy 3.321916 -241.777121) (xy 3.31393 -241.706247) (xy 1.53416 -241.706247) (xy 1.53416 -241.795808)
			(xy 1.534617 -241.818085) (xy 1.542377 -241.861956) (xy 1.557674 -241.903801) (xy 1.580037 -241.942334)
			(xy 1.608781 -241.976374) (xy 1.643024 -242.004876) (xy 1.681715 -242.026966) (xy 1.723667 -242.041965)
			(xy 1.767593 -242.049414) (xy 1.812144 -242.049083) (xy 1.834134 -242.04549) (xy 1.869571 -242.039487)
			(xy 1.941277 -242.034562) (xy 2.013082 -242.037758) (xy 2.084068 -242.049034) (xy 2.153329 -242.068247)
			(xy 2.219979 -242.095152) (xy 2.283169 -242.129404) (xy 2.342091 -242.170567) (xy 2.395992 -242.218114)
			(xy 2.444186 -242.271439) (xy 2.486055 -242.32986) (xy 2.521067 -242.392633) (xy 2.548772 -242.458954)
			(xy 2.568819 -242.527978) (xy 2.58095 -242.598823) (xy 2.585011 -242.670584) (xy 2.582993 -242.706245)
			(xy 7.813794 -242.706245) (xy 7.813794 -242.634923) (xy 7.82178 -242.564049) (xy 7.83765 -242.494514)
			(xy 7.861207 -242.427194) (xy 7.892152 -242.362935) (xy 7.930098 -242.302544) (xy 7.974567 -242.246782)
			(xy 8.025 -242.196349) (xy 8.080762 -242.15188) (xy 8.141153 -242.113934) (xy 8.205412 -242.082989)
			(xy 8.272732 -242.059432) (xy 8.342267 -242.043562) (xy 8.413141 -242.035576) (xy 8.484463 -242.035576)
			(xy 8.555337 -242.043562) (xy 8.624872 -242.059432) (xy 8.692192 -242.082989) (xy 8.756451 -242.113934)
			(xy 8.816842 -242.15188) (xy 8.872604 -242.196349) (xy 8.923037 -242.246782) (xy 8.967506 -242.302544)
			(xy 9.005452 -242.362935) (xy 9.036397 -242.427194) (xy 9.059954 -242.494514) (xy 9.075824 -242.564049)
			(xy 9.08381 -242.634923) (xy 9.08431 -242.670584) (xy 9.08381 -242.706245) (xy 9.075824 -242.777119)
			(xy 9.059954 -242.846654) (xy 9.036397 -242.913974) (xy 9.005452 -242.978233) (xy 8.967506 -243.038624)
			(xy 8.923037 -243.094386) (xy 8.872604 -243.144819) (xy 8.816842 -243.189288) (xy 8.756451 -243.227234)
			(xy 8.692192 -243.258179) (xy 8.624872 -243.281736) (xy 8.555337 -243.297606) (xy 8.484463 -243.305592)
			(xy 8.413141 -243.305592) (xy 8.342267 -243.297606) (xy 8.272732 -243.281736) (xy 8.205412 -243.258179)
			(xy 8.141153 -243.227234) (xy 8.080762 -243.189288) (xy 8.025 -243.144819) (xy 7.974567 -243.094386)
			(xy 7.930098 -243.038624) (xy 7.892152 -242.978233) (xy 7.861207 -242.913974) (xy 7.83765 -242.846654)
			(xy 7.82178 -242.777119) (xy 7.813794 -242.706245) (xy 2.582993 -242.706245) (xy 2.58095 -242.742345)
			(xy 2.568819 -242.81319) (xy 2.548772 -242.882214) (xy 2.521067 -242.948535) (xy 2.486055 -243.011308)
			(xy 2.444186 -243.069729) (xy 2.395992 -243.123054) (xy 2.342091 -243.170601) (xy 2.283169 -243.211764)
			(xy 2.219979 -243.246016) (xy 2.153329 -243.272921) (xy 2.084068 -243.292134) (xy 2.013082 -243.30341)
			(xy 1.941277 -243.306606) (xy 1.869571 -243.301681) (xy 1.834134 -243.295678) (xy 1.812149 -243.292106)
			(xy 1.767612 -243.291811) (xy 1.723706 -243.299283) (xy 1.681775 -243.314295) (xy 1.643102 -243.336386)
			(xy 1.608872 -243.36488) (xy 1.580133 -243.398904) (xy 1.557765 -243.437418) (xy 1.542453 -243.47924)
			(xy 1.534665 -243.523092) (xy 1.53416 -243.54536) (xy 1.53416 -243.706243) (xy 3.31393 -243.706243)
			(xy 3.31393 -243.634921) (xy 3.321916 -243.564047) (xy 3.337786 -243.494512) (xy 3.361343 -243.427192)
			(xy 3.392288 -243.362933) (xy 3.430234 -243.302542) (xy 3.474703 -243.24678) (xy 3.525136 -243.196347)
			(xy 3.580898 -243.151878) (xy 3.641289 -243.113932) (xy 3.705548 -243.082987) (xy 3.772868 -243.05943)
			(xy 3.842403 -243.04356) (xy 3.913277 -243.035574) (xy 3.984599 -243.035574) (xy 4.055473 -243.04356)
			(xy 4.125008 -243.05943) (xy 4.192328 -243.082987) (xy 4.256587 -243.113932) (xy 4.316978 -243.151878)
			(xy 4.37274 -243.196347) (xy 4.423173 -243.24678) (xy 4.467642 -243.302542) (xy 4.505588 -243.362933)
			(xy 4.536533 -243.427192) (xy 4.56009 -243.494512) (xy 4.57596 -243.564047) (xy 4.583946 -243.634921)
			(xy 4.584446 -243.670582) (xy 4.583946 -243.706243) (xy 5.813798 -243.706243) (xy 5.813798 -243.634921)
			(xy 5.821784 -243.564047) (xy 5.837654 -243.494512) (xy 5.861211 -243.427192) (xy 5.892156 -243.362933)
			(xy 5.930102 -243.302542) (xy 5.974571 -243.24678) (xy 6.025004 -243.196347) (xy 6.080766 -243.151878)
			(xy 6.141157 -243.113932) (xy 6.205416 -243.082987) (xy 6.272736 -243.05943) (xy 6.342271 -243.04356)
			(xy 6.413145 -243.035574) (xy 6.484467 -243.035574) (xy 6.555341 -243.04356) (xy 6.624876 -243.05943)
			(xy 6.692196 -243.082987) (xy 6.756455 -243.113932) (xy 6.816846 -243.151878) (xy 6.872608 -243.196347)
			(xy 6.923041 -243.24678) (xy 6.96751 -243.302542) (xy 7.005456 -243.362933) (xy 7.036401 -243.427192)
			(xy 7.059958 -243.494512) (xy 7.075828 -243.564047) (xy 7.083814 -243.634921) (xy 7.084314 -243.670582)
			(xy 7.083814 -243.706243) (xy 7.075828 -243.777117) (xy 7.059958 -243.846652) (xy 7.036401 -243.913972)
			(xy 7.005456 -243.978231) (xy 6.96751 -244.038622) (xy 6.923041 -244.094384) (xy 6.872608 -244.144817)
			(xy 6.816846 -244.189286) (xy 6.756455 -244.227232) (xy 6.692196 -244.258177) (xy 6.624876 -244.281734)
			(xy 6.555341 -244.297604) (xy 6.484467 -244.30559) (xy 6.413145 -244.30559) (xy 6.342271 -244.297604)
			(xy 6.272736 -244.281734) (xy 6.205416 -244.258177) (xy 6.141157 -244.227232) (xy 6.080766 -244.189286)
			(xy 6.025004 -244.144817) (xy 5.974571 -244.094384) (xy 5.930102 -244.038622) (xy 5.892156 -243.978231)
			(xy 5.861211 -243.913972) (xy 5.837654 -243.846652) (xy 5.821784 -243.777117) (xy 5.813798 -243.706243)
			(xy 4.583946 -243.706243) (xy 4.57596 -243.777117) (xy 4.56009 -243.846652) (xy 4.536533 -243.913972)
			(xy 4.505588 -243.978231) (xy 4.467642 -244.038622) (xy 4.423173 -244.094384) (xy 4.37274 -244.144817)
			(xy 4.316978 -244.189286) (xy 4.256587 -244.227232) (xy 4.192328 -244.258177) (xy 4.125008 -244.281734)
			(xy 4.055473 -244.297604) (xy 3.984599 -244.30559) (xy 3.913277 -244.30559) (xy 3.842403 -244.297604)
			(xy 3.772868 -244.281734) (xy 3.705548 -244.258177) (xy 3.641289 -244.227232) (xy 3.580898 -244.189286)
			(xy 3.525136 -244.144817) (xy 3.474703 -244.094384) (xy 3.430234 -244.038622) (xy 3.392288 -243.978231)
			(xy 3.361343 -243.913972) (xy 3.337786 -243.846652) (xy 3.321916 -243.777117) (xy 3.31393 -243.706243)
			(xy 1.53416 -243.706243) (xy 1.53416 -244.706241) (xy 7.813794 -244.706241) (xy 7.813794 -244.634919)
			(xy 7.82178 -244.564045) (xy 7.83765 -244.49451) (xy 7.861207 -244.42719) (xy 7.892152 -244.362931)
			(xy 7.930098 -244.30254) (xy 7.974567 -244.246778) (xy 8.025 -244.196345) (xy 8.080762 -244.151876)
			(xy 8.141153 -244.11393) (xy 8.205412 -244.082985) (xy 8.272732 -244.059428) (xy 8.342267 -244.043558)
			(xy 8.413141 -244.035572) (xy 8.484463 -244.035572) (xy 8.555337 -244.043558) (xy 8.624872 -244.059428)
			(xy 8.692192 -244.082985) (xy 8.756451 -244.11393) (xy 8.816842 -244.151876) (xy 8.872604 -244.196345)
			(xy 8.923037 -244.246778) (xy 8.967506 -244.30254) (xy 9.005452 -244.362931) (xy 9.036397 -244.42719)
			(xy 9.059954 -244.49451) (xy 9.075824 -244.564045) (xy 9.08381 -244.634919) (xy 9.08431 -244.67058)
			(xy 9.08381 -244.706241) (xy 9.075824 -244.777115) (xy 9.059954 -244.84665) (xy 9.036397 -244.91397)
			(xy 9.005452 -244.978229) (xy 8.967506 -245.03862) (xy 8.923037 -245.094382) (xy 8.872604 -245.144815)
			(xy 8.816842 -245.189284) (xy 8.756451 -245.22723) (xy 8.692192 -245.258175) (xy 8.624872 -245.281732)
			(xy 8.555337 -245.297602) (xy 8.484463 -245.305588) (xy 8.413141 -245.305588) (xy 8.342267 -245.297602)
			(xy 8.272732 -245.281732) (xy 8.205412 -245.258175) (xy 8.141153 -245.22723) (xy 8.080762 -245.189284)
			(xy 8.025 -245.144815) (xy 7.974567 -245.094382) (xy 7.930098 -245.03862) (xy 7.892152 -244.978229)
			(xy 7.861207 -244.91397) (xy 7.83765 -244.84665) (xy 7.82178 -244.777115) (xy 7.813794 -244.706241)
			(xy 1.53416 -244.706241) (xy 1.53416 -245.706239) (xy 3.31393 -245.706239) (xy 3.31393 -245.634917)
			(xy 3.321916 -245.564043) (xy 3.337786 -245.494508) (xy 3.361343 -245.427188) (xy 3.392288 -245.362929)
			(xy 3.430234 -245.302538) (xy 3.474703 -245.246776) (xy 3.525136 -245.196343) (xy 3.580898 -245.151874)
			(xy 3.641289 -245.113928) (xy 3.705548 -245.082983) (xy 3.772868 -245.059426) (xy 3.842403 -245.043556)
			(xy 3.913277 -245.03557) (xy 3.984599 -245.03557) (xy 4.055473 -245.043556) (xy 4.125008 -245.059426)
			(xy 4.192328 -245.082983) (xy 4.256587 -245.113928) (xy 4.316978 -245.151874) (xy 4.37274 -245.196343)
			(xy 4.423173 -245.246776) (xy 4.467642 -245.302538) (xy 4.505588 -245.362929) (xy 4.536533 -245.427188)
			(xy 4.56009 -245.494508) (xy 4.57596 -245.564043) (xy 4.583946 -245.634917) (xy 4.584446 -245.670578)
			(xy 4.583946 -245.706239) (xy 5.813798 -245.706239) (xy 5.813798 -245.634917) (xy 5.821784 -245.564043)
			(xy 5.837654 -245.494508) (xy 5.861211 -245.427188) (xy 5.892156 -245.362929) (xy 5.930102 -245.302538)
			(xy 5.974571 -245.246776) (xy 6.025004 -245.196343) (xy 6.080766 -245.151874) (xy 6.141157 -245.113928)
			(xy 6.205416 -245.082983) (xy 6.272736 -245.059426) (xy 6.342271 -245.043556) (xy 6.413145 -245.03557)
			(xy 6.484467 -245.03557) (xy 6.555341 -245.043556) (xy 6.624876 -245.059426) (xy 6.692196 -245.082983)
			(xy 6.756455 -245.113928) (xy 6.816846 -245.151874) (xy 6.872608 -245.196343) (xy 6.923041 -245.246776)
			(xy 6.96751 -245.302538) (xy 7.005456 -245.362929) (xy 7.036401 -245.427188) (xy 7.059958 -245.494508)
			(xy 7.075828 -245.564043) (xy 7.083814 -245.634917) (xy 7.084314 -245.670578) (xy 7.083814 -245.706239)
			(xy 7.075828 -245.777113) (xy 7.059958 -245.846648) (xy 7.036401 -245.913968) (xy 7.005456 -245.978227)
			(xy 6.96751 -246.038618) (xy 6.923041 -246.09438) (xy 6.872608 -246.144813) (xy 6.816846 -246.189282)
			(xy 6.756455 -246.227228) (xy 6.692196 -246.258173) (xy 6.624876 -246.28173) (xy 6.555341 -246.2976)
			(xy 6.484467 -246.305586) (xy 6.413145 -246.305586) (xy 6.342271 -246.2976) (xy 6.272736 -246.28173)
			(xy 6.205416 -246.258173) (xy 6.141157 -246.227228) (xy 6.080766 -246.189282) (xy 6.025004 -246.144813)
			(xy 5.974571 -246.09438) (xy 5.930102 -246.038618) (xy 5.892156 -245.978227) (xy 5.861211 -245.913968)
			(xy 5.837654 -245.846648) (xy 5.821784 -245.777113) (xy 5.813798 -245.706239) (xy 4.583946 -245.706239)
			(xy 4.57596 -245.777113) (xy 4.56009 -245.846648) (xy 4.536533 -245.913968) (xy 4.505588 -245.978227)
			(xy 4.467642 -246.038618) (xy 4.423173 -246.09438) (xy 4.37274 -246.144813) (xy 4.316978 -246.189282)
			(xy 4.256587 -246.227228) (xy 4.192328 -246.258173) (xy 4.125008 -246.28173) (xy 4.055473 -246.2976)
			(xy 3.984599 -246.305586) (xy 3.913277 -246.305586) (xy 3.842403 -246.2976) (xy 3.772868 -246.28173)
			(xy 3.705548 -246.258173) (xy 3.641289 -246.227228) (xy 3.580898 -246.189282) (xy 3.525136 -246.144813)
			(xy 3.474703 -246.09438) (xy 3.430234 -246.038618) (xy 3.392288 -245.978227) (xy 3.361343 -245.913968)
			(xy 3.337786 -245.846648) (xy 3.321916 -245.777113) (xy 3.31393 -245.706239) (xy 1.53416 -245.706239)
			(xy 1.53416 -245.7958) (xy 1.534617 -245.818076) (xy 1.542378 -245.861948) (xy 1.557674 -245.903792)
			(xy 1.580038 -245.942325) (xy 1.608782 -245.976365) (xy 1.643025 -246.004867) (xy 1.681716 -246.026956)
			(xy 1.723667 -246.041955) (xy 1.767593 -246.049404) (xy 1.812144 -246.049073) (xy 1.834134 -246.045482)
			(xy 1.869571 -246.039479) (xy 1.941277 -246.034554) (xy 2.013082 -246.03775) (xy 2.084068 -246.049026)
			(xy 2.153329 -246.068239) (xy 2.219979 -246.095144) (xy 2.283169 -246.129396) (xy 2.342091 -246.170559)
			(xy 2.395992 -246.218106) (xy 2.444186 -246.271431) (xy 2.486055 -246.329852) (xy 2.521067 -246.392625)
			(xy 2.548772 -246.458946) (xy 2.568819 -246.52797) (xy 2.58095 -246.598815) (xy 2.585011 -246.670576)
			(xy 2.58095 -246.742337) (xy 2.568819 -246.813182) (xy 2.548772 -246.882206) (xy 2.521067 -246.948527)
			(xy 2.486055 -247.0113) (xy 2.444186 -247.069721) (xy 2.395992 -247.123046) (xy 2.342091 -247.170593)
			(xy 2.283169 -247.211756) (xy 2.219979 -247.246008) (xy 2.153329 -247.272913) (xy 2.084068 -247.292126)
			(xy 2.013082 -247.303402) (xy 1.941277 -247.306598) (xy 1.869571 -247.301673) (xy 1.834134 -247.29567)
			(xy 1.812148 -247.292098) (xy 1.767612 -247.291803) (xy 1.723705 -247.299276) (xy 1.681773 -247.314287)
			(xy 1.6431 -247.336378) (xy 1.608869 -247.364872) (xy 1.580129 -247.398896) (xy 1.55776 -247.437409)
			(xy 1.542447 -247.479232) (xy 1.534658 -247.523083) (xy 1.53416 -247.545352) (xy 1.53416 -247.706235)
			(xy 3.31393 -247.706235) (xy 3.31393 -247.634913) (xy 3.321916 -247.564039) (xy 3.337786 -247.494504)
			(xy 3.361343 -247.427184) (xy 3.392288 -247.362925) (xy 3.430234 -247.302534) (xy 3.474703 -247.246772)
			(xy 3.525136 -247.196339) (xy 3.580898 -247.15187) (xy 3.641289 -247.113924) (xy 3.705548 -247.082979)
			(xy 3.772868 -247.059422) (xy 3.842403 -247.043552) (xy 3.913277 -247.035566) (xy 3.984599 -247.035566)
			(xy 4.055473 -247.043552) (xy 4.125008 -247.059422) (xy 4.192328 -247.082979) (xy 4.256587 -247.113924)
			(xy 4.316978 -247.15187) (xy 4.37274 -247.196339) (xy 4.423173 -247.246772) (xy 4.467642 -247.302534)
			(xy 4.505588 -247.362925) (xy 4.536533 -247.427184) (xy 4.56009 -247.494504) (xy 4.57596 -247.564039)
			(xy 4.583946 -247.634913) (xy 4.584446 -247.670574) (xy 4.583946 -247.706235) (xy 5.813798 -247.706235)
			(xy 5.813798 -247.634913) (xy 5.821784 -247.564039) (xy 5.837654 -247.494504) (xy 5.861211 -247.427184)
			(xy 5.892156 -247.362925) (xy 5.930102 -247.302534) (xy 5.974571 -247.246772) (xy 6.025004 -247.196339)
			(xy 6.080766 -247.15187) (xy 6.141157 -247.113924) (xy 6.205416 -247.082979) (xy 6.272736 -247.059422)
			(xy 6.342271 -247.043552) (xy 6.413145 -247.035566) (xy 6.484467 -247.035566) (xy 6.555341 -247.043552)
			(xy 6.624876 -247.059422) (xy 6.692196 -247.082979) (xy 6.756455 -247.113924) (xy 6.816846 -247.15187)
			(xy 6.872608 -247.196339) (xy 6.923041 -247.246772) (xy 6.96751 -247.302534) (xy 7.005456 -247.362925)
			(xy 7.036401 -247.427184) (xy 7.059958 -247.494504) (xy 7.075828 -247.564039) (xy 7.083814 -247.634913)
			(xy 7.084314 -247.670574) (xy 7.083814 -247.706235) (xy 7.075828 -247.777109) (xy 7.059958 -247.846644)
			(xy 7.036401 -247.913964) (xy 7.005456 -247.978223) (xy 6.96751 -248.038614) (xy 6.923041 -248.094376)
			(xy 6.872608 -248.144809) (xy 6.816846 -248.189278) (xy 6.756455 -248.227224) (xy 6.692196 -248.258169)
			(xy 6.624876 -248.281726) (xy 6.555341 -248.297596) (xy 6.484467 -248.305582) (xy 6.413145 -248.305582)
			(xy 6.342271 -248.297596) (xy 6.272736 -248.281726) (xy 6.205416 -248.258169) (xy 6.141157 -248.227224)
			(xy 6.080766 -248.189278) (xy 6.025004 -248.144809) (xy 5.974571 -248.094376) (xy 5.930102 -248.038614)
			(xy 5.892156 -247.978223) (xy 5.861211 -247.913964) (xy 5.837654 -247.846644) (xy 5.821784 -247.777109)
			(xy 5.813798 -247.706235) (xy 4.583946 -247.706235) (xy 4.57596 -247.777109) (xy 4.56009 -247.846644)
			(xy 4.536533 -247.913964) (xy 4.505588 -247.978223) (xy 4.467642 -248.038614) (xy 4.423173 -248.094376)
			(xy 4.37274 -248.144809) (xy 4.316978 -248.189278) (xy 4.256587 -248.227224) (xy 4.192328 -248.258169)
			(xy 4.125008 -248.281726) (xy 4.055473 -248.297596) (xy 3.984599 -248.305582) (xy 3.913277 -248.305582)
			(xy 3.842403 -248.297596) (xy 3.772868 -248.281726) (xy 3.705548 -248.258169) (xy 3.641289 -248.227224)
			(xy 3.580898 -248.189278) (xy 3.525136 -248.144809) (xy 3.474703 -248.094376) (xy 3.430234 -248.038614)
			(xy 3.392288 -247.978223) (xy 3.361343 -247.913964) (xy 3.337786 -247.846644) (xy 3.321916 -247.777109)
			(xy 3.31393 -247.706235) (xy 1.53416 -247.706235) (xy 1.53416 -247.795796) (xy 1.534617 -247.818073)
			(xy 1.542377 -247.861945) (xy 1.557673 -247.90379) (xy 1.580036 -247.942323) (xy 1.608781 -247.976364)
			(xy 1.643024 -248.004866) (xy 1.681715 -248.026956) (xy 1.723667 -248.041955) (xy 1.767593 -248.049404)
			(xy 1.812145 -248.049073) (xy 1.834134 -248.045478) (xy 1.869571 -248.039475) (xy 1.941277 -248.03455)
			(xy 2.013082 -248.037746) (xy 2.084068 -248.049022) (xy 2.153329 -248.068235) (xy 2.219979 -248.09514)
			(xy 2.283169 -248.129392) (xy 2.342091 -248.170555) (xy 2.395992 -248.218102) (xy 2.444186 -248.271427)
			(xy 2.486055 -248.329848) (xy 2.521067 -248.392621) (xy 2.548772 -248.458942) (xy 2.568819 -248.527966)
			(xy 2.58095 -248.598811) (xy 2.585011 -248.670572) (xy 2.58095 -248.742333) (xy 2.568819 -248.813178)
			(xy 2.548772 -248.882202) (xy 2.521067 -248.948523) (xy 2.486055 -249.011296) (xy 2.444186 -249.069717)
			(xy 2.395992 -249.123042) (xy 2.342091 -249.170589) (xy 2.283169 -249.211752) (xy 2.219979 -249.246004)
			(xy 2.153329 -249.272909) (xy 2.084068 -249.292122) (xy 2.013082 -249.303398) (xy 1.941277 -249.306594)
			(xy 1.869571 -249.301669) (xy 1.834134 -249.295666) (xy 1.812148 -249.292094) (xy 1.767611 -249.291799)
			(xy 1.723704 -249.299272) (xy 1.681772 -249.314283) (xy 1.643099 -249.336374) (xy 1.608868 -249.364868)
			(xy 1.580127 -249.398892) (xy 1.557758 -249.437405) (xy 1.542444 -249.479228) (xy 1.534654 -249.523079)
			(xy 1.53416 -249.545348) (xy 1.53416 -251.652726) (xy 3.313144 -251.652726) (xy 3.319107 -251.58188)
			(xy 3.33294 -251.512142) (xy 3.35447 -251.444383) (xy 3.383429 -251.379451) (xy 3.419454 -251.318157)
			(xy 3.462095 -251.261266) (xy 3.510819 -251.209491) (xy 3.565018 -251.163477) (xy 3.624014 -251.1238)
			(xy 3.655314 -251.10694) (xy 3.674734 -251.096276) (xy 3.709879 -251.069308) (xy 3.739815 -251.036654)
			(xy 3.763636 -250.999303) (xy 3.780619 -250.958389) (xy 3.790251 -250.915149) (xy 3.79224 -250.870894)
			(xy 3.786524 -250.826964) (xy 3.773279 -250.784691) (xy 3.763518 -250.764802) (xy 3.738506 -250.715541)
			(xy 3.694475 -250.614203) (xy 3.657468 -250.510095) (xy 3.627656 -250.403703) (xy 3.605179 -250.295523)
			(xy 3.590142 -250.186061) (xy 3.582615 -250.075827) (xy 3.582162 -250.020582) (xy 3.582667 -249.963207)
			(xy 3.590809 -249.848747) (xy 3.607047 -249.735153) (xy 3.6313 -249.622996) (xy 3.663446 -249.512841)
			(xy 3.703323 -249.405244) (xy 3.75073 -249.300745) (xy 3.805428 -249.199871) (xy 3.867141 -249.10313)
			(xy 3.93556 -249.011009) (xy 4.01034 -248.923972) (xy 4.091103 -248.842458) (xy 4.177444 -248.766876)
			(xy 4.268927 -248.697607) (xy 4.365092 -248.635) (xy 4.465455 -248.57937) (xy 4.569511 -248.530998)
			(xy 4.676734 -248.490126) (xy 4.786587 -248.456962) (xy 4.898514 -248.431671) (xy 5.011953 -248.414381)
			(xy 5.126333 -248.40518) (xy 5.241077 -248.404113) (xy 5.355608 -248.411186) (xy 5.46935 -248.426363)
			(xy 5.581728 -248.449568) (xy 5.692178 -248.480683) (xy 5.800143 -248.519554) (xy 5.90508 -248.565982)
			(xy 6.00646 -248.619736) (xy 6.103773 -248.680544) (xy 6.139045 -248.706233) (xy 7.813794 -248.706233)
			(xy 7.813794 -248.634911) (xy 7.82178 -248.564037) (xy 7.83765 -248.494502) (xy 7.861207 -248.427182)
			(xy 7.892152 -248.362923) (xy 7.930098 -248.302532) (xy 7.974567 -248.24677) (xy 8.025 -248.196337)
			(xy 8.080762 -248.151868) (xy 8.141153 -248.113922) (xy 8.205412 -248.082977) (xy 8.272732 -248.05942)
			(xy 8.342267 -248.04355) (xy 8.413141 -248.035564) (xy 8.484463 -248.035564) (xy 8.555337 -248.04355)
			(xy 8.624872 -248.05942) (xy 8.692192 -248.082977) (xy 8.756451 -248.113922) (xy 8.816842 -248.151868)
			(xy 8.872604 -248.196337) (xy 8.923037 -248.24677) (xy 8.967506 -248.302532) (xy 9.005452 -248.362923)
			(xy 9.036397 -248.427182) (xy 9.059954 -248.494502) (xy 9.075824 -248.564037) (xy 9.08381 -248.634911)
			(xy 9.08431 -248.670572) (xy 9.08381 -248.706233) (xy 9.075824 -248.777107) (xy 9.059954 -248.846642)
			(xy 9.036397 -248.913962) (xy 9.005452 -248.978221) (xy 8.967506 -249.038612) (xy 8.923037 -249.094374)
			(xy 8.872604 -249.144807) (xy 8.816842 -249.189276) (xy 8.756451 -249.227222) (xy 8.692192 -249.258167)
			(xy 8.624872 -249.281724) (xy 8.555337 -249.297594) (xy 8.484463 -249.30558) (xy 8.413141 -249.30558)
			(xy 8.342267 -249.297594) (xy 8.272732 -249.281724) (xy 8.205412 -249.258167) (xy 8.141153 -249.227222)
			(xy 8.080762 -249.189276) (xy 8.025 -249.144807) (xy 7.974567 -249.094374) (xy 7.930098 -249.038612)
			(xy 7.892152 -248.978221) (xy 7.861207 -248.913962) (xy 7.83765 -248.846642) (xy 7.82178 -248.777107)
			(xy 7.813794 -248.706233) (xy 6.139045 -248.706233) (xy 6.196529 -248.748099) (xy 6.284261 -248.822063)
			(xy 6.366526 -248.902061) (xy 6.442911 -248.987693) (xy 6.513031 -249.078525) (xy 6.576533 -249.174102)
			(xy 6.633098 -249.273941) (xy 6.68244 -249.37754) (xy 6.72431 -249.484377) (xy 6.758499 -249.593915)
			(xy 6.784834 -249.705601) (xy 6.803182 -249.818874) (xy 6.813452 -249.933163) (xy 6.81559 -250.047892)
			(xy 6.809587 -250.162485) (xy 6.795473 -250.276362) (xy 6.773318 -250.388953) (xy 6.743235 -250.499688)
			(xy 6.705375 -250.608012) (xy 6.659928 -250.713378) (xy 6.633972 -250.764548) (xy 6.624195 -250.784446)
			(xy 6.610935 -250.826745) (xy 6.605209 -250.870704) (xy 6.607191 -250.914989) (xy 6.616821 -250.95826)
			(xy 6.633807 -250.999206) (xy 6.657635 -251.036587) (xy 6.687583 -251.069271) (xy 6.722744 -251.096268)
			(xy 6.742176 -251.10694) (xy 6.773477 -251.123798) (xy 6.832484 -251.163456) (xy 6.886695 -251.209454)
			(xy 6.935433 -251.261215) (xy 6.978089 -251.318093) (xy 7.014129 -251.379377) (xy 7.043103 -251.444301)
			(xy 7.06465 -251.512053) (xy 7.078498 -251.581787) (xy 7.084477 -251.652631) (xy 7.08251 -251.7237)
			(xy 7.072622 -251.794105) (xy 7.054938 -251.862966) (xy 7.029677 -251.929423) (xy 6.997156 -251.992645)
			(xy 6.957782 -252.051842) (xy 6.912045 -252.106274) (xy 6.860519 -252.15526) (xy 6.803846 -252.198189)
			(xy 6.742736 -252.234523) (xy 6.677952 -252.263809) (xy 6.610304 -252.285681) (xy 6.540638 -252.299864)
			(xy 6.469823 -252.306183) (xy 6.398746 -252.304558) (xy 6.328294 -252.295009) (xy 6.259348 -252.277655)
			(xy 6.192771 -252.252714) (xy 6.129393 -252.220497) (xy 6.070008 -252.181408) (xy 6.015357 -252.135933)
			(xy 5.966124 -252.084643) (xy 5.922923 -252.028177) (xy 5.886296 -251.967243) (xy 5.856699 -251.9026)
			(xy 5.834503 -251.835058) (xy 5.82676 -251.80036) (xy 5.821807 -251.778751) (xy 5.805353 -251.737588)
			(xy 5.782007 -251.699904) (xy 5.752477 -251.666841) (xy 5.71766 -251.639402) (xy 5.67861 -251.618419)
			(xy 5.636512 -251.604529) (xy 5.592643 -251.598152) (xy 5.548333 -251.599483) (xy 5.526532 -251.60351)
			(xy 5.472591 -251.614244) (xy 5.36362 -251.629213) (xy 5.253883 -251.636735) (xy 5.143889 -251.636775)
			(xy 5.034146 -251.629333) (xy 4.925164 -251.614443) (xy 4.871212 -251.603764) (xy 4.849427 -251.599696)
			(xy 4.805133 -251.598335) (xy 4.761275 -251.604683) (xy 4.719185 -251.618545) (xy 4.680139 -251.639502)
			(xy 4.645323 -251.666917) (xy 4.615793 -251.699959) (xy 4.592445 -251.737624) (xy 4.575989 -251.77877)
			(xy 4.570984 -251.80036) (xy 4.563244 -251.835059) (xy 4.541045 -251.902602) (xy 4.511446 -251.967244)
			(xy 4.474817 -252.028179) (xy 4.431616 -252.084646) (xy 4.382382 -252.135937) (xy 4.327731 -252.181413)
			(xy 4.268345 -252.220505) (xy 4.204968 -252.252724) (xy 4.138391 -252.277668) (xy 4.069445 -252.295026)
			(xy 3.998993 -252.304579) (xy 3.927914 -252.30621) (xy 3.857098 -252.299897) (xy 3.787429 -252.285719)
			(xy 3.719778 -252.263855) (xy 3.65499 -252.234575) (xy 3.593874 -252.198248) (xy 3.537195 -252.155326)
			(xy 3.485661 -252.106346) (xy 3.439916 -252.051921) (xy 3.400531 -251.99273) (xy 3.367999 -251.929512)
			(xy 3.342726 -251.863059) (xy 3.325028 -251.7942) (xy 3.315126 -251.723796) (xy 3.313144 -251.652726)
			(xy 1.53416 -251.652726) (xy 1.53416 -251.795788) (xy 1.534617 -251.818065) (xy 1.542377 -251.861936)
			(xy 1.557674 -251.903781) (xy 1.580037 -251.942314) (xy 1.608781 -251.976354) (xy 1.643024 -252.004856)
			(xy 1.681715 -252.026946) (xy 1.723667 -252.041945) (xy 1.767593 -252.049394) (xy 1.812144 -252.049063)
			(xy 1.834134 -252.04547) (xy 1.869571 -252.039467) (xy 1.941277 -252.034542) (xy 2.013082 -252.037738)
			(xy 2.084068 -252.049014) (xy 2.153329 -252.068227) (xy 2.219979 -252.095132) (xy 2.283169 -252.129384)
			(xy 2.342091 -252.170547) (xy 2.395992 -252.218094) (xy 2.444186 -252.271419) (xy 2.486055 -252.32984)
			(xy 2.521067 -252.392613) (xy 2.548772 -252.458934) (xy 2.568819 -252.527958) (xy 2.58095 -252.598803)
			(xy 2.585011 -252.670564) (xy 2.582993 -252.706225) (xy 7.813794 -252.706225) (xy 7.813794 -252.634903)
			(xy 7.82178 -252.564029) (xy 7.83765 -252.494494) (xy 7.861207 -252.427174) (xy 7.892152 -252.362915)
			(xy 7.930098 -252.302524) (xy 7.974567 -252.246762) (xy 8.025 -252.196329) (xy 8.080762 -252.15186)
			(xy 8.141153 -252.113914) (xy 8.205412 -252.082969) (xy 8.272732 -252.059412) (xy 8.342267 -252.043542)
			(xy 8.413141 -252.035556) (xy 8.484463 -252.035556) (xy 8.555337 -252.043542) (xy 8.624872 -252.059412)
			(xy 8.692192 -252.082969) (xy 8.756451 -252.113914) (xy 8.816842 -252.15186) (xy 8.872604 -252.196329)
			(xy 8.923037 -252.246762) (xy 8.967506 -252.302524) (xy 9.005452 -252.362915) (xy 9.036397 -252.427174)
			(xy 9.059954 -252.494494) (xy 9.075824 -252.564029) (xy 9.08381 -252.634903) (xy 9.08431 -252.670564)
			(xy 9.08381 -252.706225) (xy 9.075824 -252.777099) (xy 9.059954 -252.846634) (xy 9.036397 -252.913954)
			(xy 9.005452 -252.978213) (xy 8.967506 -253.038604) (xy 8.923037 -253.094366) (xy 8.872604 -253.144799)
			(xy 8.816842 -253.189268) (xy 8.756451 -253.227214) (xy 8.692192 -253.258159) (xy 8.624872 -253.281716)
			(xy 8.555337 -253.297586) (xy 8.484463 -253.305572) (xy 8.413141 -253.305572) (xy 8.342267 -253.297586)
			(xy 8.272732 -253.281716) (xy 8.205412 -253.258159) (xy 8.141153 -253.227214) (xy 8.080762 -253.189268)
			(xy 8.025 -253.144799) (xy 7.974567 -253.094366) (xy 7.930098 -253.038604) (xy 7.892152 -252.978213)
			(xy 7.861207 -252.913954) (xy 7.83765 -252.846634) (xy 7.82178 -252.777099) (xy 7.813794 -252.706225)
			(xy 2.582993 -252.706225) (xy 2.58095 -252.742325) (xy 2.568819 -252.81317) (xy 2.548772 -252.882194)
			(xy 2.521067 -252.948515) (xy 2.486055 -253.011288) (xy 2.444186 -253.069709) (xy 2.395992 -253.123034)
			(xy 2.342091 -253.170581) (xy 2.283169 -253.211744) (xy 2.219979 -253.245996) (xy 2.153329 -253.272901)
			(xy 2.084068 -253.292114) (xy 2.013082 -253.30339) (xy 1.941277 -253.306586) (xy 1.869571 -253.301661)
			(xy 1.834134 -253.295658) (xy 1.812148 -253.292086) (xy 1.767611 -253.291791) (xy 1.723703 -253.299264)
			(xy 1.681771 -253.314275) (xy 1.643096 -253.336366) (xy 1.608865 -253.364859) (xy 1.580124 -253.398884)
			(xy 1.557753 -253.437396) (xy 1.542438 -253.479219) (xy 1.534647 -253.523071) (xy 1.53416 -253.54534)
			(xy 1.53416 -253.706223) (xy 5.813798 -253.706223) (xy 5.813798 -253.634901) (xy 5.821784 -253.564027)
			(xy 5.837654 -253.494492) (xy 5.861211 -253.427172) (xy 5.892156 -253.362913) (xy 5.930102 -253.302522)
			(xy 5.974571 -253.24676) (xy 6.025004 -253.196327) (xy 6.080766 -253.151858) (xy 6.141157 -253.113912)
			(xy 6.205416 -253.082967) (xy 6.272736 -253.05941) (xy 6.342271 -253.04354) (xy 6.413145 -253.035554)
			(xy 6.484467 -253.035554) (xy 6.555341 -253.04354) (xy 6.624876 -253.05941) (xy 6.692196 -253.082967)
			(xy 6.756455 -253.113912) (xy 6.816846 -253.151858) (xy 6.872608 -253.196327) (xy 6.923041 -253.24676)
			(xy 6.96751 -253.302522) (xy 7.005456 -253.362913) (xy 7.036401 -253.427172) (xy 7.059958 -253.494492)
			(xy 7.075828 -253.564027) (xy 7.083814 -253.634901) (xy 7.084314 -253.670562) (xy 7.083814 -253.706223)
			(xy 7.075828 -253.777097) (xy 7.059958 -253.846632) (xy 7.036401 -253.913952) (xy 7.005456 -253.978211)
			(xy 6.96751 -254.038602) (xy 6.923041 -254.094364) (xy 6.872608 -254.144797) (xy 6.816846 -254.189266)
			(xy 6.756455 -254.227212) (xy 6.692196 -254.258157) (xy 6.624876 -254.281714) (xy 6.555341 -254.297584)
			(xy 6.484467 -254.30557) (xy 6.413145 -254.30557) (xy 6.342271 -254.297584) (xy 6.272736 -254.281714)
			(xy 6.205416 -254.258157) (xy 6.141157 -254.227212) (xy 6.080766 -254.189266) (xy 6.025004 -254.144797)
			(xy 5.974571 -254.094364) (xy 5.930102 -254.038602) (xy 5.892156 -253.978211) (xy 5.861211 -253.913952)
			(xy 5.837654 -253.846632) (xy 5.821784 -253.777097) (xy 5.813798 -253.706223) (xy 1.53416 -253.706223)
			(xy 1.53416 -253.795784) (xy 1.534618 -253.81806) (xy 1.542379 -253.861931) (xy 1.557675 -253.903775)
			(xy 1.580039 -253.942307) (xy 1.608783 -253.976346) (xy 1.643026 -254.004848) (xy 1.681717 -254.026936)
			(xy 1.723668 -254.041935) (xy 1.767593 -254.049384) (xy 1.812144 -254.049054) (xy 1.834134 -254.045466)
			(xy 1.869571 -254.039463) (xy 1.941277 -254.034538) (xy 2.013082 -254.037734) (xy 2.084068 -254.04901)
			(xy 2.153329 -254.068223) (xy 2.219979 -254.095128) (xy 2.283169 -254.12938) (xy 2.342091 -254.170543)
			(xy 2.395992 -254.21809) (xy 2.444186 -254.271415) (xy 2.486055 -254.329836) (xy 2.521067 -254.392609)
			(xy 2.548772 -254.45893) (xy 2.568819 -254.527954) (xy 2.58095 -254.598799) (xy 2.585011 -254.67056)
			(xy 2.582993 -254.706221) (xy 7.813794 -254.706221) (xy 7.813794 -254.634899) (xy 7.82178 -254.564025)
			(xy 7.83765 -254.49449) (xy 7.861207 -254.42717) (xy 7.892152 -254.362911) (xy 7.930098 -254.30252)
			(xy 7.974567 -254.246758) (xy 8.025 -254.196325) (xy 8.080762 -254.151856) (xy 8.141153 -254.11391)
			(xy 8.205412 -254.082965) (xy 8.272732 -254.059408) (xy 8.342267 -254.043538) (xy 8.413141 -254.035552)
			(xy 8.484463 -254.035552) (xy 8.555337 -254.043538) (xy 8.624872 -254.059408) (xy 8.692192 -254.082965)
			(xy 8.756451 -254.11391) (xy 8.816842 -254.151856) (xy 8.872604 -254.196325) (xy 8.923037 -254.246758)
			(xy 8.967506 -254.30252) (xy 9.005452 -254.362911) (xy 9.036397 -254.42717) (xy 9.059954 -254.49449)
			(xy 9.075824 -254.564025) (xy 9.08381 -254.634899) (xy 9.08431 -254.67056) (xy 9.08381 -254.706221)
			(xy 9.075824 -254.777095) (xy 9.059954 -254.84663) (xy 9.036397 -254.91395) (xy 9.005452 -254.978209)
			(xy 8.967506 -255.0386) (xy 8.923037 -255.094362) (xy 8.872604 -255.144795) (xy 8.816842 -255.189264)
			(xy 8.756451 -255.22721) (xy 8.692192 -255.258155) (xy 8.624872 -255.281712) (xy 8.555337 -255.297582)
			(xy 8.484463 -255.305568) (xy 8.413141 -255.305568) (xy 8.342267 -255.297582) (xy 8.272732 -255.281712)
			(xy 8.205412 -255.258155) (xy 8.141153 -255.22721) (xy 8.080762 -255.189264) (xy 8.025 -255.144795)
			(xy 7.974567 -255.094362) (xy 7.930098 -255.0386) (xy 7.892152 -254.978209) (xy 7.861207 -254.91395)
			(xy 7.83765 -254.84663) (xy 7.82178 -254.777095) (xy 7.813794 -254.706221) (xy 2.582993 -254.706221)
			(xy 2.58095 -254.742321) (xy 2.568819 -254.813166) (xy 2.548772 -254.88219) (xy 2.521067 -254.948511)
			(xy 2.486055 -255.011284) (xy 2.444186 -255.069705) (xy 2.395992 -255.12303) (xy 2.342091 -255.170577)
			(xy 2.283169 -255.21174) (xy 2.219979 -255.245992) (xy 2.153329 -255.272897) (xy 2.084068 -255.29211)
			(xy 2.013082 -255.303386) (xy 1.941277 -255.306582) (xy 1.869571 -255.301657) (xy 1.834134 -255.295654)
			(xy 1.812148 -255.292082) (xy 1.76761 -255.291787) (xy 1.723703 -255.29926) (xy 1.68177 -255.314271)
			(xy 1.643095 -255.336362) (xy 1.608863 -255.364855) (xy 1.580122 -255.398879) (xy 1.557751 -255.437392)
			(xy 1.542435 -255.479215) (xy 1.534644 -255.523067) (xy 1.53416 -255.545336) (xy 1.53416 -255.706219)
			(xy 3.31393 -255.706219) (xy 3.31393 -255.634897) (xy 3.321916 -255.564023) (xy 3.337786 -255.494488)
			(xy 3.361343 -255.427168) (xy 3.392288 -255.362909) (xy 3.430234 -255.302518) (xy 3.474703 -255.246756)
			(xy 3.525136 -255.196323) (xy 3.580898 -255.151854) (xy 3.641289 -255.113908) (xy 3.705548 -255.082963)
			(xy 3.772868 -255.059406) (xy 3.842403 -255.043536) (xy 3.913277 -255.03555) (xy 3.984599 -255.03555)
			(xy 4.055473 -255.043536) (xy 4.125008 -255.059406) (xy 4.192328 -255.082963) (xy 4.256587 -255.113908)
			(xy 4.316978 -255.151854) (xy 4.37274 -255.196323) (xy 4.423173 -255.246756) (xy 4.467642 -255.302518)
			(xy 4.505588 -255.362909) (xy 4.536533 -255.427168) (xy 4.56009 -255.494488) (xy 4.57596 -255.564023)
			(xy 4.583946 -255.634897) (xy 4.584446 -255.670558) (xy 4.583946 -255.706219) (xy 4.57596 -255.777093)
			(xy 4.56009 -255.846628) (xy 4.536533 -255.913948) (xy 4.505588 -255.978207) (xy 4.467642 -256.038598)
			(xy 4.423173 -256.09436) (xy 4.37274 -256.144793) (xy 4.316978 -256.189262) (xy 4.256587 -256.227208)
			(xy 4.192328 -256.258153) (xy 4.125008 -256.28171) (xy 4.055473 -256.29758) (xy 3.984599 -256.305566)
			(xy 3.913277 -256.305566) (xy 3.842403 -256.29758) (xy 3.772868 -256.28171) (xy 3.705548 -256.258153)
			(xy 3.641289 -256.227208) (xy 3.580898 -256.189262) (xy 3.525136 -256.144793) (xy 3.474703 -256.09436)
			(xy 3.430234 -256.038598) (xy 3.392288 -255.978207) (xy 3.361343 -255.913948) (xy 3.337786 -255.846628)
			(xy 3.321916 -255.777093) (xy 3.31393 -255.706219) (xy 1.53416 -255.706219) (xy 1.53416 -255.79578)
			(xy 1.534617 -255.818056) (xy 1.542378 -255.861928) (xy 1.557674 -255.903772) (xy 1.580038 -255.942305)
			(xy 1.608782 -255.976345) (xy 1.643025 -256.004847) (xy 1.681716 -256.026936) (xy 1.723667 -256.041935)
			(xy 1.767593 -256.049384) (xy 1.812144 -256.049053) (xy 1.834134 -256.045462) (xy 1.869571 -256.039459)
			(xy 1.941277 -256.034534) (xy 2.013082 -256.03773) (xy 2.084068 -256.049006) (xy 2.153329 -256.068219)
			(xy 2.219979 -256.095124) (xy 2.283169 -256.129376) (xy 2.342091 -256.170539) (xy 2.395992 -256.218086)
			(xy 2.444186 -256.271411) (xy 2.486055 -256.329832) (xy 2.521067 -256.392605) (xy 2.548772 -256.458926)
			(xy 2.568819 -256.52795) (xy 2.58095 -256.598795) (xy 2.585011 -256.670556) (xy 2.582993 -256.706217)
			(xy 7.813794 -256.706217) (xy 7.813794 -256.634895) (xy 7.82178 -256.564021) (xy 7.83765 -256.494486)
			(xy 7.861207 -256.427166) (xy 7.892152 -256.362907) (xy 7.930098 -256.302516) (xy 7.974567 -256.246754)
			(xy 8.025 -256.196321) (xy 8.080762 -256.151852) (xy 8.141153 -256.113906) (xy 8.205412 -256.082961)
			(xy 8.272732 -256.059404) (xy 8.342267 -256.043534) (xy 8.413141 -256.035548) (xy 8.484463 -256.035548)
			(xy 8.555337 -256.043534) (xy 8.624872 -256.059404) (xy 8.692192 -256.082961) (xy 8.756451 -256.113906)
			(xy 8.816842 -256.151852) (xy 8.872604 -256.196321) (xy 8.923037 -256.246754) (xy 8.967506 -256.302516)
			(xy 9.005452 -256.362907) (xy 9.036397 -256.427166) (xy 9.059954 -256.494486) (xy 9.075824 -256.564021)
			(xy 9.08381 -256.634895) (xy 9.08431 -256.670556) (xy 9.08381 -256.706217) (xy 9.075824 -256.777091)
			(xy 9.059954 -256.846626) (xy 9.036397 -256.913946) (xy 9.005452 -256.978205) (xy 8.967506 -257.038596)
			(xy 8.923037 -257.094358) (xy 8.872604 -257.144791) (xy 8.816842 -257.18926) (xy 8.756451 -257.227206)
			(xy 8.692192 -257.258151) (xy 8.624872 -257.281708) (xy 8.555337 -257.297578) (xy 8.484463 -257.305564)
			(xy 8.413141 -257.305564) (xy 8.342267 -257.297578) (xy 8.272732 -257.281708) (xy 8.205412 -257.258151)
			(xy 8.141153 -257.227206) (xy 8.080762 -257.18926) (xy 8.025 -257.144791) (xy 7.974567 -257.094358)
			(xy 7.930098 -257.038596) (xy 7.892152 -256.978205) (xy 7.861207 -256.913946) (xy 7.83765 -256.846626)
			(xy 7.82178 -256.777091) (xy 7.813794 -256.706217) (xy 2.582993 -256.706217) (xy 2.58095 -256.742317)
			(xy 2.568819 -256.813162) (xy 2.548772 -256.882186) (xy 2.521067 -256.948507) (xy 2.486055 -257.01128)
			(xy 2.444186 -257.069701) (xy 2.395992 -257.123026) (xy 2.342091 -257.170573) (xy 2.283169 -257.211736)
			(xy 2.219979 -257.245988) (xy 2.153329 -257.272893) (xy 2.084068 -257.292106) (xy 2.013082 -257.303382)
			(xy 1.941277 -257.306578) (xy 1.869571 -257.301653) (xy 1.834134 -257.29565) (xy 1.812148 -257.292078)
			(xy 1.76761 -257.291783) (xy 1.723702 -257.299256) (xy 1.681769 -257.314267) (xy 1.643094 -257.336358)
			(xy 1.608862 -257.364851) (xy 1.58012 -257.398875) (xy 1.557748 -257.437388) (xy 1.542432 -257.479211)
			(xy 1.53464 -257.523063) (xy 1.53416 -257.545332) (xy 1.53416 -257.706215) (xy 3.31393 -257.706215)
			(xy 3.31393 -257.634893) (xy 3.321916 -257.564019) (xy 3.337786 -257.494484) (xy 3.361343 -257.427164)
			(xy 3.392288 -257.362905) (xy 3.430234 -257.302514) (xy 3.474703 -257.246752) (xy 3.525136 -257.196319)
			(xy 3.580898 -257.15185) (xy 3.641289 -257.113904) (xy 3.705548 -257.082959) (xy 3.772868 -257.059402)
			(xy 3.842403 -257.043532) (xy 3.913277 -257.035546) (xy 3.984599 -257.035546) (xy 4.055473 -257.043532)
			(xy 4.125008 -257.059402) (xy 4.192328 -257.082959) (xy 4.256587 -257.113904) (xy 4.316978 -257.15185)
			(xy 4.37274 -257.196319) (xy 4.423173 -257.246752) (xy 4.467642 -257.302514) (xy 4.505588 -257.362905)
			(xy 4.536533 -257.427164) (xy 4.56009 -257.494484) (xy 4.57596 -257.564019) (xy 4.583946 -257.634893)
			(xy 4.584446 -257.670554) (xy 4.583946 -257.706215) (xy 5.813798 -257.706215) (xy 5.813798 -257.634893)
			(xy 5.821784 -257.564019) (xy 5.837654 -257.494484) (xy 5.861211 -257.427164) (xy 5.892156 -257.362905)
			(xy 5.930102 -257.302514) (xy 5.974571 -257.246752) (xy 6.025004 -257.196319) (xy 6.080766 -257.15185)
			(xy 6.141157 -257.113904) (xy 6.205416 -257.082959) (xy 6.272736 -257.059402) (xy 6.342271 -257.043532)
			(xy 6.413145 -257.035546) (xy 6.484467 -257.035546) (xy 6.555341 -257.043532) (xy 6.624876 -257.059402)
			(xy 6.692196 -257.082959) (xy 6.756455 -257.113904) (xy 6.816846 -257.15185) (xy 6.872608 -257.196319)
			(xy 6.923041 -257.246752) (xy 6.96751 -257.302514) (xy 7.005456 -257.362905) (xy 7.036401 -257.427164)
			(xy 7.059958 -257.494484) (xy 7.075828 -257.564019) (xy 7.083814 -257.634893) (xy 7.084314 -257.670554)
			(xy 7.083814 -257.706215) (xy 7.075828 -257.777089) (xy 7.059958 -257.846624) (xy 7.036401 -257.913944)
			(xy 7.005456 -257.978203) (xy 6.96751 -258.038594) (xy 6.923041 -258.094356) (xy 6.872608 -258.144789)
			(xy 6.816846 -258.189258) (xy 6.756455 -258.227204) (xy 6.692196 -258.258149) (xy 6.624876 -258.281706)
			(xy 6.555341 -258.297576) (xy 6.484467 -258.305562) (xy 6.413145 -258.305562) (xy 6.342271 -258.297576)
			(xy 6.272736 -258.281706) (xy 6.205416 -258.258149) (xy 6.141157 -258.227204) (xy 6.080766 -258.189258)
			(xy 6.025004 -258.144789) (xy 5.974571 -258.094356) (xy 5.930102 -258.038594) (xy 5.892156 -257.978203)
			(xy 5.861211 -257.913944) (xy 5.837654 -257.846624) (xy 5.821784 -257.777089) (xy 5.813798 -257.706215)
			(xy 4.583946 -257.706215) (xy 4.57596 -257.777089) (xy 4.56009 -257.846624) (xy 4.536533 -257.913944)
			(xy 4.505588 -257.978203) (xy 4.467642 -258.038594) (xy 4.423173 -258.094356) (xy 4.37274 -258.144789)
			(xy 4.316978 -258.189258) (xy 4.256587 -258.227204) (xy 4.192328 -258.258149) (xy 4.125008 -258.281706)
			(xy 4.055473 -258.297576) (xy 3.984599 -258.305562) (xy 3.913277 -258.305562) (xy 3.842403 -258.297576)
			(xy 3.772868 -258.281706) (xy 3.705548 -258.258149) (xy 3.641289 -258.227204) (xy 3.580898 -258.189258)
			(xy 3.525136 -258.144789) (xy 3.474703 -258.094356) (xy 3.430234 -258.038594) (xy 3.392288 -257.978203)
			(xy 3.361343 -257.913944) (xy 3.337786 -257.846624) (xy 3.321916 -257.777089) (xy 3.31393 -257.706215)
			(xy 1.53416 -257.706215) (xy 1.53416 -259.706211) (xy 3.31393 -259.706211) (xy 3.31393 -259.634889)
			(xy 3.321916 -259.564015) (xy 3.337786 -259.49448) (xy 3.361343 -259.42716) (xy 3.392288 -259.362901)
			(xy 3.430234 -259.30251) (xy 3.474703 -259.246748) (xy 3.525136 -259.196315) (xy 3.580898 -259.151846)
			(xy 3.641289 -259.1139) (xy 3.705548 -259.082955) (xy 3.772868 -259.059398) (xy 3.842403 -259.043528)
			(xy 3.913277 -259.035542) (xy 3.984599 -259.035542) (xy 4.055473 -259.043528) (xy 4.125008 -259.059398)
			(xy 4.192328 -259.082955) (xy 4.256587 -259.1139) (xy 4.316978 -259.151846) (xy 4.37274 -259.196315)
			(xy 4.423173 -259.246748) (xy 4.467642 -259.30251) (xy 4.505588 -259.362901) (xy 4.536533 -259.42716)
			(xy 4.56009 -259.49448) (xy 4.57596 -259.564015) (xy 4.583946 -259.634889) (xy 4.584446 -259.67055)
			(xy 4.583946 -259.706211) (xy 5.813798 -259.706211) (xy 5.813798 -259.634889) (xy 5.821784 -259.564015)
			(xy 5.837654 -259.49448) (xy 5.861211 -259.42716) (xy 5.892156 -259.362901) (xy 5.930102 -259.30251)
			(xy 5.974571 -259.246748) (xy 6.025004 -259.196315) (xy 6.080766 -259.151846) (xy 6.141157 -259.1139)
			(xy 6.205416 -259.082955) (xy 6.272736 -259.059398) (xy 6.342271 -259.043528) (xy 6.413145 -259.035542)
			(xy 6.484467 -259.035542) (xy 6.555341 -259.043528) (xy 6.624876 -259.059398) (xy 6.692196 -259.082955)
			(xy 6.756455 -259.1139) (xy 6.816846 -259.151846) (xy 6.872608 -259.196315) (xy 6.923041 -259.246748)
			(xy 6.96751 -259.30251) (xy 7.005456 -259.362901) (xy 7.036401 -259.42716) (xy 7.059958 -259.49448)
			(xy 7.075828 -259.564015) (xy 7.083814 -259.634889) (xy 7.084314 -259.67055) (xy 7.083814 -259.706211)
			(xy 7.075828 -259.777085) (xy 7.059958 -259.84662) (xy 7.036401 -259.91394) (xy 7.005456 -259.978199)
			(xy 6.96751 -260.03859) (xy 6.923041 -260.094352) (xy 6.872608 -260.144785) (xy 6.816846 -260.189254)
			(xy 6.756455 -260.2272) (xy 6.692196 -260.258145) (xy 6.624876 -260.281702) (xy 6.555341 -260.297572)
			(xy 6.484467 -260.305558) (xy 6.413145 -260.305558) (xy 6.342271 -260.297572) (xy 6.272736 -260.281702)
			(xy 6.205416 -260.258145) (xy 6.141157 -260.2272) (xy 6.080766 -260.189254) (xy 6.025004 -260.144785)
			(xy 5.974571 -260.094352) (xy 5.930102 -260.03859) (xy 5.892156 -259.978199) (xy 5.861211 -259.91394)
			(xy 5.837654 -259.84662) (xy 5.821784 -259.777085) (xy 5.813798 -259.706211) (xy 4.583946 -259.706211)
			(xy 4.57596 -259.777085) (xy 4.56009 -259.84662) (xy 4.536533 -259.91394) (xy 4.505588 -259.978199)
			(xy 4.467642 -260.03859) (xy 4.423173 -260.094352) (xy 4.37274 -260.144785) (xy 4.316978 -260.189254)
			(xy 4.256587 -260.2272) (xy 4.192328 -260.258145) (xy 4.125008 -260.281702) (xy 4.055473 -260.297572)
			(xy 3.984599 -260.305558) (xy 3.913277 -260.305558) (xy 3.842403 -260.297572) (xy 3.772868 -260.281702)
			(xy 3.705548 -260.258145) (xy 3.641289 -260.2272) (xy 3.580898 -260.189254) (xy 3.525136 -260.144785)
			(xy 3.474703 -260.094352) (xy 3.430234 -260.03859) (xy 3.392288 -259.978199) (xy 3.361343 -259.91394)
			(xy 3.337786 -259.84662) (xy 3.321916 -259.777085) (xy 3.31393 -259.706211) (xy 1.53416 -259.706211)
			(xy 1.53416 -259.795772) (xy 1.534618 -259.818048) (xy 1.542378 -259.861919) (xy 1.557675 -259.903763)
			(xy 1.580038 -259.942296) (xy 1.608783 -259.976336) (xy 1.643025 -260.004837) (xy 1.681716 -260.026926)
			(xy 1.723668 -260.041925) (xy 1.767593 -260.049374) (xy 1.812144 -260.049044) (xy 1.834134 -260.045454)
			(xy 1.869571 -260.039451) (xy 1.941277 -260.034526) (xy 2.013082 -260.037722) (xy 2.084068 -260.048998)
			(xy 2.153329 -260.068211) (xy 2.219979 -260.095116) (xy 2.283169 -260.129368) (xy 2.342091 -260.170531)
			(xy 2.395992 -260.218078) (xy 2.444186 -260.271403) (xy 2.486055 -260.329824) (xy 2.521067 -260.392597)
			(xy 2.548772 -260.458918) (xy 2.568819 -260.527942) (xy 2.58095 -260.598787) (xy 2.585011 -260.670548)
			(xy 2.582993 -260.706209) (xy 7.813794 -260.706209) (xy 7.813794 -260.634887) (xy 7.82178 -260.564013)
			(xy 7.83765 -260.494478) (xy 7.861207 -260.427158) (xy 7.892152 -260.362899) (xy 7.930098 -260.302508)
			(xy 7.974567 -260.246746) (xy 8.025 -260.196313) (xy 8.080762 -260.151844) (xy 8.141153 -260.113898)
			(xy 8.205412 -260.082953) (xy 8.272732 -260.059396) (xy 8.342267 -260.043526) (xy 8.413141 -260.03554)
			(xy 8.484463 -260.03554) (xy 8.555337 -260.043526) (xy 8.624872 -260.059396) (xy 8.692192 -260.082953)
			(xy 8.756451 -260.113898) (xy 8.816842 -260.151844) (xy 8.872604 -260.196313) (xy 8.923037 -260.246746)
			(xy 8.967506 -260.302508) (xy 9.005452 -260.362899) (xy 9.036397 -260.427158) (xy 9.059954 -260.494478)
			(xy 9.075824 -260.564013) (xy 9.08381 -260.634887) (xy 9.08431 -260.670548) (xy 9.08381 -260.706209)
			(xy 9.075824 -260.777083) (xy 9.059954 -260.846618) (xy 9.036397 -260.913938) (xy 9.005452 -260.978197)
			(xy 8.967506 -261.038588) (xy 8.923037 -261.09435) (xy 8.872604 -261.144783) (xy 8.816842 -261.189252)
			(xy 8.756451 -261.227198) (xy 8.692192 -261.258143) (xy 8.624872 -261.2817) (xy 8.555337 -261.29757)
			(xy 8.484463 -261.305556) (xy 8.413141 -261.305556) (xy 8.342267 -261.29757) (xy 8.272732 -261.2817)
			(xy 8.205412 -261.258143) (xy 8.141153 -261.227198) (xy 8.080762 -261.189252) (xy 8.025 -261.144783)
			(xy 7.974567 -261.09435) (xy 7.930098 -261.038588) (xy 7.892152 -260.978197) (xy 7.861207 -260.913938)
			(xy 7.83765 -260.846618) (xy 7.82178 -260.777083) (xy 7.813794 -260.706209) (xy 2.582993 -260.706209)
			(xy 2.58095 -260.742309) (xy 2.568819 -260.813154) (xy 2.548772 -260.882178) (xy 2.521067 -260.948499)
			(xy 2.486055 -261.011272) (xy 2.444186 -261.069693) (xy 2.395992 -261.123018) (xy 2.342091 -261.170565)
			(xy 2.283169 -261.211728) (xy 2.219979 -261.24598) (xy 2.153329 -261.272885) (xy 2.084068 -261.292098)
			(xy 2.013082 -261.303374) (xy 1.941277 -261.30657) (xy 1.869571 -261.301645) (xy 1.834134 -261.295642)
			(xy 1.812148 -261.29207) (xy 1.767609 -261.291775) (xy 1.723701 -261.299248) (xy 1.681767 -261.314259)
			(xy 1.643092 -261.33635) (xy 1.608859 -261.364843) (xy 1.580116 -261.398867) (xy 1.557744 -261.43738)
			(xy 1.542426 -261.479202) (xy 1.534633 -261.523055) (xy 1.53416 -261.545324) (xy 1.53416 -267.850739)
			(xy 3.584556 -267.850739) (xy 3.589879 -267.737285) (xy 3.603163 -267.624485) (xy 3.624341 -267.512897)
			(xy 3.653308 -267.403074) (xy 3.689922 -267.295558) (xy 3.734001 -267.190881) (xy 3.785327 -267.08956)
			(xy 3.843647 -266.992097) (xy 3.908672 -266.898974) (xy 3.980081 -266.81065) (xy 4.05752 -266.727563)
			(xy 4.140607 -266.650124) (xy 4.228931 -266.578715) (xy 4.322054 -266.51369) (xy 4.419517 -266.455369)
			(xy 4.520837 -266.404043) (xy 4.625514 -266.359963) (xy 4.73303 -266.323349) (xy 4.842854 -266.294382)
			(xy 4.954441 -266.273204) (xy 5.067241 -266.25992) (xy 5.180695 -266.254596) (xy 5.294243 -266.257258)
			(xy 5.407324 -266.267894) (xy 5.519377 -266.28645) (xy 5.629849 -266.312835) (xy 5.738194 -266.346919)
			(xy 5.843876 -266.388532) (xy 5.946371 -266.437469) (xy 6.045175 -266.493488) (xy 6.139797 -266.556312)
			(xy 6.229771 -266.625631) (xy 6.31465 -266.701101) (xy 6.394016 -266.78235) (xy 6.467475 -266.868975)
			(xy 6.534666 -266.960549) (xy 6.595255 -267.056618) (xy 6.648942 -267.156707) (xy 6.695463 -267.260322)
			(xy 6.734588 -267.36695) (xy 6.766122 -267.476064) (xy 6.78991 -267.587124) (xy 6.805834 -267.699582)
			(xy 6.813816 -267.81288) (xy 6.814312 -267.86967) (xy 6.813806 -267.92732) (xy 6.805599 -268.042327)
			(xy 6.789208 -268.156456) (xy 6.764716 -268.269125) (xy 6.73225 -268.37976) (xy 6.691973 -268.487796)
			(xy 6.644093 -268.592684) (xy 6.588851 -268.693889) (xy 6.52653 -268.790895) (xy 6.457448 -268.883208)
			(xy 6.381956 -268.970358) (xy 6.30044 -269.0519) (xy 6.213314 -269.127419) (xy 6.121023 -269.196531)
			(xy 6.024036 -269.258882) (xy 5.922848 -269.314155) (xy 5.817976 -269.362069) (xy 5.709952 -269.402379)
			(xy 5.599327 -269.434881) (xy 5.486666 -269.459407) (xy 5.372543 -269.475834) (xy 5.257538 -269.484078)
			(xy 5.199888 -269.484602) (xy 5.199634 -269.484602) (xy 5.199634 -269.484348) (xy 5.142844 -269.483856)
			(xy 5.029546 -269.475875) (xy 4.917088 -269.459951) (xy 4.806028 -269.436163) (xy 4.696914 -269.404629)
			(xy 4.590286 -269.365505) (xy 4.486671 -269.318984) (xy 4.386581 -269.265297) (xy 4.290512 -269.204708)
			(xy 4.198938 -269.137518) (xy 4.112313 -269.064058) (xy 4.031064 -268.984693) (xy 3.955594 -268.899814)
			(xy 3.886275 -268.80984) (xy 3.82345 -268.715218) (xy 3.767431 -268.616415) (xy 3.718493 -268.513919)
			(xy 3.67688 -268.408238) (xy 3.642796 -268.299893) (xy 3.616411 -268.189421) (xy 3.597855 -268.077368)
			(xy 3.587219 -267.964287) (xy 3.584556 -267.850739) (xy 1.53416 -267.850739) (xy 1.53416 -268.794992)
			(xy 1.5346 -268.817295) (xy 1.542339 -268.861222) (xy 1.55763 -268.903123) (xy 1.580004 -268.94171)
			(xy 1.608773 -268.975795) (xy 1.643053 -269.004333) (xy 1.68179 -269.026445) (xy 1.723794 -269.041452)
			(xy 1.767773 -269.048893) (xy 1.812375 -269.048539) (xy 1.834388 -269.044928) (xy 1.869836 -269.038878)
			(xy 1.941576 -269.033866) (xy 2.013424 -269.036985) (xy 2.08446 -269.048196) (xy 2.153775 -269.067355)
			(xy 2.220485 -269.094218) (xy 2.283735 -269.12844) (xy 2.342718 -269.169584) (xy 2.396677 -269.217125)
			(xy 2.444925 -269.270453) (xy 2.486843 -269.328888) (xy 2.521896 -269.391682) (xy 2.549636 -269.458031)
			(xy 2.569707 -269.527089) (xy 2.581853 -269.59797) (xy 2.585919 -269.66977) (xy 2.5839 -269.705429)
			(xy 7.81481 -269.705429) (xy 7.81481 -269.634107) (xy 7.822796 -269.563233) (xy 7.838666 -269.493698)
			(xy 7.862223 -269.426378) (xy 7.893168 -269.362119) (xy 7.931114 -269.301728) (xy 7.975583 -269.245966)
			(xy 8.026016 -269.195533) (xy 8.081778 -269.151064) (xy 8.142169 -269.113118) (xy 8.206428 -269.082173)
			(xy 8.273748 -269.058616) (xy 8.343283 -269.042746) (xy 8.414157 -269.03476) (xy 8.485479 -269.03476)
			(xy 8.556353 -269.042746) (xy 8.625888 -269.058616) (xy 8.693208 -269.082173) (xy 8.757467 -269.113118)
			(xy 8.817858 -269.151064) (xy 8.87362 -269.195533) (xy 8.924053 -269.245966) (xy 8.968522 -269.301728)
			(xy 9.006468 -269.362119) (xy 9.037413 -269.426378) (xy 9.06097 -269.493698) (xy 9.07684 -269.563233)
			(xy 9.084826 -269.634107) (xy 9.085326 -269.669768) (xy 9.084826 -269.705429) (xy 9.07684 -269.776303)
			(xy 9.06097 -269.845838) (xy 9.037413 -269.913158) (xy 9.006468 -269.977417) (xy 8.968522 -270.037808)
			(xy 8.924053 -270.09357) (xy 8.87362 -270.144003) (xy 8.817858 -270.188472) (xy 8.757467 -270.226418)
			(xy 8.693208 -270.257363) (xy 8.625888 -270.28092) (xy 8.556353 -270.29679) (xy 8.485479 -270.304776)
			(xy 8.414157 -270.304776) (xy 8.343283 -270.29679) (xy 8.273748 -270.28092) (xy 8.206428 -270.257363)
			(xy 8.142169 -270.226418) (xy 8.081778 -270.188472) (xy 8.026016 -270.144003) (xy 7.975583 -270.09357)
			(xy 7.931114 -270.037808) (xy 7.893168 -269.977417) (xy 7.862223 -269.913158) (xy 7.838666 -269.845838)
			(xy 7.822796 -269.776303) (xy 7.81481 -269.705429) (xy 2.5839 -269.705429) (xy 2.581853 -269.74157)
			(xy 2.569707 -269.812452) (xy 2.549636 -269.881509) (xy 2.521896 -269.947859) (xy 2.486843 -270.010653)
			(xy 2.444925 -270.069087) (xy 2.396677 -270.122416) (xy 2.342717 -270.169956) (xy 2.283735 -270.211101)
			(xy 2.220484 -270.245323) (xy 2.153775 -270.272185) (xy 2.084459 -270.291344) (xy 2.013423 -270.302555)
			(xy 1.941576 -270.305674) (xy 1.869836 -270.300662) (xy 1.834388 -270.294608) (xy 1.812378 -270.291011)
			(xy 1.767785 -270.29068) (xy 1.723819 -270.298137) (xy 1.681828 -270.313152) (xy 1.643103 -270.335265)
			(xy 1.608831 -270.363797) (xy 1.580065 -270.397873) (xy 1.557687 -270.436446) (xy 1.542384 -270.478332)
			(xy 1.534626 -270.522247) (xy 1.53416 -270.544544) (xy 1.53416 -270.705427) (xy 3.314946 -270.705427)
			(xy 3.314946 -270.634105) (xy 3.322932 -270.563231) (xy 3.338802 -270.493696) (xy 3.362359 -270.426376)
			(xy 3.393304 -270.362117) (xy 3.43125 -270.301726) (xy 3.475719 -270.245964) (xy 3.526152 -270.195531)
			(xy 3.581914 -270.151062) (xy 3.642305 -270.113116) (xy 3.706564 -270.082171) (xy 3.773884 -270.058614)
			(xy 3.843419 -270.042744) (xy 3.914293 -270.034758) (xy 3.985615 -270.034758) (xy 4.056489 -270.042744)
			(xy 4.126024 -270.058614) (xy 4.193344 -270.082171) (xy 4.257603 -270.113116) (xy 4.317994 -270.151062)
			(xy 4.373756 -270.195531) (xy 4.424189 -270.245964) (xy 4.468658 -270.301726) (xy 4.506604 -270.362117)
			(xy 4.537549 -270.426376) (xy 4.561106 -270.493696) (xy 4.576976 -270.563231) (xy 4.584962 -270.634105)
			(xy 4.585462 -270.669766) (xy 4.584962 -270.705427) (xy 5.814814 -270.705427) (xy 5.814814 -270.634105)
			(xy 5.8228 -270.563231) (xy 5.83867 -270.493696) (xy 5.862227 -270.426376) (xy 5.893172 -270.362117)
			(xy 5.931118 -270.301726) (xy 5.975587 -270.245964) (xy 6.02602 -270.195531) (xy 6.081782 -270.151062)
			(xy 6.142173 -270.113116) (xy 6.206432 -270.082171) (xy 6.273752 -270.058614) (xy 6.343287 -270.042744)
			(xy 6.414161 -270.034758) (xy 6.485483 -270.034758) (xy 6.556357 -270.042744) (xy 6.625892 -270.058614)
			(xy 6.693212 -270.082171) (xy 6.757471 -270.113116) (xy 6.817862 -270.151062) (xy 6.873624 -270.195531)
			(xy 6.924057 -270.245964) (xy 6.968526 -270.301726) (xy 7.006472 -270.362117) (xy 7.037417 -270.426376)
			(xy 7.060974 -270.493696) (xy 7.076844 -270.563231) (xy 7.08483 -270.634105) (xy 7.08533 -270.669766)
			(xy 7.08483 -270.705427) (xy 7.076844 -270.776301) (xy 7.060974 -270.845836) (xy 7.037417 -270.913156)
			(xy 7.006472 -270.977415) (xy 6.968526 -271.037806) (xy 6.924057 -271.093568) (xy 6.873624 -271.144001)
			(xy 6.817862 -271.18847) (xy 6.757471 -271.226416) (xy 6.693212 -271.257361) (xy 6.625892 -271.280918)
			(xy 6.556357 -271.296788) (xy 6.485483 -271.304774) (xy 6.414161 -271.304774) (xy 6.343287 -271.296788)
			(xy 6.273752 -271.280918) (xy 6.206432 -271.257361) (xy 6.142173 -271.226416) (xy 6.081782 -271.18847)
			(xy 6.02602 -271.144001) (xy 5.975587 -271.093568) (xy 5.931118 -271.037806) (xy 5.893172 -270.977415)
			(xy 5.862227 -270.913156) (xy 5.83867 -270.845836) (xy 5.8228 -270.776301) (xy 5.814814 -270.705427)
			(xy 4.584962 -270.705427) (xy 4.576976 -270.776301) (xy 4.561106 -270.845836) (xy 4.537549 -270.913156)
			(xy 4.506604 -270.977415) (xy 4.468658 -271.037806) (xy 4.424189 -271.093568) (xy 4.373756 -271.144001)
			(xy 4.317994 -271.18847) (xy 4.257603 -271.226416) (xy 4.193344 -271.257361) (xy 4.126024 -271.280918)
			(xy 4.056489 -271.296788) (xy 3.985615 -271.304774) (xy 3.914293 -271.304774) (xy 3.843419 -271.296788)
			(xy 3.773884 -271.280918) (xy 3.706564 -271.257361) (xy 3.642305 -271.226416) (xy 3.581914 -271.18847)
			(xy 3.526152 -271.144001) (xy 3.475719 -271.093568) (xy 3.43125 -271.037806) (xy 3.393304 -270.977415)
			(xy 3.362359 -270.913156) (xy 3.338802 -270.845836) (xy 3.322932 -270.776301) (xy 3.314946 -270.705427)
			(xy 1.53416 -270.705427) (xy 1.53416 -271.705425) (xy 7.81481 -271.705425) (xy 7.81481 -271.634103)
			(xy 7.822796 -271.563229) (xy 7.838666 -271.493694) (xy 7.862223 -271.426374) (xy 7.893168 -271.362115)
			(xy 7.931114 -271.301724) (xy 7.975583 -271.245962) (xy 8.026016 -271.195529) (xy 8.081778 -271.15106)
			(xy 8.142169 -271.113114) (xy 8.206428 -271.082169) (xy 8.273748 -271.058612) (xy 8.343283 -271.042742)
			(xy 8.414157 -271.034756) (xy 8.485479 -271.034756) (xy 8.556353 -271.042742) (xy 8.625888 -271.058612)
			(xy 8.693208 -271.082169) (xy 8.757467 -271.113114) (xy 8.817858 -271.15106) (xy 8.87362 -271.195529)
			(xy 8.924053 -271.245962) (xy 8.968522 -271.301724) (xy 9.006468 -271.362115) (xy 9.037413 -271.426374)
			(xy 9.06097 -271.493694) (xy 9.07684 -271.563229) (xy 9.084826 -271.634103) (xy 9.085326 -271.669764)
			(xy 9.084826 -271.705425) (xy 9.07684 -271.776299) (xy 9.06097 -271.845834) (xy 9.037413 -271.913154)
			(xy 9.006468 -271.977413) (xy 8.968522 -272.037804) (xy 8.924053 -272.093566) (xy 8.87362 -272.143999)
			(xy 8.817858 -272.188468) (xy 8.757467 -272.226414) (xy 8.693208 -272.257359) (xy 8.625888 -272.280916)
			(xy 8.556353 -272.296786) (xy 8.485479 -272.304772) (xy 8.414157 -272.304772) (xy 8.343283 -272.296786)
			(xy 8.273748 -272.280916) (xy 8.206428 -272.257359) (xy 8.142169 -272.226414) (xy 8.081778 -272.188468)
			(xy 8.026016 -272.143999) (xy 7.975583 -272.093566) (xy 7.931114 -272.037804) (xy 7.893168 -271.977413)
			(xy 7.862223 -271.913154) (xy 7.838666 -271.845834) (xy 7.822796 -271.776299) (xy 7.81481 -271.705425)
			(xy 1.53416 -271.705425) (xy 1.53416 -272.705423) (xy 3.314946 -272.705423) (xy 3.314946 -272.634101)
			(xy 3.322932 -272.563227) (xy 3.338802 -272.493692) (xy 3.362359 -272.426372) (xy 3.393304 -272.362113)
			(xy 3.43125 -272.301722) (xy 3.475719 -272.24596) (xy 3.526152 -272.195527) (xy 3.581914 -272.151058)
			(xy 3.642305 -272.113112) (xy 3.706564 -272.082167) (xy 3.773884 -272.05861) (xy 3.843419 -272.04274)
			(xy 3.914293 -272.034754) (xy 3.985615 -272.034754) (xy 4.056489 -272.04274) (xy 4.126024 -272.05861)
			(xy 4.193344 -272.082167) (xy 4.257603 -272.113112) (xy 4.317994 -272.151058) (xy 4.373756 -272.195527)
			(xy 4.424189 -272.24596) (xy 4.468658 -272.301722) (xy 4.506604 -272.362113) (xy 4.537549 -272.426372)
			(xy 4.561106 -272.493692) (xy 4.576976 -272.563227) (xy 4.584962 -272.634101) (xy 4.585462 -272.669762)
			(xy 4.584962 -272.705423) (xy 4.576976 -272.776297) (xy 4.561106 -272.845832) (xy 4.537549 -272.913152)
			(xy 4.506604 -272.977411) (xy 4.468658 -273.037802) (xy 4.424189 -273.093564) (xy 4.373756 -273.143997)
			(xy 4.317994 -273.188466) (xy 4.257603 -273.226412) (xy 4.193344 -273.257357) (xy 4.126024 -273.280914)
			(xy 4.056489 -273.296784) (xy 3.985615 -273.30477) (xy 3.914293 -273.30477) (xy 3.843419 -273.296784)
			(xy 3.773884 -273.280914) (xy 3.706564 -273.257357) (xy 3.642305 -273.226412) (xy 3.581914 -273.188466)
			(xy 3.526152 -273.143997) (xy 3.475719 -273.093564) (xy 3.43125 -273.037802) (xy 3.393304 -272.977411)
			(xy 3.362359 -272.913152) (xy 3.338802 -272.845832) (xy 3.322932 -272.776297) (xy 3.314946 -272.705423)
			(xy 1.53416 -272.705423) (xy 1.53416 -272.794984) (xy 1.5346 -272.817287) (xy 1.542337 -272.861216)
			(xy 1.557627 -272.903118) (xy 1.580001 -272.941706) (xy 1.60877 -272.975793) (xy 1.643051 -273.004332)
			(xy 1.681788 -273.026445) (xy 1.723793 -273.041452) (xy 1.767773 -273.048893) (xy 1.812376 -273.048538)
			(xy 1.834388 -273.04492) (xy 1.869836 -273.03887) (xy 1.941576 -273.033858) (xy 2.013423 -273.036977)
			(xy 2.084459 -273.048188) (xy 2.153774 -273.067347) (xy 2.220484 -273.094209) (xy 2.283734 -273.128431)
			(xy 2.342716 -273.169576) (xy 2.396676 -273.217116) (xy 2.444923 -273.270444) (xy 2.486841 -273.328879)
			(xy 2.521894 -273.391672) (xy 2.549634 -273.458022) (xy 2.569705 -273.527079) (xy 2.581851 -273.59796)
			(xy 2.585917 -273.66976) (xy 2.583898 -273.705421) (xy 7.81481 -273.705421) (xy 7.81481 -273.634099)
			(xy 7.822796 -273.563225) (xy 7.838666 -273.49369) (xy 7.862223 -273.42637) (xy 7.893168 -273.362111)
			(xy 7.931114 -273.30172) (xy 7.975583 -273.245958) (xy 8.026016 -273.195525) (xy 8.081778 -273.151056)
			(xy 8.142169 -273.11311) (xy 8.206428 -273.082165) (xy 8.273748 -273.058608) (xy 8.343283 -273.042738)
			(xy 8.414157 -273.034752) (xy 8.485479 -273.034752) (xy 8.556353 -273.042738) (xy 8.625888 -273.058608)
			(xy 8.693208 -273.082165) (xy 8.757467 -273.11311) (xy 8.817858 -273.151056) (xy 8.87362 -273.195525)
			(xy 8.924053 -273.245958) (xy 8.968522 -273.30172) (xy 9.006468 -273.362111) (xy 9.037413 -273.42637)
			(xy 9.06097 -273.49369) (xy 9.07684 -273.563225) (xy 9.084826 -273.634099) (xy 9.085326 -273.66976)
			(xy 9.084826 -273.705421) (xy 9.07684 -273.776295) (xy 9.06097 -273.84583) (xy 9.037413 -273.91315)
			(xy 9.006468 -273.977409) (xy 8.968522 -274.0378) (xy 8.924053 -274.093562) (xy 8.87362 -274.143995)
			(xy 8.817858 -274.188464) (xy 8.757467 -274.22641) (xy 8.693208 -274.257355) (xy 8.625888 -274.280912)
			(xy 8.556353 -274.296782) (xy 8.485479 -274.304768) (xy 8.414157 -274.304768) (xy 8.343283 -274.296782)
			(xy 8.273748 -274.280912) (xy 8.206428 -274.257355) (xy 8.142169 -274.22641) (xy 8.081778 -274.188464)
			(xy 8.026016 -274.143995) (xy 7.975583 -274.093562) (xy 7.931114 -274.0378) (xy 7.893168 -273.977409)
			(xy 7.862223 -273.91315) (xy 7.838666 -273.84583) (xy 7.822796 -273.776295) (xy 7.81481 -273.705421)
			(xy 2.583898 -273.705421) (xy 2.581851 -273.74156) (xy 2.569705 -273.812441) (xy 2.549634 -273.881498)
			(xy 2.521894 -273.947848) (xy 2.486841 -274.010641) (xy 2.444923 -274.069076) (xy 2.396676 -274.122404)
			(xy 2.342716 -274.169944) (xy 2.283734 -274.211089) (xy 2.220484 -274.245311) (xy 2.153774 -274.272173)
			(xy 2.084459 -274.291332) (xy 2.013423 -274.302543) (xy 1.941576 -274.305662) (xy 1.869836 -274.30065)
			(xy 1.834388 -274.2946) (xy 1.812378 -274.291003) (xy 1.767784 -274.290672) (xy 1.723817 -274.298129)
			(xy 1.681827 -274.313144) (xy 1.643101 -274.335257) (xy 1.608828 -274.363789) (xy 1.580061 -274.397865)
			(xy 1.557682 -274.436437) (xy 1.542378 -274.478324) (xy 1.534619 -274.522238) (xy 1.53416 -274.544536)
			(xy 1.53416 -274.705419) (xy 3.314946 -274.705419) (xy 3.314946 -274.634097) (xy 3.322932 -274.563223)
			(xy 3.338802 -274.493688) (xy 3.362359 -274.426368) (xy 3.393304 -274.362109) (xy 3.43125 -274.301718)
			(xy 3.475719 -274.245956) (xy 3.526152 -274.195523) (xy 3.581914 -274.151054) (xy 3.642305 -274.113108)
			(xy 3.706564 -274.082163) (xy 3.773884 -274.058606) (xy 3.843419 -274.042736) (xy 3.914293 -274.03475)
			(xy 3.985615 -274.03475) (xy 4.056489 -274.042736) (xy 4.126024 -274.058606) (xy 4.193344 -274.082163)
			(xy 4.257603 -274.113108) (xy 4.317994 -274.151054) (xy 4.373756 -274.195523) (xy 4.424189 -274.245956)
			(xy 4.468658 -274.301718) (xy 4.506604 -274.362109) (xy 4.537549 -274.426368) (xy 4.561106 -274.493688)
			(xy 4.576976 -274.563223) (xy 4.584962 -274.634097) (xy 4.585462 -274.669758) (xy 4.584962 -274.705419)
			(xy 5.814814 -274.705419) (xy 5.814814 -274.634097) (xy 5.8228 -274.563223) (xy 5.83867 -274.493688)
			(xy 5.862227 -274.426368) (xy 5.893172 -274.362109) (xy 5.931118 -274.301718) (xy 5.975587 -274.245956)
			(xy 6.02602 -274.195523) (xy 6.081782 -274.151054) (xy 6.142173 -274.113108) (xy 6.206432 -274.082163)
			(xy 6.273752 -274.058606) (xy 6.343287 -274.042736) (xy 6.414161 -274.03475) (xy 6.485483 -274.03475)
			(xy 6.556357 -274.042736) (xy 6.625892 -274.058606) (xy 6.693212 -274.082163) (xy 6.757471 -274.113108)
			(xy 6.817862 -274.151054) (xy 6.873624 -274.195523) (xy 6.924057 -274.245956) (xy 6.968526 -274.301718)
			(xy 7.006472 -274.362109) (xy 7.037417 -274.426368) (xy 7.060974 -274.493688) (xy 7.076844 -274.563223)
			(xy 7.08483 -274.634097) (xy 7.08533 -274.669758) (xy 7.08483 -274.705419) (xy 7.076844 -274.776293)
			(xy 7.060974 -274.845828) (xy 7.037417 -274.913148) (xy 7.006472 -274.977407) (xy 6.968526 -275.037798)
			(xy 6.924057 -275.09356) (xy 6.873624 -275.143993) (xy 6.817862 -275.188462) (xy 6.757471 -275.226408)
			(xy 6.693212 -275.257353) (xy 6.625892 -275.28091) (xy 6.556357 -275.29678) (xy 6.485483 -275.304766)
			(xy 6.414161 -275.304766) (xy 6.343287 -275.29678) (xy 6.273752 -275.28091) (xy 6.206432 -275.257353)
			(xy 6.142173 -275.226408) (xy 6.081782 -275.188462) (xy 6.02602 -275.143993) (xy 5.975587 -275.09356)
			(xy 5.931118 -275.037798) (xy 5.893172 -274.977407) (xy 5.862227 -274.913148) (xy 5.83867 -274.845828)
			(xy 5.8228 -274.776293) (xy 5.814814 -274.705419) (xy 4.584962 -274.705419) (xy 4.576976 -274.776293)
			(xy 4.561106 -274.845828) (xy 4.537549 -274.913148) (xy 4.506604 -274.977407) (xy 4.468658 -275.037798)
			(xy 4.424189 -275.09356) (xy 4.373756 -275.143993) (xy 4.317994 -275.188462) (xy 4.257603 -275.226408)
			(xy 4.193344 -275.257353) (xy 4.126024 -275.28091) (xy 4.056489 -275.29678) (xy 3.985615 -275.304766)
			(xy 3.914293 -275.304766) (xy 3.843419 -275.29678) (xy 3.773884 -275.28091) (xy 3.706564 -275.257353)
			(xy 3.642305 -275.226408) (xy 3.581914 -275.188462) (xy 3.526152 -275.143993) (xy 3.475719 -275.09356)
			(xy 3.43125 -275.037798) (xy 3.393304 -274.977407) (xy 3.362359 -274.913148) (xy 3.338802 -274.845828)
			(xy 3.322932 -274.776293) (xy 3.314946 -274.705419) (xy 1.53416 -274.705419) (xy 1.53416 -274.79498)
			(xy 1.5346 -274.817283) (xy 1.542338 -274.861211) (xy 1.557629 -274.903112) (xy 1.580003 -274.941699)
			(xy 1.608772 -274.975785) (xy 1.643052 -275.004323) (xy 1.68179 -275.026435) (xy 1.723794 -275.041442)
			(xy 1.767773 -275.048883) (xy 1.812376 -275.048529) (xy 1.834388 -275.044916) (xy 1.869836 -275.038866)
			(xy 1.941576 -275.033854) (xy 2.013423 -275.036974) (xy 2.084458 -275.048185) (xy 2.153774 -275.067344)
			(xy 2.220483 -275.094206) (xy 2.283733 -275.128428) (xy 2.342715 -275.169572) (xy 2.396674 -275.217113)
			(xy 2.444921 -275.270441) (xy 2.486839 -275.328875) (xy 2.521892 -275.391669) (xy 2.549632 -275.458018)
			(xy 2.569703 -275.527075) (xy 2.581849 -275.597956) (xy 2.585915 -275.669756) (xy 2.583896 -275.705417)
			(xy 7.81481 -275.705417) (xy 7.81481 -275.634095) (xy 7.822796 -275.563221) (xy 7.838666 -275.493686)
			(xy 7.862223 -275.426366) (xy 7.893168 -275.362107) (xy 7.931114 -275.301716) (xy 7.975583 -275.245954)
			(xy 8.026016 -275.195521) (xy 8.081778 -275.151052) (xy 8.142169 -275.113106) (xy 8.206428 -275.082161)
			(xy 8.273748 -275.058604) (xy 8.343283 -275.042734) (xy 8.414157 -275.034748) (xy 8.485479 -275.034748)
			(xy 8.556353 -275.042734) (xy 8.625888 -275.058604) (xy 8.693208 -275.082161) (xy 8.757467 -275.113106)
			(xy 8.817858 -275.151052) (xy 8.87362 -275.195521) (xy 8.924053 -275.245954) (xy 8.968522 -275.301716)
			(xy 9.006468 -275.362107) (xy 9.037413 -275.426366) (xy 9.06097 -275.493686) (xy 9.07684 -275.563221)
			(xy 9.084826 -275.634095) (xy 9.085326 -275.669756) (xy 9.084826 -275.705417) (xy 9.07684 -275.776291)
			(xy 9.06097 -275.845826) (xy 9.037413 -275.913146) (xy 9.006468 -275.977405) (xy 8.968522 -276.037796)
			(xy 8.924053 -276.093558) (xy 8.87362 -276.143991) (xy 8.817858 -276.18846) (xy 8.757467 -276.226406)
			(xy 8.693208 -276.257351) (xy 8.625888 -276.280908) (xy 8.556353 -276.296778) (xy 8.485479 -276.304764)
			(xy 8.414157 -276.304764) (xy 8.343283 -276.296778) (xy 8.273748 -276.280908) (xy 8.206428 -276.257351)
			(xy 8.142169 -276.226406) (xy 8.081778 -276.18846) (xy 8.026016 -276.143991) (xy 7.975583 -276.093558)
			(xy 7.931114 -276.037796) (xy 7.893168 -275.977405) (xy 7.862223 -275.913146) (xy 7.838666 -275.845826)
			(xy 7.822796 -275.776291) (xy 7.81481 -275.705417) (xy 2.583896 -275.705417) (xy 2.581849 -275.741556)
			(xy 2.569703 -275.812437) (xy 2.549632 -275.881494) (xy 2.521892 -275.947843) (xy 2.486839 -276.010637)
			(xy 2.444921 -276.069071) (xy 2.396674 -276.122399) (xy 2.342715 -276.16994) (xy 2.283733 -276.211084)
			(xy 2.220483 -276.245306) (xy 2.153774 -276.272168) (xy 2.084458 -276.291327) (xy 2.013423 -276.302538)
			(xy 1.941576 -276.305658) (xy 1.869836 -276.300646) (xy 1.834388 -276.294596) (xy 1.812378 -276.290999)
			(xy 1.767784 -276.290668) (xy 1.723817 -276.298125) (xy 1.681826 -276.31314) (xy 1.6431 -276.335253)
			(xy 1.608827 -276.363785) (xy 1.580059 -276.39786) (xy 1.557679 -276.436433) (xy 1.542375 -276.47832)
			(xy 1.534615 -276.522234) (xy 1.53416 -276.544532) (xy 1.53416 -276.705415) (xy 5.814814 -276.705415)
			(xy 5.814814 -276.634093) (xy 5.8228 -276.563219) (xy 5.83867 -276.493684) (xy 5.862227 -276.426364)
			(xy 5.893172 -276.362105) (xy 5.931118 -276.301714) (xy 5.975587 -276.245952) (xy 6.02602 -276.195519)
			(xy 6.081782 -276.15105) (xy 6.142173 -276.113104) (xy 6.206432 -276.082159) (xy 6.273752 -276.058602)
			(xy 6.343287 -276.042732) (xy 6.414161 -276.034746) (xy 6.485483 -276.034746) (xy 6.556357 -276.042732)
			(xy 6.625892 -276.058602) (xy 6.693212 -276.082159) (xy 6.757471 -276.113104) (xy 6.817862 -276.15105)
			(xy 6.873624 -276.195519) (xy 6.924057 -276.245952) (xy 6.968526 -276.301714) (xy 7.006472 -276.362105)
			(xy 7.037417 -276.426364) (xy 7.060974 -276.493684) (xy 7.076844 -276.563219) (xy 7.08483 -276.634093)
			(xy 7.08533 -276.669754) (xy 7.08483 -276.705415) (xy 7.076844 -276.776289) (xy 7.060974 -276.845824)
			(xy 7.037417 -276.913144) (xy 7.006472 -276.977403) (xy 6.968526 -277.037794) (xy 6.924057 -277.093556)
			(xy 6.873624 -277.143989) (xy 6.817862 -277.188458) (xy 6.757471 -277.226404) (xy 6.693212 -277.257349)
			(xy 6.625892 -277.280906) (xy 6.556357 -277.296776) (xy 6.485483 -277.304762) (xy 6.414161 -277.304762)
			(xy 6.343287 -277.296776) (xy 6.273752 -277.280906) (xy 6.206432 -277.257349) (xy 6.142173 -277.226404)
			(xy 6.081782 -277.188458) (xy 6.02602 -277.143989) (xy 5.975587 -277.093556) (xy 5.931118 -277.037794)
			(xy 5.893172 -276.977403) (xy 5.862227 -276.913144) (xy 5.83867 -276.845824) (xy 5.8228 -276.776289)
			(xy 5.814814 -276.705415) (xy 1.53416 -276.705415) (xy 1.53416 -276.794976) (xy 1.5346 -276.817279)
			(xy 1.542337 -276.861207) (xy 1.557628 -276.903109) (xy 1.580002 -276.941697) (xy 1.608771 -276.975784)
			(xy 1.643051 -277.004322) (xy 1.681789 -277.026435) (xy 1.723793 -277.041442) (xy 1.767773 -277.048883)
			(xy 1.812376 -277.048528) (xy 1.834388 -277.044912) (xy 1.869836 -277.038862) (xy 1.941576 -277.03385)
			(xy 2.013423 -277.036969) (xy 2.084458 -277.04818) (xy 2.153773 -277.067339) (xy 2.220483 -277.094201)
			(xy 2.283733 -277.128423) (xy 2.342715 -277.169567) (xy 2.396674 -277.217107) (xy 2.444921 -277.270435)
			(xy 2.48684 -277.328869) (xy 2.521892 -277.391663) (xy 2.549632 -277.458012) (xy 2.569703 -277.527069)
			(xy 2.581849 -277.59795) (xy 2.585915 -277.66975) (xy 2.581849 -277.741549) (xy 2.569703 -277.81243)
			(xy 2.549632 -277.881487) (xy 2.521893 -277.947837) (xy 2.48684 -278.01063) (xy 2.444922 -278.069064)
			(xy 2.396675 -278.122393) (xy 2.342715 -278.169933) (xy 2.283733 -278.211077) (xy 2.220483 -278.245299)
			(xy 2.153774 -278.272161) (xy 2.084459 -278.29132) (xy 2.013423 -278.302531) (xy 1.941577 -278.30565)
			(xy 1.869837 -278.300638) (xy 1.834388 -278.294592) (xy 1.812378 -278.290995) (xy 1.767784 -278.290664)
			(xy 1.723816 -278.298121) (xy 1.681825 -278.313136) (xy 1.643098 -278.335249) (xy 1.608825 -278.363781)
			(xy 1.580057 -278.397856) (xy 1.557677 -278.436429) (xy 1.542372 -278.478316) (xy 1.534612 -278.52223)
			(xy 1.53416 -278.544528) (xy 1.53416 -278.705411) (xy 3.314946 -278.705411) (xy 3.314946 -278.634089)
			(xy 3.322932 -278.563215) (xy 3.338802 -278.49368) (xy 3.362359 -278.42636) (xy 3.393304 -278.362101)
			(xy 3.43125 -278.30171) (xy 3.475719 -278.245948) (xy 3.526152 -278.195515) (xy 3.581914 -278.151046)
			(xy 3.642305 -278.1131) (xy 3.706564 -278.082155) (xy 3.773884 -278.058598) (xy 3.843419 -278.042728)
			(xy 3.914293 -278.034742) (xy 3.985615 -278.034742) (xy 4.056489 -278.042728) (xy 4.126024 -278.058598)
			(xy 4.193344 -278.082155) (xy 4.257603 -278.1131) (xy 4.317994 -278.151046) (xy 4.373756 -278.195515)
			(xy 4.424189 -278.245948) (xy 4.468658 -278.30171) (xy 4.506604 -278.362101) (xy 4.537549 -278.42636)
			(xy 4.561106 -278.49368) (xy 4.576976 -278.563215) (xy 4.584962 -278.634089) (xy 4.585462 -278.66975)
			(xy 4.584962 -278.705411) (xy 5.814814 -278.705411) (xy 5.814814 -278.634089) (xy 5.8228 -278.563215)
			(xy 5.83867 -278.49368) (xy 5.862227 -278.42636) (xy 5.893172 -278.362101) (xy 5.931118 -278.30171)
			(xy 5.975587 -278.245948) (xy 6.02602 -278.195515) (xy 6.081782 -278.151046) (xy 6.142173 -278.1131)
			(xy 6.206432 -278.082155) (xy 6.273752 -278.058598) (xy 6.343287 -278.042728) (xy 6.414161 -278.034742)
			(xy 6.485483 -278.034742) (xy 6.556357 -278.042728) (xy 6.625892 -278.058598) (xy 6.693212 -278.082155)
			(xy 6.757471 -278.1131) (xy 6.817862 -278.151046) (xy 6.873624 -278.195515) (xy 6.924057 -278.245948)
			(xy 6.968526 -278.30171) (xy 7.006472 -278.362101) (xy 7.037417 -278.42636) (xy 7.060974 -278.49368)
			(xy 7.076844 -278.563215) (xy 7.08483 -278.634089) (xy 7.08533 -278.66975) (xy 7.08483 -278.705411)
			(xy 7.076844 -278.776285) (xy 7.060974 -278.84582) (xy 7.037417 -278.91314) (xy 7.006472 -278.977399)
			(xy 6.968526 -279.03779) (xy 6.924057 -279.093552) (xy 6.873624 -279.143985) (xy 6.817862 -279.188454)
			(xy 6.757471 -279.2264) (xy 6.693212 -279.257345) (xy 6.625892 -279.280902) (xy 6.556357 -279.296772)
			(xy 6.485483 -279.304758) (xy 6.414161 -279.304758) (xy 6.343287 -279.296772) (xy 6.273752 -279.280902)
			(xy 6.206432 -279.257345) (xy 6.142173 -279.2264) (xy 6.081782 -279.188454) (xy 6.02602 -279.143985)
			(xy 5.975587 -279.093552) (xy 5.931118 -279.03779) (xy 5.893172 -278.977399) (xy 5.862227 -278.91314)
			(xy 5.83867 -278.84582) (xy 5.8228 -278.776285) (xy 5.814814 -278.705411) (xy 4.584962 -278.705411)
			(xy 4.576976 -278.776285) (xy 4.561106 -278.84582) (xy 4.537549 -278.91314) (xy 4.506604 -278.977399)
			(xy 4.468658 -279.03779) (xy 4.424189 -279.093552) (xy 4.373756 -279.143985) (xy 4.317994 -279.188454)
			(xy 4.257603 -279.2264) (xy 4.193344 -279.257345) (xy 4.126024 -279.280902) (xy 4.056489 -279.296772)
			(xy 3.985615 -279.304758) (xy 3.914293 -279.304758) (xy 3.843419 -279.296772) (xy 3.773884 -279.280902)
			(xy 3.706564 -279.257345) (xy 3.642305 -279.2264) (xy 3.581914 -279.188454) (xy 3.526152 -279.143985)
			(xy 3.475719 -279.093552) (xy 3.43125 -279.03779) (xy 3.393304 -278.977399) (xy 3.362359 -278.91314)
			(xy 3.338802 -278.84582) (xy 3.322932 -278.776285) (xy 3.314946 -278.705411) (xy 1.53416 -278.705411)
			(xy 1.53416 -278.794972) (xy 1.5346 -278.817275) (xy 1.542339 -278.861202) (xy 1.55763 -278.903103)
			(xy 1.580004 -278.94169) (xy 1.608773 -278.975775) (xy 1.643053 -279.004313) (xy 1.68179 -279.026425)
			(xy 1.723794 -279.041432) (xy 1.767773 -279.048873) (xy 1.812375 -279.048519) (xy 1.834388 -279.044908)
			(xy 1.869836 -279.038858) (xy 1.941576 -279.033846) (xy 2.013424 -279.036965) (xy 2.08446 -279.048176)
			(xy 2.153775 -279.067335) (xy 2.220485 -279.094198) (xy 2.283735 -279.12842) (xy 2.342718 -279.169564)
			(xy 2.396677 -279.217105) (xy 2.444925 -279.270433) (xy 2.486843 -279.328868) (xy 2.521896 -279.391662)
			(xy 2.549636 -279.458011) (xy 2.569707 -279.527069) (xy 2.581853 -279.59795) (xy 2.585919 -279.66975)
			(xy 2.5839 -279.705409) (xy 7.81481 -279.705409) (xy 7.81481 -279.634087) (xy 7.822796 -279.563213)
			(xy 7.838666 -279.493678) (xy 7.862223 -279.426358) (xy 7.893168 -279.362099) (xy 7.931114 -279.301708)
			(xy 7.975583 -279.245946) (xy 8.026016 -279.195513) (xy 8.081778 -279.151044) (xy 8.142169 -279.113098)
			(xy 8.206428 -279.082153) (xy 8.273748 -279.058596) (xy 8.343283 -279.042726) (xy 8.414157 -279.03474)
			(xy 8.485479 -279.03474) (xy 8.556353 -279.042726) (xy 8.625888 -279.058596) (xy 8.693208 -279.082153)
			(xy 8.757467 -279.113098) (xy 8.817858 -279.151044) (xy 8.87362 -279.195513) (xy 8.924053 -279.245946)
			(xy 8.968522 -279.301708) (xy 9.006468 -279.362099) (xy 9.037413 -279.426358) (xy 9.06097 -279.493678)
			(xy 9.07684 -279.563213) (xy 9.084826 -279.634087) (xy 9.085326 -279.669748) (xy 9.084826 -279.705409)
			(xy 9.07684 -279.776283) (xy 9.06097 -279.845818) (xy 9.037413 -279.913138) (xy 9.006468 -279.977397)
			(xy 8.968522 -280.037788) (xy 8.924053 -280.09355) (xy 8.87362 -280.143983) (xy 8.817858 -280.188452)
			(xy 8.757467 -280.226398) (xy 8.693208 -280.257343) (xy 8.625888 -280.2809) (xy 8.556353 -280.29677)
			(xy 8.485479 -280.304756) (xy 8.414157 -280.304756) (xy 8.343283 -280.29677) (xy 8.273748 -280.2809)
			(xy 8.206428 -280.257343) (xy 8.142169 -280.226398) (xy 8.081778 -280.188452) (xy 8.026016 -280.143983)
			(xy 7.975583 -280.09355) (xy 7.931114 -280.037788) (xy 7.893168 -279.977397) (xy 7.862223 -279.913138)
			(xy 7.838666 -279.845818) (xy 7.822796 -279.776283) (xy 7.81481 -279.705409) (xy 2.5839 -279.705409)
			(xy 2.581853 -279.74155) (xy 2.569707 -279.812432) (xy 2.549636 -279.881489) (xy 2.521896 -279.947839)
			(xy 2.486843 -280.010633) (xy 2.444925 -280.069067) (xy 2.396677 -280.122396) (xy 2.342717 -280.169936)
			(xy 2.283735 -280.211081) (xy 2.220484 -280.245303) (xy 2.153775 -280.272165) (xy 2.084459 -280.291324)
			(xy 2.013423 -280.302535) (xy 1.941576 -280.305654) (xy 1.869836 -280.300642) (xy 1.834388 -280.294588)
			(xy 1.812377 -280.290991) (xy 1.767783 -280.290661) (xy 1.723816 -280.298117) (xy 1.681824 -280.313132)
			(xy 1.643097 -280.335245) (xy 1.608824 -280.363777) (xy 1.580055 -280.397852) (xy 1.557675 -280.436425)
			(xy 1.542369 -280.478311) (xy 1.534608 -280.522226) (xy 1.53416 -280.544524) (xy 1.53416 -280.705407)
			(xy 3.314946 -280.705407) (xy 3.314946 -280.634085) (xy 3.322932 -280.563211) (xy 3.338802 -280.493676)
			(xy 3.362359 -280.426356) (xy 3.393304 -280.362097) (xy 3.43125 -280.301706) (xy 3.475719 -280.245944)
			(xy 3.526152 -280.195511) (xy 3.581914 -280.151042) (xy 3.642305 -280.113096) (xy 3.706564 -280.082151)
			(xy 3.773884 -280.058594) (xy 3.843419 -280.042724) (xy 3.914293 -280.034738) (xy 3.985615 -280.034738)
			(xy 4.056489 -280.042724) (xy 4.126024 -280.058594) (xy 4.193344 -280.082151) (xy 4.257603 -280.113096)
			(xy 4.317994 -280.151042) (xy 4.373756 -280.195511) (xy 4.424189 -280.245944) (xy 4.468658 -280.301706)
			(xy 4.506604 -280.362097) (xy 4.537549 -280.426356) (xy 4.561106 -280.493676) (xy 4.576976 -280.563211)
			(xy 4.584962 -280.634085) (xy 4.585462 -280.669746) (xy 4.584962 -280.705407) (xy 5.814814 -280.705407)
			(xy 5.814814 -280.634085) (xy 5.8228 -280.563211) (xy 5.83867 -280.493676) (xy 5.862227 -280.426356)
			(xy 5.893172 -280.362097) (xy 5.931118 -280.301706) (xy 5.975587 -280.245944) (xy 6.02602 -280.195511)
			(xy 6.081782 -280.151042) (xy 6.142173 -280.113096) (xy 6.206432 -280.082151) (xy 6.273752 -280.058594)
			(xy 6.343287 -280.042724) (xy 6.414161 -280.034738) (xy 6.485483 -280.034738) (xy 6.556357 -280.042724)
			(xy 6.625892 -280.058594) (xy 6.693212 -280.082151) (xy 6.757471 -280.113096) (xy 6.817862 -280.151042)
			(xy 6.873624 -280.195511) (xy 6.924057 -280.245944) (xy 6.968526 -280.301706) (xy 7.006472 -280.362097)
			(xy 7.037417 -280.426356) (xy 7.060974 -280.493676) (xy 7.076844 -280.563211) (xy 7.08483 -280.634085)
			(xy 7.08533 -280.669746) (xy 7.08483 -280.705407) (xy 7.076844 -280.776281) (xy 7.060974 -280.845816)
			(xy 7.037417 -280.913136) (xy 7.006472 -280.977395) (xy 6.968526 -281.037786) (xy 6.924057 -281.093548)
			(xy 6.873624 -281.143981) (xy 6.817862 -281.18845) (xy 6.757471 -281.226396) (xy 6.693212 -281.257341)
			(xy 6.625892 -281.280898) (xy 6.556357 -281.296768) (xy 6.485483 -281.304754) (xy 6.414161 -281.304754)
			(xy 6.343287 -281.296768) (xy 6.273752 -281.280898) (xy 6.206432 -281.257341) (xy 6.142173 -281.226396)
			(xy 6.081782 -281.18845) (xy 6.02602 -281.143981) (xy 5.975587 -281.093548) (xy 5.931118 -281.037786)
			(xy 5.893172 -280.977395) (xy 5.862227 -280.913136) (xy 5.83867 -280.845816) (xy 5.8228 -280.776281)
			(xy 5.814814 -280.705407) (xy 4.584962 -280.705407) (xy 4.576976 -280.776281) (xy 4.561106 -280.845816)
			(xy 4.537549 -280.913136) (xy 4.506604 -280.977395) (xy 4.468658 -281.037786) (xy 4.424189 -281.093548)
			(xy 4.373756 -281.143981) (xy 4.317994 -281.18845) (xy 4.257603 -281.226396) (xy 4.193344 -281.257341)
			(xy 4.126024 -281.280898) (xy 4.056489 -281.296768) (xy 3.985615 -281.304754) (xy 3.914293 -281.304754)
			(xy 3.843419 -281.296768) (xy 3.773884 -281.280898) (xy 3.706564 -281.257341) (xy 3.642305 -281.226396)
			(xy 3.581914 -281.18845) (xy 3.526152 -281.143981) (xy 3.475719 -281.093548) (xy 3.43125 -281.037786)
			(xy 3.393304 -280.977395) (xy 3.362359 -280.913136) (xy 3.338802 -280.845816) (xy 3.322932 -280.776281)
			(xy 3.314946 -280.705407) (xy 1.53416 -280.705407) (xy 1.53416 -281.705405) (xy 7.81481 -281.705405)
			(xy 7.81481 -281.634083) (xy 7.822796 -281.563209) (xy 7.838666 -281.493674) (xy 7.862223 -281.426354)
			(xy 7.893168 -281.362095) (xy 7.931114 -281.301704) (xy 7.975583 -281.245942) (xy 8.026016 -281.195509)
			(xy 8.081778 -281.15104) (xy 8.142169 -281.113094) (xy 8.206428 -281.082149) (xy 8.273748 -281.058592)
			(xy 8.343283 -281.042722) (xy 8.414157 -281.034736) (xy 8.485479 -281.034736) (xy 8.556353 -281.042722)
			(xy 8.625888 -281.058592) (xy 8.693208 -281.082149) (xy 8.757467 -281.113094) (xy 8.817858 -281.15104)
			(xy 8.87362 -281.195509) (xy 8.924053 -281.245942) (xy 8.968522 -281.301704) (xy 9.006468 -281.362095)
			(xy 9.037413 -281.426354) (xy 9.06097 -281.493674) (xy 9.07684 -281.563209) (xy 9.084826 -281.634083)
			(xy 9.085326 -281.669744) (xy 9.084826 -281.705405) (xy 9.07684 -281.776279) (xy 9.06097 -281.845814)
			(xy 9.037413 -281.913134) (xy 9.006468 -281.977393) (xy 8.968522 -282.037784) (xy 8.924053 -282.093546)
			(xy 8.87362 -282.143979) (xy 8.817858 -282.188448) (xy 8.757467 -282.226394) (xy 8.693208 -282.257339)
			(xy 8.625888 -282.280896) (xy 8.556353 -282.296766) (xy 8.485479 -282.304752) (xy 8.414157 -282.304752)
			(xy 8.343283 -282.296766) (xy 8.273748 -282.280896) (xy 8.206428 -282.257339) (xy 8.142169 -282.226394)
			(xy 8.081778 -282.188448) (xy 8.026016 -282.143979) (xy 7.975583 -282.093546) (xy 7.931114 -282.037784)
			(xy 7.893168 -281.977393) (xy 7.862223 -281.913134) (xy 7.838666 -281.845814) (xy 7.822796 -281.776279)
			(xy 7.81481 -281.705405) (xy 1.53416 -281.705405) (xy 1.53416 -282.705403) (xy 3.314946 -282.705403)
			(xy 3.314946 -282.634081) (xy 3.322932 -282.563207) (xy 3.338802 -282.493672) (xy 3.362359 -282.426352)
			(xy 3.393304 -282.362093) (xy 3.43125 -282.301702) (xy 3.475719 -282.24594) (xy 3.526152 -282.195507)
			(xy 3.581914 -282.151038) (xy 3.642305 -282.113092) (xy 3.706564 -282.082147) (xy 3.773884 -282.05859)
			(xy 3.843419 -282.04272) (xy 3.914293 -282.034734) (xy 3.985615 -282.034734) (xy 4.056489 -282.04272)
			(xy 4.126024 -282.05859) (xy 4.193344 -282.082147) (xy 4.257603 -282.113092) (xy 4.317994 -282.151038)
			(xy 4.373756 -282.195507) (xy 4.424189 -282.24594) (xy 4.468658 -282.301702) (xy 4.506604 -282.362093)
			(xy 4.537549 -282.426352) (xy 4.561106 -282.493672) (xy 4.576976 -282.563207) (xy 4.584962 -282.634081)
			(xy 4.585462 -282.669742) (xy 4.584962 -282.705403) (xy 4.576976 -282.776277) (xy 4.561106 -282.845812)
			(xy 4.537549 -282.913132) (xy 4.506604 -282.977391) (xy 4.468658 -283.037782) (xy 4.424189 -283.093544)
			(xy 4.373756 -283.143977) (xy 4.317994 -283.188446) (xy 4.257603 -283.226392) (xy 4.193344 -283.257337)
			(xy 4.126024 -283.280894) (xy 4.056489 -283.296764) (xy 3.985615 -283.30475) (xy 3.914293 -283.30475)
			(xy 3.843419 -283.296764) (xy 3.773884 -283.280894) (xy 3.706564 -283.257337) (xy 3.642305 -283.226392)
			(xy 3.581914 -283.188446) (xy 3.526152 -283.143977) (xy 3.475719 -283.093544) (xy 3.43125 -283.037782)
			(xy 3.393304 -282.977391) (xy 3.362359 -282.913132) (xy 3.338802 -282.845812) (xy 3.322932 -282.776277)
			(xy 3.314946 -282.705403) (xy 1.53416 -282.705403) (xy 1.53416 -282.794964) (xy 1.5346 -282.817267)
			(xy 1.542337 -282.861196) (xy 1.557627 -282.903098) (xy 1.580001 -282.941686) (xy 1.60877 -282.975773)
			(xy 1.643051 -283.004312) (xy 1.681788 -283.026425) (xy 1.723793 -283.041432) (xy 1.767773 -283.048873)
			(xy 1.812376 -283.048518) (xy 1.834388 -283.0449) (xy 1.869836 -283.03885) (xy 1.941576 -283.033838)
			(xy 2.013423 -283.036957) (xy 2.084459 -283.048168) (xy 2.153774 -283.067327) (xy 2.220484 -283.094189)
			(xy 2.283734 -283.128411) (xy 2.342716 -283.169556) (xy 2.396676 -283.217096) (xy 2.444923 -283.270424)
			(xy 2.486841 -283.328859) (xy 2.521894 -283.391652) (xy 2.549634 -283.458002) (xy 2.569705 -283.527059)
			(xy 2.581851 -283.59794) (xy 2.585917 -283.66974) (xy 2.583898 -283.705401) (xy 7.81481 -283.705401)
			(xy 7.81481 -283.634079) (xy 7.822796 -283.563205) (xy 7.838666 -283.49367) (xy 7.862223 -283.42635)
			(xy 7.893168 -283.362091) (xy 7.931114 -283.3017) (xy 7.975583 -283.245938) (xy 8.026016 -283.195505)
			(xy 8.081778 -283.151036) (xy 8.142169 -283.11309) (xy 8.206428 -283.082145) (xy 8.273748 -283.058588)
			(xy 8.343283 -283.042718) (xy 8.414157 -283.034732) (xy 8.485479 -283.034732) (xy 8.556353 -283.042718)
			(xy 8.625888 -283.058588) (xy 8.693208 -283.082145) (xy 8.757467 -283.11309) (xy 8.817858 -283.151036)
			(xy 8.87362 -283.195505) (xy 8.924053 -283.245938) (xy 8.968522 -283.3017) (xy 9.006468 -283.362091)
			(xy 9.037413 -283.42635) (xy 9.06097 -283.49367) (xy 9.07684 -283.563205) (xy 9.084826 -283.634079)
			(xy 9.085326 -283.66974) (xy 9.084826 -283.705401) (xy 9.07684 -283.776275) (xy 9.06097 -283.84581)
			(xy 9.037413 -283.91313) (xy 9.006468 -283.977389) (xy 8.968522 -284.03778) (xy 8.924053 -284.093542)
			(xy 8.87362 -284.143975) (xy 8.817858 -284.188444) (xy 8.757467 -284.22639) (xy 8.693208 -284.257335)
			(xy 8.625888 -284.280892) (xy 8.556353 -284.296762) (xy 8.485479 -284.304748) (xy 8.414157 -284.304748)
			(xy 8.343283 -284.296762) (xy 8.273748 -284.280892) (xy 8.206428 -284.257335) (xy 8.142169 -284.22639)
			(xy 8.081778 -284.188444) (xy 8.026016 -284.143975) (xy 7.975583 -284.093542) (xy 7.931114 -284.03778)
			(xy 7.893168 -283.977389) (xy 7.862223 -283.91313) (xy 7.838666 -283.84581) (xy 7.822796 -283.776275)
			(xy 7.81481 -283.705401) (xy 2.583898 -283.705401) (xy 2.581851 -283.74154) (xy 2.569705 -283.812421)
			(xy 2.549634 -283.881478) (xy 2.521894 -283.947828) (xy 2.486841 -284.010621) (xy 2.444923 -284.069056)
			(xy 2.396676 -284.122384) (xy 2.342716 -284.169924) (xy 2.283734 -284.211069) (xy 2.220484 -284.245291)
			(xy 2.153774 -284.272153) (xy 2.084459 -284.291312) (xy 2.013423 -284.302523) (xy 1.941576 -284.305642)
			(xy 1.869836 -284.30063) (xy 1.834388 -284.29458) (xy 1.812377 -284.290983) (xy 1.767783 -284.290653)
			(xy 1.723815 -284.298109) (xy 1.681823 -284.313124) (xy 1.643095 -284.335237) (xy 1.608821 -284.363769)
			(xy 1.580052 -284.397844) (xy 1.55767 -284.436416) (xy 1.542363 -284.478303) (xy 1.534601 -284.522218)
			(xy 1.53416 -284.544516) (xy 1.53416 -284.705653) (xy 3.314946 -284.705653) (xy 3.314946 -284.634331)
			(xy 3.322932 -284.563457) (xy 3.338802 -284.493922) (xy 3.362359 -284.426602) (xy 3.393304 -284.362343)
			(xy 3.43125 -284.301952) (xy 3.475719 -284.24619) (xy 3.526152 -284.195757) (xy 3.581914 -284.151288)
			(xy 3.642305 -284.113342) (xy 3.706564 -284.082397) (xy 3.773884 -284.05884) (xy 3.843419 -284.04297)
			(xy 3.914293 -284.034984) (xy 3.985615 -284.034984) (xy 4.056489 -284.04297) (xy 4.126024 -284.05884)
			(xy 4.193344 -284.082397) (xy 4.257603 -284.113342) (xy 4.317994 -284.151288) (xy 4.373756 -284.195757)
			(xy 4.424189 -284.24619) (xy 4.468658 -284.301952) (xy 4.506604 -284.362343) (xy 4.537549 -284.426602)
			(xy 4.561106 -284.493922) (xy 4.576976 -284.563457) (xy 4.584962 -284.634331) (xy 4.585462 -284.669992)
			(xy 4.584962 -284.705653) (xy 5.814814 -284.705653) (xy 5.814814 -284.634331) (xy 5.8228 -284.563457)
			(xy 5.83867 -284.493922) (xy 5.862227 -284.426602) (xy 5.893172 -284.362343) (xy 5.931118 -284.301952)
			(xy 5.975587 -284.24619) (xy 6.02602 -284.195757) (xy 6.081782 -284.151288) (xy 6.142173 -284.113342)
			(xy 6.206432 -284.082397) (xy 6.273752 -284.05884) (xy 6.343287 -284.04297) (xy 6.414161 -284.034984)
			(xy 6.485483 -284.034984) (xy 6.556357 -284.04297) (xy 6.625892 -284.05884) (xy 6.693212 -284.082397)
			(xy 6.757471 -284.113342) (xy 6.817862 -284.151288) (xy 6.873624 -284.195757) (xy 6.924057 -284.24619)
			(xy 6.968526 -284.301952) (xy 7.006472 -284.362343) (xy 7.037417 -284.426602) (xy 7.060974 -284.493922)
			(xy 7.076844 -284.563457) (xy 7.08483 -284.634331) (xy 7.08533 -284.669992) (xy 7.08483 -284.705653)
			(xy 7.076844 -284.776527) (xy 7.060974 -284.846062) (xy 7.037417 -284.913382) (xy 7.006472 -284.977641)
			(xy 6.968526 -285.038032) (xy 6.924057 -285.093794) (xy 6.873624 -285.144227) (xy 6.817862 -285.188696)
			(xy 6.757471 -285.226642) (xy 6.693212 -285.257587) (xy 6.625892 -285.281144) (xy 6.556357 -285.297014)
			(xy 6.485483 -285.305) (xy 6.414161 -285.305) (xy 6.343287 -285.297014) (xy 6.273752 -285.281144)
			(xy 6.206432 -285.257587) (xy 6.142173 -285.226642) (xy 6.081782 -285.188696) (xy 6.02602 -285.144227)
			(xy 5.975587 -285.093794) (xy 5.931118 -285.038032) (xy 5.893172 -284.977641) (xy 5.862227 -284.913382)
			(xy 5.83867 -284.846062) (xy 5.8228 -284.776527) (xy 5.814814 -284.705653) (xy 4.584962 -284.705653)
			(xy 4.576976 -284.776527) (xy 4.561106 -284.846062) (xy 4.537549 -284.913382) (xy 4.506604 -284.977641)
			(xy 4.468658 -285.038032) (xy 4.424189 -285.093794) (xy 4.373756 -285.144227) (xy 4.317994 -285.188696)
			(xy 4.257603 -285.226642) (xy 4.193344 -285.257587) (xy 4.126024 -285.281144) (xy 4.056489 -285.297014)
			(xy 3.985615 -285.305) (xy 3.914293 -285.305) (xy 3.843419 -285.297014) (xy 3.773884 -285.281144)
			(xy 3.706564 -285.257587) (xy 3.642305 -285.226642) (xy 3.581914 -285.188696) (xy 3.526152 -285.144227)
			(xy 3.475719 -285.093794) (xy 3.43125 -285.038032) (xy 3.393304 -284.977641) (xy 3.362359 -284.913382)
			(xy 3.338802 -284.846062) (xy 3.322932 -284.776527) (xy 3.314946 -284.705653) (xy 1.53416 -284.705653)
			(xy 1.53416 -284.79496) (xy 1.5346 -284.817263) (xy 1.542338 -284.861191) (xy 1.557629 -284.903092)
			(xy 1.580003 -284.941679) (xy 1.608772 -284.975765) (xy 1.643052 -285.004303) (xy 1.68179 -285.026415)
			(xy 1.723794 -285.041422) (xy 1.767773 -285.048863) (xy 1.812376 -285.048509) (xy 1.834388 -285.044896)
			(xy 1.869836 -285.038846) (xy 1.941576 -285.033834) (xy 2.013423 -285.036954) (xy 2.084458 -285.048165)
			(xy 2.153774 -285.067324) (xy 2.220483 -285.094186) (xy 2.283733 -285.128408) (xy 2.342715 -285.169552)
			(xy 2.396674 -285.217093) (xy 2.444921 -285.270421) (xy 2.486839 -285.328855) (xy 2.521892 -285.391649)
			(xy 2.549632 -285.457998) (xy 2.569703 -285.527055) (xy 2.581849 -285.597936) (xy 2.585915 -285.669736)
			(xy 2.583896 -285.705397) (xy 7.81481 -285.705397) (xy 7.81481 -285.634075) (xy 7.822796 -285.563201)
			(xy 7.838666 -285.493666) (xy 7.862223 -285.426346) (xy 7.893168 -285.362087) (xy 7.931114 -285.301696)
			(xy 7.975583 -285.245934) (xy 8.026016 -285.195501) (xy 8.081778 -285.151032) (xy 8.142169 -285.113086)
			(xy 8.206428 -285.082141) (xy 8.273748 -285.058584) (xy 8.343283 -285.042714) (xy 8.414157 -285.034728)
			(xy 8.485479 -285.034728) (xy 8.556353 -285.042714) (xy 8.625888 -285.058584) (xy 8.693208 -285.082141)
			(xy 8.757467 -285.113086) (xy 8.817858 -285.151032) (xy 8.87362 -285.195501) (xy 8.924053 -285.245934)
			(xy 8.968522 -285.301696) (xy 9.006468 -285.362087) (xy 9.037413 -285.426346) (xy 9.06097 -285.493666)
			(xy 9.07684 -285.563201) (xy 9.084826 -285.634075) (xy 9.085326 -285.669736) (xy 9.084826 -285.705397)
			(xy 9.07684 -285.776271) (xy 9.06097 -285.845806) (xy 9.037413 -285.913126) (xy 9.006468 -285.977385)
			(xy 8.968522 -286.037776) (xy 8.924053 -286.093538) (xy 8.87362 -286.143971) (xy 8.817858 -286.18844)
			(xy 8.757467 -286.226386) (xy 8.693208 -286.257331) (xy 8.625888 -286.280888) (xy 8.556353 -286.296758)
			(xy 8.485479 -286.304744) (xy 8.414157 -286.304744) (xy 8.343283 -286.296758) (xy 8.273748 -286.280888)
			(xy 8.206428 -286.257331) (xy 8.142169 -286.226386) (xy 8.081778 -286.18844) (xy 8.026016 -286.143971)
			(xy 7.975583 -286.093538) (xy 7.931114 -286.037776) (xy 7.893168 -285.977385) (xy 7.862223 -285.913126)
			(xy 7.838666 -285.845806) (xy 7.822796 -285.776271) (xy 7.81481 -285.705397) (xy 2.583896 -285.705397)
			(xy 2.581849 -285.741536) (xy 2.569703 -285.812417) (xy 2.549632 -285.881474) (xy 2.521892 -285.947823)
			(xy 2.486839 -286.010617) (xy 2.444921 -286.069051) (xy 2.396674 -286.122379) (xy 2.342715 -286.16992)
			(xy 2.283733 -286.211064) (xy 2.220483 -286.245286) (xy 2.153774 -286.272148) (xy 2.084458 -286.291307)
			(xy 2.013423 -286.302518) (xy 1.941576 -286.305638) (xy 1.869836 -286.300626) (xy 1.834388 -286.294576)
			(xy 1.812377 -286.290979) (xy 1.767782 -286.290649) (xy 1.723814 -286.298105) (xy 1.681822 -286.31312)
			(xy 1.643094 -286.335233) (xy 1.608819 -286.363765) (xy 1.58005 -286.397839) (xy 1.557668 -286.436412)
			(xy 1.54236 -286.478299) (xy 1.534597 -286.522214) (xy 1.53416 -286.544512) (xy 1.53416 -286.705649)
			(xy 5.814814 -286.705649) (xy 5.814814 -286.634327) (xy 5.8228 -286.563453) (xy 5.83867 -286.493918)
			(xy 5.862227 -286.426598) (xy 5.893172 -286.362339) (xy 5.931118 -286.301948) (xy 5.975587 -286.246186)
			(xy 6.02602 -286.195753) (xy 6.081782 -286.151284) (xy 6.142173 -286.113338) (xy 6.206432 -286.082393)
			(xy 6.273752 -286.058836) (xy 6.343287 -286.042966) (xy 6.414161 -286.03498) (xy 6.485483 -286.03498)
			(xy 6.556357 -286.042966) (xy 6.625892 -286.058836) (xy 6.693212 -286.082393) (xy 6.757471 -286.113338)
			(xy 6.817862 -286.151284) (xy 6.873624 -286.195753) (xy 6.924057 -286.246186) (xy 6.968526 -286.301948)
			(xy 7.006472 -286.362339) (xy 7.037417 -286.426598) (xy 7.060974 -286.493918) (xy 7.076844 -286.563453)
			(xy 7.08483 -286.634327) (xy 7.08533 -286.669988) (xy 7.08483 -286.705649) (xy 7.076844 -286.776523)
			(xy 7.060974 -286.846058) (xy 7.037417 -286.913378) (xy 7.006472 -286.977637) (xy 6.968526 -287.038028)
			(xy 6.924057 -287.09379) (xy 6.873624 -287.144223) (xy 6.817862 -287.188692) (xy 6.757471 -287.226638)
			(xy 6.693212 -287.257583) (xy 6.625892 -287.28114) (xy 6.556357 -287.29701) (xy 6.485483 -287.304996)
			(xy 6.414161 -287.304996) (xy 6.343287 -287.29701) (xy 6.273752 -287.28114) (xy 6.206432 -287.257583)
			(xy 6.142173 -287.226638) (xy 6.081782 -287.188692) (xy 6.02602 -287.144223) (xy 5.975587 -287.09379)
			(xy 5.931118 -287.038028) (xy 5.893172 -286.977637) (xy 5.862227 -286.913378) (xy 5.83867 -286.846058)
			(xy 5.8228 -286.776523) (xy 5.814814 -286.705649) (xy 1.53416 -286.705649) (xy 1.53416 -286.794956)
			(xy 1.5346 -286.817259) (xy 1.542337 -286.861187) (xy 1.557628 -286.903089) (xy 1.580002 -286.941677)
			(xy 1.608771 -286.975764) (xy 1.643051 -287.004302) (xy 1.681789 -287.026415) (xy 1.723793 -287.041422)
			(xy 1.767773 -287.048863) (xy 1.812376 -287.048508) (xy 1.834388 -287.044892) (xy 1.869836 -287.038842)
			(xy 1.941576 -287.03383) (xy 2.013423 -287.036949) (xy 2.084458 -287.04816) (xy 2.153773 -287.067319)
			(xy 2.220483 -287.094181) (xy 2.283733 -287.128403) (xy 2.342715 -287.169547) (xy 2.396674 -287.217087)
			(xy 2.444921 -287.270415) (xy 2.48684 -287.328849) (xy 2.521892 -287.391643) (xy 2.549632 -287.457992)
			(xy 2.569703 -287.527049) (xy 2.581849 -287.59793) (xy 2.585915 -287.66973) (xy 2.581849 -287.741529)
			(xy 2.569703 -287.81241) (xy 2.549632 -287.881467) (xy 2.521893 -287.947817) (xy 2.48684 -288.01061)
			(xy 2.444922 -288.069044) (xy 2.396675 -288.122373) (xy 2.342715 -288.169913) (xy 2.283733 -288.211057)
			(xy 2.220483 -288.245279) (xy 2.153774 -288.272141) (xy 2.084459 -288.2913) (xy 2.013423 -288.302511)
			(xy 1.941577 -288.30563) (xy 1.869837 -288.300618) (xy 1.834388 -288.294572) (xy 1.812377 -288.290975)
			(xy 1.767782 -288.290645) (xy 1.723814 -288.298102) (xy 1.681821 -288.313116) (xy 1.643093 -288.335229)
			(xy 1.608818 -288.36376) (xy 1.580048 -288.397835) (xy 1.557665 -288.436408) (xy 1.542357 -288.478294)
			(xy 1.534594 -288.52221) (xy 1.53416 -288.544508) (xy 1.53416 -288.705645) (xy 3.314946 -288.705645)
			(xy 3.314946 -288.634323) (xy 3.322932 -288.563449) (xy 3.338802 -288.493914) (xy 3.362359 -288.426594)
			(xy 3.393304 -288.362335) (xy 3.43125 -288.301944) (xy 3.475719 -288.246182) (xy 3.526152 -288.195749)
			(xy 3.581914 -288.15128) (xy 3.642305 -288.113334) (xy 3.706564 -288.082389) (xy 3.773884 -288.058832)
			(xy 3.843419 -288.042962) (xy 3.914293 -288.034976) (xy 3.985615 -288.034976) (xy 4.056489 -288.042962)
			(xy 4.126024 -288.058832) (xy 4.193344 -288.082389) (xy 4.257603 -288.113334) (xy 4.317994 -288.15128)
			(xy 4.373756 -288.195749) (xy 4.424189 -288.246182) (xy 4.468658 -288.301944) (xy 4.506604 -288.362335)
			(xy 4.537549 -288.426594) (xy 4.561106 -288.493914) (xy 4.576976 -288.563449) (xy 4.584962 -288.634323)
			(xy 4.585462 -288.669984) (xy 4.584962 -288.705645) (xy 5.814814 -288.705645) (xy 5.814814 -288.634323)
			(xy 5.8228 -288.563449) (xy 5.83867 -288.493914) (xy 5.862227 -288.426594) (xy 5.893172 -288.362335)
			(xy 5.931118 -288.301944) (xy 5.975587 -288.246182) (xy 6.02602 -288.195749) (xy 6.081782 -288.15128)
			(xy 6.142173 -288.113334) (xy 6.206432 -288.082389) (xy 6.273752 -288.058832) (xy 6.343287 -288.042962)
			(xy 6.414161 -288.034976) (xy 6.485483 -288.034976) (xy 6.556357 -288.042962) (xy 6.625892 -288.058832)
			(xy 6.693212 -288.082389) (xy 6.757471 -288.113334) (xy 6.817862 -288.15128) (xy 6.873624 -288.195749)
			(xy 6.924057 -288.246182) (xy 6.968526 -288.301944) (xy 7.006472 -288.362335) (xy 7.037417 -288.426594)
			(xy 7.060974 -288.493914) (xy 7.076844 -288.563449) (xy 7.08483 -288.634323) (xy 7.08533 -288.669984)
			(xy 7.08483 -288.705645) (xy 7.076844 -288.776519) (xy 7.060974 -288.846054) (xy 7.037417 -288.913374)
			(xy 7.006472 -288.977633) (xy 6.968526 -289.038024) (xy 6.924057 -289.093786) (xy 6.873624 -289.144219)
			(xy 6.817862 -289.188688) (xy 6.757471 -289.226634) (xy 6.693212 -289.257579) (xy 6.625892 -289.281136)
			(xy 6.556357 -289.297006) (xy 6.485483 -289.304992) (xy 6.414161 -289.304992) (xy 6.343287 -289.297006)
			(xy 6.273752 -289.281136) (xy 6.206432 -289.257579) (xy 6.142173 -289.226634) (xy 6.081782 -289.188688)
			(xy 6.02602 -289.144219) (xy 5.975587 -289.093786) (xy 5.931118 -289.038024) (xy 5.893172 -288.977633)
			(xy 5.862227 -288.913374) (xy 5.83867 -288.846054) (xy 5.8228 -288.776519) (xy 5.814814 -288.705645)
			(xy 4.584962 -288.705645) (xy 4.576976 -288.776519) (xy 4.561106 -288.846054) (xy 4.537549 -288.913374)
			(xy 4.506604 -288.977633) (xy 4.468658 -289.038024) (xy 4.424189 -289.093786) (xy 4.373756 -289.144219)
			(xy 4.317994 -289.188688) (xy 4.257603 -289.226634) (xy 4.193344 -289.257579) (xy 4.126024 -289.281136)
			(xy 4.056489 -289.297006) (xy 3.985615 -289.304992) (xy 3.914293 -289.304992) (xy 3.843419 -289.297006)
			(xy 3.773884 -289.281136) (xy 3.706564 -289.257579) (xy 3.642305 -289.226634) (xy 3.581914 -289.188688)
			(xy 3.526152 -289.144219) (xy 3.475719 -289.093786) (xy 3.43125 -289.038024) (xy 3.393304 -288.977633)
			(xy 3.362359 -288.913374) (xy 3.338802 -288.846054) (xy 3.322932 -288.776519) (xy 3.314946 -288.705645)
			(xy 1.53416 -288.705645) (xy 1.53416 -288.794952) (xy 1.5346 -288.817255) (xy 1.542339 -288.861182)
			(xy 1.55763 -288.903083) (xy 1.580004 -288.94167) (xy 1.608773 -288.975755) (xy 1.643053 -289.004293)
			(xy 1.68179 -289.026405) (xy 1.723794 -289.041412) (xy 1.767773 -289.048853) (xy 1.812375 -289.048499)
			(xy 1.834388 -289.044888) (xy 1.869836 -289.038838) (xy 1.941576 -289.033826) (xy 2.013424 -289.036945)
			(xy 2.08446 -289.048156) (xy 2.153775 -289.067315) (xy 2.220485 -289.094178) (xy 2.283735 -289.1284)
			(xy 2.342718 -289.169544) (xy 2.396677 -289.217085) (xy 2.444925 -289.270413) (xy 2.486843 -289.328848)
			(xy 2.521896 -289.391642) (xy 2.549636 -289.457991) (xy 2.569707 -289.527049) (xy 2.581853 -289.59793)
			(xy 2.585919 -289.66973) (xy 2.5839 -289.705389) (xy 7.81481 -289.705389) (xy 7.81481 -289.634067)
			(xy 7.822796 -289.563193) (xy 7.838666 -289.493658) (xy 7.862223 -289.426338) (xy 7.893168 -289.362079)
			(xy 7.931114 -289.301688) (xy 7.975583 -289.245926) (xy 8.026016 -289.195493) (xy 8.081778 -289.151024)
			(xy 8.142169 -289.113078) (xy 8.206428 -289.082133) (xy 8.273748 -289.058576) (xy 8.343283 -289.042706)
			(xy 8.414157 -289.03472) (xy 8.485479 -289.03472) (xy 8.556353 -289.042706) (xy 8.625888 -289.058576)
			(xy 8.693208 -289.082133) (xy 8.757467 -289.113078) (xy 8.817858 -289.151024) (xy 8.87362 -289.195493)
			(xy 8.924053 -289.245926) (xy 8.968522 -289.301688) (xy 9.006468 -289.362079) (xy 9.037413 -289.426338)
			(xy 9.06097 -289.493658) (xy 9.07684 -289.563193) (xy 9.084826 -289.634067) (xy 9.085326 -289.669728)
			(xy 9.084826 -289.705389) (xy 9.07684 -289.776263) (xy 9.06097 -289.845798) (xy 9.037413 -289.913118)
			(xy 9.006468 -289.977377) (xy 8.968522 -290.037768) (xy 8.924053 -290.09353) (xy 8.87362 -290.143963)
			(xy 8.817858 -290.188432) (xy 8.757467 -290.226378) (xy 8.693208 -290.257323) (xy 8.625888 -290.28088)
			(xy 8.556353 -290.29675) (xy 8.485479 -290.304736) (xy 8.414157 -290.304736) (xy 8.343283 -290.29675)
			(xy 8.273748 -290.28088) (xy 8.206428 -290.257323) (xy 8.142169 -290.226378) (xy 8.081778 -290.188432)
			(xy 8.026016 -290.143963) (xy 7.975583 -290.09353) (xy 7.931114 -290.037768) (xy 7.893168 -289.977377)
			(xy 7.862223 -289.913118) (xy 7.838666 -289.845798) (xy 7.822796 -289.776263) (xy 7.81481 -289.705389)
			(xy 2.5839 -289.705389) (xy 2.581853 -289.74153) (xy 2.569707 -289.812412) (xy 2.549636 -289.881469)
			(xy 2.521896 -289.947819) (xy 2.486843 -290.010613) (xy 2.444925 -290.069047) (xy 2.396677 -290.122376)
			(xy 2.342717 -290.169916) (xy 2.283735 -290.211061) (xy 2.220484 -290.245283) (xy 2.153775 -290.272145)
			(xy 2.084459 -290.291304) (xy 2.013423 -290.302515) (xy 1.941576 -290.305634) (xy 1.869836 -290.300622)
			(xy 1.834388 -290.294568) (xy 1.812377 -290.290971) (xy 1.767782 -290.290641) (xy 1.723813 -290.298098)
			(xy 1.68182 -290.313113) (xy 1.643092 -290.335225) (xy 1.608817 -290.363756) (xy 1.580046 -290.397831)
			(xy 1.557663 -290.436404) (xy 1.542354 -290.47829) (xy 1.53459 -290.522206) (xy 1.53416 -290.544504)
			(xy 1.53416 -290.705641) (xy 3.314946 -290.705641) (xy 3.314946 -290.634319) (xy 3.322932 -290.563445)
			(xy 3.338802 -290.49391) (xy 3.362359 -290.42659) (xy 3.393304 -290.362331) (xy 3.43125 -290.30194)
			(xy 3.475719 -290.246178) (xy 3.526152 -290.195745) (xy 3.581914 -290.151276) (xy 3.642305 -290.11333)
			(xy 3.706564 -290.082385) (xy 3.773884 -290.058828) (xy 3.843419 -290.042958) (xy 3.914293 -290.034972)
			(xy 3.985615 -290.034972) (xy 4.056489 -290.042958) (xy 4.126024 -290.058828) (xy 4.193344 -290.082385)
			(xy 4.257603 -290.11333) (xy 4.317994 -290.151276) (xy 4.373756 -290.195745) (xy 4.424189 -290.246178)
			(xy 4.468658 -290.30194) (xy 4.506604 -290.362331) (xy 4.537549 -290.42659) (xy 4.561106 -290.49391)
			(xy 4.576976 -290.563445) (xy 4.584962 -290.634319) (xy 4.585462 -290.66998) (xy 4.584962 -290.705641)
			(xy 5.814814 -290.705641) (xy 5.814814 -290.634319) (xy 5.8228 -290.563445) (xy 5.83867 -290.49391)
			(xy 5.862227 -290.42659) (xy 5.893172 -290.362331) (xy 5.931118 -290.30194) (xy 5.975587 -290.246178)
			(xy 6.02602 -290.195745) (xy 6.081782 -290.151276) (xy 6.142173 -290.11333) (xy 6.206432 -290.082385)
			(xy 6.273752 -290.058828) (xy 6.343287 -290.042958) (xy 6.414161 -290.034972) (xy 6.485483 -290.034972)
			(xy 6.556357 -290.042958) (xy 6.625892 -290.058828) (xy 6.693212 -290.082385) (xy 6.757471 -290.11333)
			(xy 6.817862 -290.151276) (xy 6.873624 -290.195745) (xy 6.924057 -290.246178) (xy 6.968526 -290.30194)
			(xy 7.006472 -290.362331) (xy 7.037417 -290.42659) (xy 7.060974 -290.49391) (xy 7.076844 -290.563445)
			(xy 7.08483 -290.634319) (xy 7.08533 -290.66998) (xy 7.08483 -290.705641) (xy 7.076844 -290.776515)
			(xy 7.060974 -290.84605) (xy 7.037417 -290.91337) (xy 7.006472 -290.977629) (xy 6.968526 -291.03802)
			(xy 6.924057 -291.093782) (xy 6.873624 -291.144215) (xy 6.817862 -291.188684) (xy 6.757471 -291.22663)
			(xy 6.693212 -291.257575) (xy 6.625892 -291.281132) (xy 6.556357 -291.297002) (xy 6.485483 -291.304988)
			(xy 6.414161 -291.304988) (xy 6.343287 -291.297002) (xy 6.273752 -291.281132) (xy 6.206432 -291.257575)
			(xy 6.142173 -291.22663) (xy 6.081782 -291.188684) (xy 6.02602 -291.144215) (xy 5.975587 -291.093782)
			(xy 5.931118 -291.03802) (xy 5.893172 -290.977629) (xy 5.862227 -290.91337) (xy 5.83867 -290.84605)
			(xy 5.8228 -290.776515) (xy 5.814814 -290.705641) (xy 4.584962 -290.705641) (xy 4.576976 -290.776515)
			(xy 4.561106 -290.84605) (xy 4.537549 -290.91337) (xy 4.506604 -290.977629) (xy 4.468658 -291.03802)
			(xy 4.424189 -291.093782) (xy 4.373756 -291.144215) (xy 4.317994 -291.188684) (xy 4.257603 -291.22663)
			(xy 4.193344 -291.257575) (xy 4.126024 -291.281132) (xy 4.056489 -291.297002) (xy 3.985615 -291.304988)
			(xy 3.914293 -291.304988) (xy 3.843419 -291.297002) (xy 3.773884 -291.281132) (xy 3.706564 -291.257575)
			(xy 3.642305 -291.22663) (xy 3.581914 -291.188684) (xy 3.526152 -291.144215) (xy 3.475719 -291.093782)
			(xy 3.43125 -291.03802) (xy 3.393304 -290.977629) (xy 3.362359 -290.91337) (xy 3.338802 -290.84605)
			(xy 3.322932 -290.776515) (xy 3.314946 -290.705641) (xy 1.53416 -290.705641) (xy 1.53416 -291.705385)
			(xy 7.81481 -291.705385) (xy 7.81481 -291.634063) (xy 7.822796 -291.563189) (xy 7.838666 -291.493654)
			(xy 7.862223 -291.426334) (xy 7.893168 -291.362075) (xy 7.931114 -291.301684) (xy 7.975583 -291.245922)
			(xy 8.026016 -291.195489) (xy 8.081778 -291.15102) (xy 8.142169 -291.113074) (xy 8.206428 -291.082129)
			(xy 8.273748 -291.058572) (xy 8.343283 -291.042702) (xy 8.414157 -291.034716) (xy 8.485479 -291.034716)
			(xy 8.556353 -291.042702) (xy 8.625888 -291.058572) (xy 8.693208 -291.082129) (xy 8.757467 -291.113074)
			(xy 8.817858 -291.15102) (xy 8.87362 -291.195489) (xy 8.924053 -291.245922) (xy 8.968522 -291.301684)
			(xy 9.006468 -291.362075) (xy 9.037413 -291.426334) (xy 9.06097 -291.493654) (xy 9.07684 -291.563189)
			(xy 9.084826 -291.634063) (xy 9.085326 -291.669724) (xy 9.084826 -291.705385) (xy 9.07684 -291.776259)
			(xy 9.06097 -291.845794) (xy 9.037413 -291.913114) (xy 9.006468 -291.977373) (xy 8.968522 -292.037764)
			(xy 8.924053 -292.093526) (xy 8.87362 -292.143959) (xy 8.817858 -292.188428) (xy 8.757467 -292.226374)
			(xy 8.693208 -292.257319) (xy 8.625888 -292.280876) (xy 8.556353 -292.296746) (xy 8.485479 -292.304732)
			(xy 8.414157 -292.304732) (xy 8.343283 -292.296746) (xy 8.273748 -292.280876) (xy 8.206428 -292.257319)
			(xy 8.142169 -292.226374) (xy 8.081778 -292.188428) (xy 8.026016 -292.143959) (xy 7.975583 -292.093526)
			(xy 7.931114 -292.037764) (xy 7.893168 -291.977373) (xy 7.862223 -291.913114) (xy 7.838666 -291.845794)
			(xy 7.822796 -291.776259) (xy 7.81481 -291.705385) (xy 1.53416 -291.705385) (xy 1.53416 -292.705637)
			(xy 3.314946 -292.705637) (xy 3.314946 -292.634315) (xy 3.322932 -292.563441) (xy 3.338802 -292.493906)
			(xy 3.362359 -292.426586) (xy 3.393304 -292.362327) (xy 3.43125 -292.301936) (xy 3.475719 -292.246174)
			(xy 3.526152 -292.195741) (xy 3.581914 -292.151272) (xy 3.642305 -292.113326) (xy 3.706564 -292.082381)
			(xy 3.773884 -292.058824) (xy 3.843419 -292.042954) (xy 3.914293 -292.034968) (xy 3.985615 -292.034968)
			(xy 4.056489 -292.042954) (xy 4.126024 -292.058824) (xy 4.193344 -292.082381) (xy 4.257603 -292.113326)
			(xy 4.317994 -292.151272) (xy 4.373756 -292.195741) (xy 4.424189 -292.246174) (xy 4.468658 -292.301936)
			(xy 4.506604 -292.362327) (xy 4.537549 -292.426586) (xy 4.561106 -292.493906) (xy 4.576976 -292.563441)
			(xy 4.584962 -292.634315) (xy 4.585462 -292.669976) (xy 4.584962 -292.705637) (xy 4.576976 -292.776511)
			(xy 4.561106 -292.846046) (xy 4.537549 -292.913366) (xy 4.506604 -292.977625) (xy 4.468658 -293.038016)
			(xy 4.424189 -293.093778) (xy 4.373756 -293.144211) (xy 4.317994 -293.18868) (xy 4.257603 -293.226626)
			(xy 4.193344 -293.257571) (xy 4.126024 -293.281128) (xy 4.056489 -293.296998) (xy 3.985615 -293.304984)
			(xy 3.914293 -293.304984) (xy 3.843419 -293.296998) (xy 3.773884 -293.281128) (xy 3.706564 -293.257571)
			(xy 3.642305 -293.226626) (xy 3.581914 -293.18868) (xy 3.526152 -293.144211) (xy 3.475719 -293.093778)
			(xy 3.43125 -293.038016) (xy 3.393304 -292.977625) (xy 3.362359 -292.913366) (xy 3.338802 -292.846046)
			(xy 3.322932 -292.776511) (xy 3.314946 -292.705637) (xy 1.53416 -292.705637) (xy 1.53416 -292.794944)
			(xy 1.5346 -292.817247) (xy 1.542337 -292.861176) (xy 1.557627 -292.903078) (xy 1.580001 -292.941666)
			(xy 1.60877 -292.975753) (xy 1.643051 -293.004292) (xy 1.681788 -293.026405) (xy 1.723793 -293.041412)
			(xy 1.767773 -293.048853) (xy 1.812376 -293.048498) (xy 1.834388 -293.04488) (xy 1.869836 -293.03883)
			(xy 1.941576 -293.033818) (xy 2.013423 -293.036937) (xy 2.084459 -293.048148) (xy 2.153774 -293.067307)
			(xy 2.220484 -293.094169) (xy 2.283734 -293.128391) (xy 2.342716 -293.169536) (xy 2.396676 -293.217076)
			(xy 2.444923 -293.270404) (xy 2.486841 -293.328839) (xy 2.521894 -293.391632) (xy 2.549634 -293.457982)
			(xy 2.569705 -293.527039) (xy 2.581851 -293.59792) (xy 2.585917 -293.66972) (xy 2.583898 -293.705381)
			(xy 7.81481 -293.705381) (xy 7.81481 -293.634059) (xy 7.822796 -293.563185) (xy 7.838666 -293.49365)
			(xy 7.862223 -293.42633) (xy 7.893168 -293.362071) (xy 7.931114 -293.30168) (xy 7.975583 -293.245918)
			(xy 8.026016 -293.195485) (xy 8.081778 -293.151016) (xy 8.142169 -293.11307) (xy 8.206428 -293.082125)
			(xy 8.273748 -293.058568) (xy 8.343283 -293.042698) (xy 8.414157 -293.034712) (xy 8.485479 -293.034712)
			(xy 8.556353 -293.042698) (xy 8.625888 -293.058568) (xy 8.693208 -293.082125) (xy 8.757467 -293.11307)
			(xy 8.817858 -293.151016) (xy 8.87362 -293.195485) (xy 8.924053 -293.245918) (xy 8.968522 -293.30168)
			(xy 9.006468 -293.362071) (xy 9.037413 -293.42633) (xy 9.06097 -293.49365) (xy 9.07684 -293.563185)
			(xy 9.084826 -293.634059) (xy 9.085326 -293.66972) (xy 9.084826 -293.705381) (xy 9.07684 -293.776255)
			(xy 9.06097 -293.84579) (xy 9.037413 -293.91311) (xy 9.006468 -293.977369) (xy 8.968522 -294.03776)
			(xy 8.924053 -294.093522) (xy 8.87362 -294.143955) (xy 8.817858 -294.188424) (xy 8.757467 -294.22637)
			(xy 8.693208 -294.257315) (xy 8.625888 -294.280872) (xy 8.556353 -294.296742) (xy 8.485479 -294.304728)
			(xy 8.414157 -294.304728) (xy 8.343283 -294.296742) (xy 8.273748 -294.280872) (xy 8.206428 -294.257315)
			(xy 8.142169 -294.22637) (xy 8.081778 -294.188424) (xy 8.026016 -294.143955) (xy 7.975583 -294.093522)
			(xy 7.931114 -294.03776) (xy 7.893168 -293.977369) (xy 7.862223 -293.91311) (xy 7.838666 -293.84579)
			(xy 7.822796 -293.776255) (xy 7.81481 -293.705381) (xy 2.583898 -293.705381) (xy 2.581851 -293.74152)
			(xy 2.569705 -293.812401) (xy 2.549634 -293.881458) (xy 2.521894 -293.947808) (xy 2.486841 -294.010601)
			(xy 2.444923 -294.069036) (xy 2.396676 -294.122364) (xy 2.342716 -294.169904) (xy 2.283734 -294.211049)
			(xy 2.220484 -294.245271) (xy 2.153774 -294.272133) (xy 2.084459 -294.291292) (xy 2.013423 -294.302503)
			(xy 1.941576 -294.305622) (xy 1.869836 -294.30061) (xy 1.834388 -294.29456) (xy 1.812377 -294.290964)
			(xy 1.767781 -294.290633) (xy 1.723812 -294.29809) (xy 1.681819 -294.313105) (xy 1.64309 -294.335217)
			(xy 1.608814 -294.363748) (xy 1.580042 -294.397823) (xy 1.557658 -294.436395) (xy 1.542349 -294.478282)
			(xy 1.534583 -294.522197) (xy 1.53416 -294.544496) (xy 1.53416 -294.705633) (xy 3.314946 -294.705633)
			(xy 3.314946 -294.634311) (xy 3.322932 -294.563437) (xy 3.338802 -294.493902) (xy 3.362359 -294.426582)
			(xy 3.393304 -294.362323) (xy 3.43125 -294.301932) (xy 3.475719 -294.24617) (xy 3.526152 -294.195737)
			(xy 3.581914 -294.151268) (xy 3.642305 -294.113322) (xy 3.706564 -294.082377) (xy 3.773884 -294.05882)
			(xy 3.843419 -294.04295) (xy 3.914293 -294.034964) (xy 3.985615 -294.034964) (xy 4.056489 -294.04295)
			(xy 4.126024 -294.05882) (xy 4.193344 -294.082377) (xy 4.257603 -294.113322) (xy 4.317994 -294.151268)
			(xy 4.373756 -294.195737) (xy 4.424189 -294.24617) (xy 4.468658 -294.301932) (xy 4.506604 -294.362323)
			(xy 4.537549 -294.426582) (xy 4.561106 -294.493902) (xy 4.576976 -294.563437) (xy 4.584962 -294.634311)
			(xy 4.585462 -294.669972) (xy 4.584962 -294.705633) (xy 5.814814 -294.705633) (xy 5.814814 -294.634311)
			(xy 5.8228 -294.563437) (xy 5.83867 -294.493902) (xy 5.862227 -294.426582) (xy 5.893172 -294.362323)
			(xy 5.931118 -294.301932) (xy 5.975587 -294.24617) (xy 6.02602 -294.195737) (xy 6.081782 -294.151268)
			(xy 6.142173 -294.113322) (xy 6.206432 -294.082377) (xy 6.273752 -294.05882) (xy 6.343287 -294.04295)
			(xy 6.414161 -294.034964) (xy 6.485483 -294.034964) (xy 6.556357 -294.04295) (xy 6.625892 -294.05882)
			(xy 6.693212 -294.082377) (xy 6.757471 -294.113322) (xy 6.817862 -294.151268) (xy 6.873624 -294.195737)
			(xy 6.924057 -294.24617) (xy 6.968526 -294.301932) (xy 7.006472 -294.362323) (xy 7.037417 -294.426582)
			(xy 7.060974 -294.493902) (xy 7.076844 -294.563437) (xy 7.08483 -294.634311) (xy 7.08533 -294.669972)
			(xy 7.08483 -294.705633) (xy 7.076844 -294.776507) (xy 7.060974 -294.846042) (xy 7.037417 -294.913362)
			(xy 7.006472 -294.977621) (xy 6.968526 -295.038012) (xy 6.924057 -295.093774) (xy 6.873624 -295.144207)
			(xy 6.817862 -295.188676) (xy 6.757471 -295.226622) (xy 6.693212 -295.257567) (xy 6.625892 -295.281124)
			(xy 6.556357 -295.296994) (xy 6.485483 -295.30498) (xy 6.414161 -295.30498) (xy 6.343287 -295.296994)
			(xy 6.273752 -295.281124) (xy 6.206432 -295.257567) (xy 6.142173 -295.226622) (xy 6.081782 -295.188676)
			(xy 6.02602 -295.144207) (xy 5.975587 -295.093774) (xy 5.931118 -295.038012) (xy 5.893172 -294.977621)
			(xy 5.862227 -294.913362) (xy 5.83867 -294.846042) (xy 5.8228 -294.776507) (xy 5.814814 -294.705633)
			(xy 4.584962 -294.705633) (xy 4.576976 -294.776507) (xy 4.561106 -294.846042) (xy 4.537549 -294.913362)
			(xy 4.506604 -294.977621) (xy 4.468658 -295.038012) (xy 4.424189 -295.093774) (xy 4.373756 -295.144207)
			(xy 4.317994 -295.188676) (xy 4.257603 -295.226622) (xy 4.193344 -295.257567) (xy 4.126024 -295.281124)
			(xy 4.056489 -295.296994) (xy 3.985615 -295.30498) (xy 3.914293 -295.30498) (xy 3.843419 -295.296994)
			(xy 3.773884 -295.281124) (xy 3.706564 -295.257567) (xy 3.642305 -295.226622) (xy 3.581914 -295.188676)
			(xy 3.526152 -295.144207) (xy 3.475719 -295.093774) (xy 3.43125 -295.038012) (xy 3.393304 -294.977621)
			(xy 3.362359 -294.913362) (xy 3.338802 -294.846042) (xy 3.322932 -294.776507) (xy 3.314946 -294.705633)
			(xy 1.53416 -294.705633) (xy 1.53416 -294.795194) (xy 1.5346 -294.817497) (xy 1.542337 -294.861426)
			(xy 1.557627 -294.903328) (xy 1.580001 -294.941916) (xy 1.60877 -294.976003) (xy 1.643051 -295.004542)
			(xy 1.681788 -295.026655) (xy 1.723793 -295.041662) (xy 1.767773 -295.049103) (xy 1.812376 -295.048748)
			(xy 1.834388 -295.04513) (xy 1.869836 -295.03908) (xy 1.941576 -295.034068) (xy 2.013423 -295.037187)
			(xy 2.084459 -295.048398) (xy 2.153774 -295.067557) (xy 2.220484 -295.094419) (xy 2.283734 -295.128641)
			(xy 2.342716 -295.169786) (xy 2.396676 -295.217326) (xy 2.444923 -295.270654) (xy 2.486841 -295.329089)
			(xy 2.521894 -295.391882) (xy 2.549634 -295.458232) (xy 2.569705 -295.527289) (xy 2.581851 -295.59817)
			(xy 2.585917 -295.66997) (xy 2.583898 -295.705631) (xy 7.81481 -295.705631) (xy 7.81481 -295.634309)
			(xy 7.822796 -295.563435) (xy 7.838666 -295.4939) (xy 7.862223 -295.42658) (xy 7.893168 -295.362321)
			(xy 7.931114 -295.30193) (xy 7.975583 -295.246168) (xy 8.026016 -295.195735) (xy 8.081778 -295.151266)
			(xy 8.142169 -295.11332) (xy 8.206428 -295.082375) (xy 8.273748 -295.058818) (xy 8.343283 -295.042948)
			(xy 8.414157 -295.034962) (xy 8.485479 -295.034962) (xy 8.556353 -295.042948) (xy 8.625888 -295.058818)
			(xy 8.693208 -295.082375) (xy 8.757467 -295.11332) (xy 8.817858 -295.151266) (xy 8.87362 -295.195735)
			(xy 8.924053 -295.246168) (xy 8.968522 -295.30193) (xy 9.006468 -295.362321) (xy 9.037413 -295.42658)
			(xy 9.06097 -295.4939) (xy 9.07684 -295.563435) (xy 9.084826 -295.634309) (xy 9.085326 -295.66997)
			(xy 9.084826 -295.705631) (xy 9.07684 -295.776505) (xy 9.06097 -295.84604) (xy 9.042055 -295.900094)
			(xy 11.59841 -295.900094) (xy 11.602414 -295.699986) (xy 11.614422 -295.500198) (xy 11.634414 -295.30105)
			(xy 11.662357 -295.102862) (xy 11.698207 -294.905951) (xy 11.741908 -294.710631) (xy 11.793387 -294.517217)
			(xy 11.852564 -294.326017) (xy 11.919344 -294.137337) (xy 11.993619 -293.951481) (xy 12.07527 -293.768745)
			(xy 12.164168 -293.589422) (xy 12.260168 -293.4138) (xy 12.363119 -293.242159) (xy 12.472854 -293.074775)
			(xy 12.589199 -292.911915) (xy 12.711966 -292.75384) (xy 12.840959 -292.600804) (xy 12.975972 -292.453052)
			(xy 13.116789 -292.310819) (xy 13.263183 -292.174335) (xy 13.414921 -292.043816) (xy 13.57176 -291.919474)
			(xy 13.733447 -291.801506) (xy 13.899726 -291.690101) (xy 14.070328 -291.585439) (xy 14.244981 -291.487686)
			(xy 14.423405 -291.396999) (xy 14.605315 -291.313523) (xy 14.790419 -291.237392) (xy 14.978421 -291.168728)
			(xy 15.169019 -291.107641) (xy 15.361909 -291.054229) (xy 15.556781 -291.008577) (xy 15.753324 -290.970758)
			(xy 15.951223 -290.940834) (xy 16.15016 -290.91885) (xy 16.349818 -290.904844) (xy 16.549876 -290.898838)
			(xy 16.750015 -290.90084) (xy 16.949913 -290.910849) (xy 17.14925 -290.928847) (xy 17.347708 -290.954806)
			(xy 17.544968 -290.988684) (xy 17.740715 -291.030428) (xy 17.934635 -291.07997) (xy 18.126418 -291.137231)
			(xy 18.315756 -291.20212) (xy 18.502346 -291.274532) (xy 18.68589 -291.354351) (xy 18.866093 -291.44145)
			(xy 19.042667 -291.535688) (xy 19.215329 -291.636917) (xy 19.383803 -291.744972) (xy 19.547819 -291.859681)
			(xy 19.707114 -291.980861) (xy 19.861433 -292.108316) (xy 20.010529 -292.241845) (xy 20.154163 -292.381231)
			(xy 20.292105 -292.526253) (xy 20.424135 -292.676677) (xy 20.550041 -292.832264) (xy 20.66962 -292.992763)
			(xy 20.782683 -293.157918) (xy 20.889047 -293.327465) (xy 20.988543 -293.501131) (xy 21.08101 -293.678639)
			(xy 21.166302 -293.859705) (xy 21.244281 -294.044038) (xy 21.314822 -294.231343) (xy 21.377813 -294.421321)
			(xy 21.433152 -294.613667) (xy 21.480752 -294.808072) (xy 21.520535 -295.004227) (xy 21.552438 -295.201817)
			(xy 21.57641 -295.400524) (xy 21.592413 -295.600032) (xy 21.600421 -295.80002) (xy 21.600922 -295.900094)
			(xy 21.600421 -296.000168) (xy 21.592413 -296.200156) (xy 21.57641 -296.399664) (xy 21.552438 -296.598371)
			(xy 21.520535 -296.795961) (xy 21.480752 -296.992116) (xy 21.433152 -297.186521) (xy 21.377813 -297.378867)
			(xy 21.314822 -297.568845) (xy 21.244281 -297.75615) (xy 21.166302 -297.940483) (xy 21.08101 -298.121549)
			(xy 20.988543 -298.299057) (xy 20.889047 -298.472723) (xy 20.782683 -298.64227) (xy 20.66962 -298.807425)
			(xy 20.550041 -298.967924) (xy 20.424135 -299.123511) (xy 20.292105 -299.273935) (xy 20.154163 -299.418957)
			(xy 20.010529 -299.558343) (xy 19.861433 -299.691872) (xy 19.707114 -299.819327) (xy 19.547819 -299.940507)
			(xy 19.383803 -300.055216) (xy 19.215329 -300.163271) (xy 19.042667 -300.2645) (xy 18.866093 -300.358738)
			(xy 18.68589 -300.445837) (xy 18.502346 -300.525656) (xy 18.315756 -300.598068) (xy 18.126418 -300.662957)
			(xy 17.934635 -300.720218) (xy 17.740715 -300.76976) (xy 17.544968 -300.811504) (xy 17.347708 -300.845382)
			(xy 17.14925 -300.871341) (xy 16.949913 -300.889339) (xy 16.750015 -300.899348) (xy 16.549876 -300.90135)
			(xy 16.349818 -300.895344) (xy 16.15016 -300.881338) (xy 15.951223 -300.859354) (xy 15.753324 -300.82943)
			(xy 15.556781 -300.791611) (xy 15.361909 -300.745959) (xy 15.169019 -300.692547) (xy 14.978421 -300.63146)
			(xy 14.790419 -300.562796) (xy 14.605315 -300.486665) (xy 14.423405 -300.403189) (xy 14.244981 -300.312502)
			(xy 14.070328 -300.214749) (xy 13.899726 -300.110087) (xy 13.733447 -299.998682) (xy 13.57176 -299.880714)
			(xy 13.414921 -299.756372) (xy 13.263183 -299.625853) (xy 13.116789 -299.489369) (xy 12.975972 -299.347136)
			(xy 12.840959 -299.199384) (xy 12.711966 -299.046348) (xy 12.589199 -298.888273) (xy 12.472854 -298.725413)
			(xy 12.363119 -298.558029) (xy 12.260168 -298.386388) (xy 12.164168 -298.210766) (xy 12.07527 -298.031443)
			(xy 11.993619 -297.848707) (xy 11.919344 -297.662851) (xy 11.852564 -297.474171) (xy 11.793387 -297.282971)
			(xy 11.741908 -297.089557) (xy 11.698207 -296.894237) (xy 11.662357 -296.697326) (xy 11.634414 -296.499138)
			(xy 11.614422 -296.29999) (xy 11.602414 -296.100202) (xy 11.59841 -295.900094) (xy 9.042055 -295.900094)
			(xy 9.037413 -295.91336) (xy 9.006468 -295.977619) (xy 8.968522 -296.03801) (xy 8.924053 -296.093772)
			(xy 8.87362 -296.144205) (xy 8.817858 -296.188674) (xy 8.757467 -296.22662) (xy 8.693208 -296.257565)
			(xy 8.625888 -296.281122) (xy 8.556353 -296.296992) (xy 8.485479 -296.304978) (xy 8.414157 -296.304978)
			(xy 8.343283 -296.296992) (xy 8.273748 -296.281122) (xy 8.206428 -296.257565) (xy 8.142169 -296.22662)
			(xy 8.081778 -296.188674) (xy 8.026016 -296.144205) (xy 7.975583 -296.093772) (xy 7.931114 -296.03801)
			(xy 7.893168 -295.977619) (xy 7.862223 -295.91336) (xy 7.838666 -295.84604) (xy 7.822796 -295.776505)
			(xy 7.81481 -295.705631) (xy 2.583898 -295.705631) (xy 2.581851 -295.74177) (xy 2.569705 -295.812651)
			(xy 2.549634 -295.881708) (xy 2.521894 -295.948058) (xy 2.486841 -296.010851) (xy 2.444923 -296.069286)
			(xy 2.396676 -296.122614) (xy 2.342716 -296.170154) (xy 2.283734 -296.211299) (xy 2.220484 -296.245521)
			(xy 2.153774 -296.272383) (xy 2.084459 -296.291542) (xy 2.013423 -296.302753) (xy 1.941576 -296.305872)
			(xy 1.869836 -296.30086) (xy 1.834388 -296.29481) (xy 1.812378 -296.291213) (xy 1.767785 -296.290882)
			(xy 1.723819 -296.298339) (xy 1.681829 -296.313354) (xy 1.643103 -296.335467) (xy 1.608832 -296.364)
			(xy 1.580066 -296.398075) (xy 1.557688 -296.436648) (xy 1.542385 -296.478534) (xy 1.534628 -296.522449)
			(xy 1.53416 -296.544746) (xy 1.53416 -296.705629) (xy 5.814814 -296.705629) (xy 5.814814 -296.634307)
			(xy 5.8228 -296.563433) (xy 5.83867 -296.493898) (xy 5.862227 -296.426578) (xy 5.893172 -296.362319)
			(xy 5.931118 -296.301928) (xy 5.975587 -296.246166) (xy 6.02602 -296.195733) (xy 6.081782 -296.151264)
			(xy 6.142173 -296.113318) (xy 6.206432 -296.082373) (xy 6.273752 -296.058816) (xy 6.343287 -296.042946)
			(xy 6.414161 -296.03496) (xy 6.485483 -296.03496) (xy 6.556357 -296.042946) (xy 6.625892 -296.058816)
			(xy 6.693212 -296.082373) (xy 6.757471 -296.113318) (xy 6.817862 -296.151264) (xy 6.873624 -296.195733)
			(xy 6.924057 -296.246166) (xy 6.968526 -296.301928) (xy 7.006472 -296.362319) (xy 7.037417 -296.426578)
			(xy 7.060974 -296.493898) (xy 7.076844 -296.563433) (xy 7.08483 -296.634307) (xy 7.08533 -296.669968)
			(xy 7.08483 -296.705629) (xy 7.076844 -296.776503) (xy 7.060974 -296.846038) (xy 7.037417 -296.913358)
			(xy 7.006472 -296.977617) (xy 6.968526 -297.038008) (xy 6.924057 -297.09377) (xy 6.873624 -297.144203)
			(xy 6.817862 -297.188672) (xy 6.757471 -297.226618) (xy 6.693212 -297.257563) (xy 6.625892 -297.28112)
			(xy 6.556357 -297.29699) (xy 6.485483 -297.304976) (xy 6.414161 -297.304976) (xy 6.343287 -297.29699)
			(xy 6.273752 -297.28112) (xy 6.206432 -297.257563) (xy 6.142173 -297.226618) (xy 6.081782 -297.188672)
			(xy 6.02602 -297.144203) (xy 5.975587 -297.09377) (xy 5.931118 -297.038008) (xy 5.893172 -296.977617)
			(xy 5.862227 -296.913358) (xy 5.83867 -296.846038) (xy 5.8228 -296.776503) (xy 5.814814 -296.705629)
			(xy 1.53416 -296.705629) (xy 1.53416 -296.79519) (xy 1.5346 -296.817493) (xy 1.542338 -296.861421)
			(xy 1.557629 -296.903322) (xy 1.580003 -296.941909) (xy 1.608772 -296.975995) (xy 1.643052 -297.004533)
			(xy 1.68179 -297.026645) (xy 1.723794 -297.041652) (xy 1.767773 -297.049093) (xy 1.812376 -297.048739)
			(xy 1.834388 -297.045126) (xy 1.869836 -297.039076) (xy 1.941576 -297.034064) (xy 2.013423 -297.037184)
			(xy 2.084458 -297.048395) (xy 2.153774 -297.067554) (xy 2.220483 -297.094416) (xy 2.283733 -297.128638)
			(xy 2.342715 -297.169782) (xy 2.396674 -297.217323) (xy 2.444921 -297.270651) (xy 2.486839 -297.329085)
			(xy 2.521892 -297.391879) (xy 2.549632 -297.458228) (xy 2.569703 -297.527285) (xy 2.581849 -297.598166)
			(xy 2.585915 -297.669966) (xy 2.581849 -297.741766) (xy 2.569703 -297.812647) (xy 2.549632 -297.881704)
			(xy 2.521892 -297.948053) (xy 2.486839 -298.010847) (xy 2.444921 -298.069281) (xy 2.396674 -298.122609)
			(xy 2.342715 -298.17015) (xy 2.283733 -298.211294) (xy 2.220483 -298.245516) (xy 2.153774 -298.272378)
			(xy 2.084458 -298.291537) (xy 2.013423 -298.302748) (xy 1.941576 -298.305868) (xy 1.869836 -298.300856)
			(xy 1.834388 -298.294806) (xy 1.812378 -298.291209) (xy 1.767785 -298.290878) (xy 1.723818 -298.298335)
			(xy 1.681828 -298.31335) (xy 1.643102 -298.335463) (xy 1.60883 -298.363995) (xy 1.580064 -298.398071)
			(xy 1.557685 -298.436644) (xy 1.542382 -298.47853) (xy 1.534624 -298.522445) (xy 1.53416 -298.544742)
			(xy 1.53416 -298.705625) (xy 3.314946 -298.705625) (xy 3.314946 -298.634303) (xy 3.322932 -298.563429)
			(xy 3.338802 -298.493894) (xy 3.362359 -298.426574) (xy 3.393304 -298.362315) (xy 3.43125 -298.301924)
			(xy 3.475719 -298.246162) (xy 3.526152 -298.195729) (xy 3.581914 -298.15126) (xy 3.642305 -298.113314)
			(xy 3.706564 -298.082369) (xy 3.773884 -298.058812) (xy 3.843419 -298.042942) (xy 3.914293 -298.034956)
			(xy 3.985615 -298.034956) (xy 4.056489 -298.042942) (xy 4.126024 -298.058812) (xy 4.193344 -298.082369)
			(xy 4.257603 -298.113314) (xy 4.317994 -298.15126) (xy 4.373756 -298.195729) (xy 4.424189 -298.246162)
			(xy 4.468658 -298.301924) (xy 4.506604 -298.362315) (xy 4.537549 -298.426574) (xy 4.561106 -298.493894)
			(xy 4.576976 -298.563429) (xy 4.584962 -298.634303) (xy 4.585462 -298.669964) (xy 4.584962 -298.705625)
			(xy 5.814814 -298.705625) (xy 5.814814 -298.634303) (xy 5.8228 -298.563429) (xy 5.83867 -298.493894)
			(xy 5.862227 -298.426574) (xy 5.893172 -298.362315) (xy 5.931118 -298.301924) (xy 5.975587 -298.246162)
			(xy 6.02602 -298.195729) (xy 6.081782 -298.15126) (xy 6.142173 -298.113314) (xy 6.206432 -298.082369)
			(xy 6.273752 -298.058812) (xy 6.343287 -298.042942) (xy 6.414161 -298.034956) (xy 6.485483 -298.034956)
			(xy 6.556357 -298.042942) (xy 6.625892 -298.058812) (xy 6.693212 -298.082369) (xy 6.757471 -298.113314)
			(xy 6.817862 -298.15126) (xy 6.873624 -298.195729) (xy 6.924057 -298.246162) (xy 6.968526 -298.301924)
			(xy 7.006472 -298.362315) (xy 7.037417 -298.426574) (xy 7.060974 -298.493894) (xy 7.076844 -298.563429)
			(xy 7.08483 -298.634303) (xy 7.08533 -298.669964) (xy 7.08483 -298.705625) (xy 7.076844 -298.776499)
			(xy 7.060974 -298.846034) (xy 7.037417 -298.913354) (xy 7.006472 -298.977613) (xy 6.968526 -299.038004)
			(xy 6.924057 -299.093766) (xy 6.873624 -299.144199) (xy 6.817862 -299.188668) (xy 6.757471 -299.226614)
			(xy 6.693212 -299.257559) (xy 6.625892 -299.281116) (xy 6.556357 -299.296986) (xy 6.485483 -299.304972)
			(xy 6.414161 -299.304972) (xy 6.343287 -299.296986) (xy 6.273752 -299.281116) (xy 6.206432 -299.257559)
			(xy 6.142173 -299.226614) (xy 6.081782 -299.188668) (xy 6.02602 -299.144199) (xy 5.975587 -299.093766)
			(xy 5.931118 -299.038004) (xy 5.893172 -298.977613) (xy 5.862227 -298.913354) (xy 5.83867 -298.846034)
			(xy 5.8228 -298.776499) (xy 5.814814 -298.705625) (xy 4.584962 -298.705625) (xy 4.576976 -298.776499)
			(xy 4.561106 -298.846034) (xy 4.537549 -298.913354) (xy 4.506604 -298.977613) (xy 4.468658 -299.038004)
			(xy 4.424189 -299.093766) (xy 4.373756 -299.144199) (xy 4.317994 -299.188668) (xy 4.257603 -299.226614)
			(xy 4.193344 -299.257559) (xy 4.126024 -299.281116) (xy 4.056489 -299.296986) (xy 3.985615 -299.304972)
			(xy 3.914293 -299.304972) (xy 3.843419 -299.296986) (xy 3.773884 -299.281116) (xy 3.706564 -299.257559)
			(xy 3.642305 -299.226614) (xy 3.581914 -299.188668) (xy 3.526152 -299.144199) (xy 3.475719 -299.093766)
			(xy 3.43125 -299.038004) (xy 3.393304 -298.977613) (xy 3.362359 -298.913354) (xy 3.338802 -298.846034)
			(xy 3.322932 -298.776499) (xy 3.314946 -298.705625) (xy 1.53416 -298.705625) (xy 1.53416 -298.795186)
			(xy 1.5346 -298.817489) (xy 1.542337 -298.861417) (xy 1.557628 -298.903319) (xy 1.580002 -298.941907)
			(xy 1.608771 -298.975994) (xy 1.643051 -299.004532) (xy 1.681789 -299.026645) (xy 1.723793 -299.041652)
			(xy 1.767773 -299.049093) (xy 1.812376 -299.048738) (xy 1.834388 -299.045122) (xy 1.869836 -299.039072)
			(xy 1.941576 -299.03406) (xy 2.013423 -299.037179) (xy 2.084458 -299.04839) (xy 2.153773 -299.067549)
			(xy 2.220483 -299.094411) (xy 2.283733 -299.128633) (xy 2.342715 -299.169777) (xy 2.396674 -299.217317)
			(xy 2.444921 -299.270645) (xy 2.48684 -299.329079) (xy 2.521892 -299.391873) (xy 2.549632 -299.458222)
			(xy 2.569703 -299.527279) (xy 2.581849 -299.59816) (xy 2.585915 -299.66996) (xy 2.583895 -299.705623)
			(xy 7.81481 -299.705623) (xy 7.81481 -299.634301) (xy 7.822796 -299.563427) (xy 7.838666 -299.493892)
			(xy 7.862223 -299.426572) (xy 7.893168 -299.362313) (xy 7.931114 -299.301922) (xy 7.975583 -299.24616)
			(xy 8.026016 -299.195727) (xy 8.081778 -299.151258) (xy 8.142169 -299.113312) (xy 8.206428 -299.082367)
			(xy 8.273748 -299.05881) (xy 8.343283 -299.04294) (xy 8.414157 -299.034954) (xy 8.485479 -299.034954)
			(xy 8.556353 -299.04294) (xy 8.625888 -299.05881) (xy 8.693208 -299.082367) (xy 8.757467 -299.113312)
			(xy 8.817858 -299.151258) (xy 8.87362 -299.195727) (xy 8.924053 -299.24616) (xy 8.968522 -299.301922)
			(xy 9.006468 -299.362313) (xy 9.037413 -299.426572) (xy 9.06097 -299.493892) (xy 9.07684 -299.563427)
			(xy 9.084826 -299.634301) (xy 9.085326 -299.669962) (xy 9.084826 -299.705623) (xy 9.07684 -299.776497)
			(xy 9.06097 -299.846032) (xy 9.037413 -299.913352) (xy 9.006468 -299.977611) (xy 8.968522 -300.038002)
			(xy 8.924053 -300.093764) (xy 8.87362 -300.144197) (xy 8.817858 -300.188666) (xy 8.757467 -300.226612)
			(xy 8.693208 -300.257557) (xy 8.625888 -300.281114) (xy 8.556353 -300.296984) (xy 8.485479 -300.30497)
			(xy 8.414157 -300.30497) (xy 8.343283 -300.296984) (xy 8.273748 -300.281114) (xy 8.206428 -300.257557)
			(xy 8.142169 -300.226612) (xy 8.081778 -300.188666) (xy 8.026016 -300.144197) (xy 7.975583 -300.093764)
			(xy 7.931114 -300.038002) (xy 7.893168 -299.977611) (xy 7.862223 -299.913352) (xy 7.838666 -299.846032)
			(xy 7.822796 -299.776497) (xy 7.81481 -299.705623) (xy 2.583895 -299.705623) (xy 2.581849 -299.741759)
			(xy 2.569703 -299.81264) (xy 2.549632 -299.881697) (xy 2.521893 -299.948047) (xy 2.48684 -300.01084)
			(xy 2.444922 -300.069274) (xy 2.396675 -300.122603) (xy 2.342715 -300.170143) (xy 2.283733 -300.211287)
			(xy 2.220483 -300.245509) (xy 2.153774 -300.272371) (xy 2.084459 -300.29153) (xy 2.013423 -300.302741)
			(xy 1.941577 -300.30586) (xy 1.869837 -300.300848) (xy 1.834388 -300.294802) (xy 1.812378 -300.291205)
			(xy 1.767784 -300.290874) (xy 1.723818 -300.298331) (xy 1.681827 -300.313346) (xy 1.643101 -300.335459)
			(xy 1.608829 -300.363991) (xy 1.580062 -300.398067) (xy 1.557683 -300.43664) (xy 1.542379 -300.478526)
			(xy 1.534621 -300.52244) (xy 1.53416 -300.544738) (xy 1.53416 -300.705621) (xy 3.314946 -300.705621)
			(xy 3.314946 -300.634299) (xy 3.322932 -300.563425) (xy 3.338802 -300.49389) (xy 3.362359 -300.42657)
			(xy 3.393304 -300.362311) (xy 3.43125 -300.30192) (xy 3.475719 -300.246158) (xy 3.526152 -300.195725)
			(xy 3.581914 -300.151256) (xy 3.642305 -300.11331) (xy 3.706564 -300.082365) (xy 3.773884 -300.058808)
			(xy 3.843419 -300.042938) (xy 3.914293 -300.034952) (xy 3.985615 -300.034952) (xy 4.056489 -300.042938)
			(xy 4.126024 -300.058808) (xy 4.193344 -300.082365) (xy 4.257603 -300.11331) (xy 4.317994 -300.151256)
			(xy 4.373756 -300.195725) (xy 4.424189 -300.246158) (xy 4.468658 -300.30192) (xy 4.506604 -300.362311)
			(xy 4.537549 -300.42657) (xy 4.561106 -300.49389) (xy 4.576976 -300.563425) (xy 4.584962 -300.634299)
			(xy 4.585462 -300.66996) (xy 4.584962 -300.705621) (xy 5.814814 -300.705621) (xy 5.814814 -300.634299)
			(xy 5.8228 -300.563425) (xy 5.83867 -300.49389) (xy 5.862227 -300.42657) (xy 5.893172 -300.362311)
			(xy 5.931118 -300.30192) (xy 5.975587 -300.246158) (xy 6.02602 -300.195725) (xy 6.081782 -300.151256)
			(xy 6.142173 -300.11331) (xy 6.206432 -300.082365) (xy 6.273752 -300.058808) (xy 6.343287 -300.042938)
			(xy 6.414161 -300.034952) (xy 6.485483 -300.034952) (xy 6.556357 -300.042938) (xy 6.625892 -300.058808)
			(xy 6.693212 -300.082365) (xy 6.757471 -300.11331) (xy 6.817862 -300.151256) (xy 6.873624 -300.195725)
			(xy 6.924057 -300.246158) (xy 6.968526 -300.30192) (xy 7.006472 -300.362311) (xy 7.037417 -300.42657)
			(xy 7.060974 -300.49389) (xy 7.076844 -300.563425) (xy 7.08483 -300.634299) (xy 7.08533 -300.66996)
			(xy 7.08483 -300.705621) (xy 7.076844 -300.776495) (xy 7.060974 -300.84603) (xy 7.037417 -300.91335)
			(xy 7.006472 -300.977609) (xy 6.968526 -301.038) (xy 6.924057 -301.093762) (xy 6.873624 -301.144195)
			(xy 6.817862 -301.188664) (xy 6.757471 -301.22661) (xy 6.693212 -301.257555) (xy 6.625892 -301.281112)
			(xy 6.556357 -301.296982) (xy 6.485483 -301.304968) (xy 6.414161 -301.304968) (xy 6.343287 -301.296982)
			(xy 6.273752 -301.281112) (xy 6.206432 -301.257555) (xy 6.142173 -301.22661) (xy 6.081782 -301.188664)
			(xy 6.02602 -301.144195) (xy 5.975587 -301.093762) (xy 5.931118 -301.038) (xy 5.893172 -300.977609)
			(xy 5.862227 -300.91335) (xy 5.83867 -300.84603) (xy 5.8228 -300.776495) (xy 5.814814 -300.705621)
			(xy 4.584962 -300.705621) (xy 4.576976 -300.776495) (xy 4.561106 -300.84603) (xy 4.537549 -300.91335)
			(xy 4.506604 -300.977609) (xy 4.468658 -301.038) (xy 4.424189 -301.093762) (xy 4.373756 -301.144195)
			(xy 4.317994 -301.188664) (xy 4.257603 -301.22661) (xy 4.193344 -301.257555) (xy 4.126024 -301.281112)
			(xy 4.056489 -301.296982) (xy 3.985615 -301.304968) (xy 3.914293 -301.304968) (xy 3.843419 -301.296982)
			(xy 3.773884 -301.281112) (xy 3.706564 -301.257555) (xy 3.642305 -301.22661) (xy 3.581914 -301.188664)
			(xy 3.526152 -301.144195) (xy 3.475719 -301.093762) (xy 3.43125 -301.038) (xy 3.393304 -300.977609)
			(xy 3.362359 -300.91335) (xy 3.338802 -300.84603) (xy 3.322932 -300.776495) (xy 3.314946 -300.705621)
			(xy 1.53416 -300.705621) (xy 1.53416 -301.705619) (xy 7.81481 -301.705619) (xy 7.81481 -301.634297)
			(xy 7.822796 -301.563423) (xy 7.838666 -301.493888) (xy 7.862223 -301.426568) (xy 7.893168 -301.362309)
			(xy 7.931114 -301.301918) (xy 7.975583 -301.246156) (xy 8.026016 -301.195723) (xy 8.081778 -301.151254)
			(xy 8.142169 -301.113308) (xy 8.206428 -301.082363) (xy 8.273748 -301.058806) (xy 8.343283 -301.042936)
			(xy 8.414157 -301.03495) (xy 8.485479 -301.03495) (xy 8.556353 -301.042936) (xy 8.625888 -301.058806)
			(xy 8.693208 -301.082363) (xy 8.757467 -301.113308) (xy 8.817858 -301.151254) (xy 8.87362 -301.195723)
			(xy 8.924053 -301.246156) (xy 8.968522 -301.301918) (xy 9.006468 -301.362309) (xy 9.037413 -301.426568)
			(xy 9.06097 -301.493888) (xy 9.07684 -301.563423) (xy 9.084826 -301.634297) (xy 9.085326 -301.669958)
			(xy 9.084826 -301.705619) (xy 9.07684 -301.776493) (xy 9.06097 -301.846028) (xy 9.037413 -301.913348)
			(xy 9.006468 -301.977607) (xy 8.968522 -302.037998) (xy 8.924053 -302.09376) (xy 8.87362 -302.144193)
			(xy 8.817858 -302.188662) (xy 8.757467 -302.226608) (xy 8.693208 -302.257553) (xy 8.625888 -302.28111)
			(xy 8.556353 -302.29698) (xy 8.485479 -302.304966) (xy 8.414157 -302.304966) (xy 8.343283 -302.29698)
			(xy 8.273748 -302.28111) (xy 8.206428 -302.257553) (xy 8.142169 -302.226608) (xy 8.081778 -302.188662)
			(xy 8.026016 -302.144193) (xy 7.975583 -302.09376) (xy 7.931114 -302.037998) (xy 7.893168 -301.977607)
			(xy 7.862223 -301.913348) (xy 7.838666 -301.846028) (xy 7.822796 -301.776493) (xy 7.81481 -301.705619)
			(xy 1.53416 -301.705619) (xy 1.53416 -302.705617) (xy 3.314946 -302.705617) (xy 3.314946 -302.634295)
			(xy 3.322932 -302.563421) (xy 3.338802 -302.493886) (xy 3.362359 -302.426566) (xy 3.393304 -302.362307)
			(xy 3.43125 -302.301916) (xy 3.475719 -302.246154) (xy 3.526152 -302.195721) (xy 3.581914 -302.151252)
			(xy 3.642305 -302.113306) (xy 3.706564 -302.082361) (xy 3.773884 -302.058804) (xy 3.843419 -302.042934)
			(xy 3.914293 -302.034948) (xy 3.985615 -302.034948) (xy 4.056489 -302.042934) (xy 4.126024 -302.058804)
			(xy 4.193344 -302.082361) (xy 4.257603 -302.113306) (xy 4.317994 -302.151252) (xy 4.373756 -302.195721)
			(xy 4.424189 -302.246154) (xy 4.468658 -302.301916) (xy 4.506604 -302.362307) (xy 4.537549 -302.426566)
			(xy 4.561106 -302.493886) (xy 4.576976 -302.563421) (xy 4.584962 -302.634295) (xy 4.585462 -302.669956)
			(xy 4.584962 -302.705617) (xy 4.576976 -302.776491) (xy 4.561106 -302.846026) (xy 4.537549 -302.913346)
			(xy 4.506604 -302.977605) (xy 4.468658 -303.037996) (xy 4.424189 -303.093758) (xy 4.373756 -303.144191)
			(xy 4.317994 -303.18866) (xy 4.257603 -303.226606) (xy 4.193344 -303.257551) (xy 4.126024 -303.281108)
			(xy 4.056489 -303.296978) (xy 3.985615 -303.304964) (xy 3.914293 -303.304964) (xy 3.843419 -303.296978)
			(xy 3.773884 -303.281108) (xy 3.706564 -303.257551) (xy 3.642305 -303.226606) (xy 3.581914 -303.18866)
			(xy 3.526152 -303.144191) (xy 3.475719 -303.093758) (xy 3.43125 -303.037996) (xy 3.393304 -302.977605)
			(xy 3.362359 -302.913346) (xy 3.338802 -302.846026) (xy 3.322932 -302.776491) (xy 3.314946 -302.705617)
			(xy 1.53416 -302.705617) (xy 1.53416 -302.795178) (xy 1.5346 -302.817481) (xy 1.542338 -302.861409)
			(xy 1.557629 -302.903311) (xy 1.580002 -302.941898) (xy 1.608772 -302.975984) (xy 1.643052 -303.004522)
			(xy 1.681789 -303.026635) (xy 1.723793 -303.041642) (xy 1.767773 -303.049083) (xy 1.812376 -303.048729)
			(xy 1.834388 -303.045114) (xy 1.869836 -303.039064) (xy 1.941576 -303.034052) (xy 2.013423 -303.037172)
			(xy 2.084458 -303.048383) (xy 2.153774 -303.067542) (xy 2.220483 -303.094404) (xy 2.283733 -303.128626)
			(xy 2.342715 -303.16977) (xy 2.396674 -303.217311) (xy 2.444921 -303.270639) (xy 2.486839 -303.329073)
			(xy 2.521892 -303.391867) (xy 2.549632 -303.458216) (xy 2.569703 -303.527273) (xy 2.581849 -303.598154)
			(xy 2.585915 -303.669954) (xy 2.583896 -303.705615) (xy 7.81481 -303.705615) (xy 7.81481 -303.634293)
			(xy 7.822796 -303.563419) (xy 7.838666 -303.493884) (xy 7.862223 -303.426564) (xy 7.893168 -303.362305)
			(xy 7.931114 -303.301914) (xy 7.975583 -303.246152) (xy 8.026016 -303.195719) (xy 8.081778 -303.15125)
			(xy 8.142169 -303.113304) (xy 8.206428 -303.082359) (xy 8.273748 -303.058802) (xy 8.343283 -303.042932)
			(xy 8.414157 -303.034946) (xy 8.485479 -303.034946) (xy 8.556353 -303.042932) (xy 8.625888 -303.058802)
			(xy 8.693208 -303.082359) (xy 8.757467 -303.113304) (xy 8.817858 -303.15125) (xy 8.87362 -303.195719)
			(xy 8.924053 -303.246152) (xy 8.968522 -303.301914) (xy 9.006468 -303.362305) (xy 9.037413 -303.426564)
			(xy 9.06097 -303.493884) (xy 9.07684 -303.563419) (xy 9.084826 -303.634293) (xy 9.085326 -303.669954)
			(xy 9.084826 -303.705615) (xy 9.07684 -303.776489) (xy 9.06097 -303.846024) (xy 9.037413 -303.913344)
			(xy 9.006468 -303.977603) (xy 8.968522 -304.037994) (xy 8.924053 -304.093756) (xy 8.87362 -304.144189)
			(xy 8.817858 -304.188658) (xy 8.757467 -304.226604) (xy 8.693208 -304.257549) (xy 8.625888 -304.281106)
			(xy 8.556353 -304.296976) (xy 8.485479 -304.304962) (xy 8.414157 -304.304962) (xy 8.343283 -304.296976)
			(xy 8.273748 -304.281106) (xy 8.206428 -304.257549) (xy 8.142169 -304.226604) (xy 8.081778 -304.188658)
			(xy 8.026016 -304.144189) (xy 7.975583 -304.093756) (xy 7.931114 -304.037994) (xy 7.893168 -303.977603)
			(xy 7.862223 -303.913344) (xy 7.838666 -303.846024) (xy 7.822796 -303.776489) (xy 7.81481 -303.705615)
			(xy 2.583896 -303.705615) (xy 2.581849 -303.741754) (xy 2.569703 -303.812635) (xy 2.549632 -303.881692)
			(xy 2.521892 -303.948041) (xy 2.486839 -304.010835) (xy 2.444921 -304.069269) (xy 2.396674 -304.122597)
			(xy 2.342715 -304.170138) (xy 2.283733 -304.211282) (xy 2.220483 -304.245504) (xy 2.153774 -304.272366)
			(xy 2.084458 -304.291525) (xy 2.013423 -304.302736) (xy 1.941576 -304.305856) (xy 1.869836 -304.300844)
			(xy 1.834388 -304.294794) (xy 1.812378 -304.291197) (xy 1.767784 -304.290866) (xy 1.723817 -304.298323)
			(xy 1.681825 -304.313338) (xy 1.643099 -304.335451) (xy 1.608826 -304.363983) (xy 1.580058 -304.398058)
			(xy 1.557678 -304.436631) (xy 1.542374 -304.478518) (xy 1.534613 -304.522432) (xy 1.53416 -304.54473)
			(xy 1.53416 -304.705613) (xy 3.314946 -304.705613) (xy 3.314946 -304.634291) (xy 3.322932 -304.563417)
			(xy 3.338802 -304.493882) (xy 3.362359 -304.426562) (xy 3.393304 -304.362303) (xy 3.43125 -304.301912)
			(xy 3.475719 -304.24615) (xy 3.526152 -304.195717) (xy 3.581914 -304.151248) (xy 3.642305 -304.113302)
			(xy 3.706564 -304.082357) (xy 3.773884 -304.0588) (xy 3.843419 -304.04293) (xy 3.914293 -304.034944)
			(xy 3.985615 -304.034944) (xy 4.056489 -304.04293) (xy 4.126024 -304.0588) (xy 4.193344 -304.082357)
			(xy 4.257603 -304.113302) (xy 4.317994 -304.151248) (xy 4.373756 -304.195717) (xy 4.424189 -304.24615)
			(xy 4.468658 -304.301912) (xy 4.506604 -304.362303) (xy 4.537549 -304.426562) (xy 4.561106 -304.493882)
			(xy 4.576976 -304.563417) (xy 4.584962 -304.634291) (xy 4.585462 -304.669952) (xy 4.584962 -304.705613)
			(xy 5.814814 -304.705613) (xy 5.814814 -304.634291) (xy 5.8228 -304.563417) (xy 5.83867 -304.493882)
			(xy 5.862227 -304.426562) (xy 5.893172 -304.362303) (xy 5.931118 -304.301912) (xy 5.975587 -304.24615)
			(xy 6.02602 -304.195717) (xy 6.081782 -304.151248) (xy 6.142173 -304.113302) (xy 6.206432 -304.082357)
			(xy 6.273752 -304.0588) (xy 6.343287 -304.04293) (xy 6.414161 -304.034944) (xy 6.485483 -304.034944)
			(xy 6.556357 -304.04293) (xy 6.625892 -304.0588) (xy 6.693212 -304.082357) (xy 6.757471 -304.113302)
			(xy 6.817862 -304.151248) (xy 6.873624 -304.195717) (xy 6.924057 -304.24615) (xy 6.968526 -304.301912)
			(xy 7.006472 -304.362303) (xy 7.037417 -304.426562) (xy 7.060974 -304.493882) (xy 7.076844 -304.563417)
			(xy 7.08483 -304.634291) (xy 7.08533 -304.669952) (xy 7.08483 -304.705613) (xy 7.076844 -304.776487)
			(xy 7.060974 -304.846022) (xy 7.037417 -304.913342) (xy 7.006472 -304.977601) (xy 6.968526 -305.037992)
			(xy 6.924057 -305.093754) (xy 6.873624 -305.144187) (xy 6.817862 -305.188656) (xy 6.757471 -305.226602)
			(xy 6.693212 -305.257547) (xy 6.625892 -305.281104) (xy 6.556357 -305.296974) (xy 6.485483 -305.30496)
			(xy 6.414161 -305.30496) (xy 6.343287 -305.296974) (xy 6.273752 -305.281104) (xy 6.206432 -305.257547)
			(xy 6.142173 -305.226602) (xy 6.081782 -305.188656) (xy 6.02602 -305.144187) (xy 5.975587 -305.093754)
			(xy 5.931118 -305.037992) (xy 5.893172 -304.977601) (xy 5.862227 -304.913342) (xy 5.83867 -304.846022)
			(xy 5.8228 -304.776487) (xy 5.814814 -304.705613) (xy 4.584962 -304.705613) (xy 4.576976 -304.776487)
			(xy 4.561106 -304.846022) (xy 4.537549 -304.913342) (xy 4.506604 -304.977601) (xy 4.468658 -305.037992)
			(xy 4.424189 -305.093754) (xy 4.373756 -305.144187) (xy 4.317994 -305.188656) (xy 4.257603 -305.226602)
			(xy 4.193344 -305.257547) (xy 4.126024 -305.281104) (xy 4.056489 -305.296974) (xy 3.985615 -305.30496)
			(xy 3.914293 -305.30496) (xy 3.843419 -305.296974) (xy 3.773884 -305.281104) (xy 3.706564 -305.257547)
			(xy 3.642305 -305.226602) (xy 3.581914 -305.188656) (xy 3.526152 -305.144187) (xy 3.475719 -305.093754)
			(xy 3.43125 -305.037992) (xy 3.393304 -304.977601) (xy 3.362359 -304.913342) (xy 3.338802 -304.846022)
			(xy 3.322932 -304.776487) (xy 3.314946 -304.705613) (xy 1.53416 -304.705613) (xy 1.53416 -304.795174)
			(xy 1.5346 -304.817477) (xy 1.542337 -304.861406) (xy 1.557627 -304.903308) (xy 1.580001 -304.941896)
			(xy 1.60877 -304.975983) (xy 1.643051 -305.004522) (xy 1.681788 -305.026635) (xy 1.723793 -305.041642)
			(xy 1.767773 -305.049083) (xy 1.812376 -305.048728) (xy 1.834388 -305.04511) (xy 1.869836 -305.03906)
			(xy 1.941576 -305.034048) (xy 2.013423 -305.037167) (xy 2.084459 -305.048378) (xy 2.153774 -305.067537)
			(xy 2.220484 -305.094399) (xy 2.283734 -305.128621) (xy 2.342716 -305.169766) (xy 2.396676 -305.217306)
			(xy 2.444923 -305.270634) (xy 2.486841 -305.329069) (xy 2.521894 -305.391862) (xy 2.549634 -305.458212)
			(xy 2.569705 -305.527269) (xy 2.581851 -305.59815) (xy 2.585917 -305.66995) (xy 2.583898 -305.705611)
			(xy 7.81481 -305.705611) (xy 7.81481 -305.634289) (xy 7.822796 -305.563415) (xy 7.838666 -305.49388)
			(xy 7.862223 -305.42656) (xy 7.893168 -305.362301) (xy 7.931114 -305.30191) (xy 7.975583 -305.246148)
			(xy 8.026016 -305.195715) (xy 8.081778 -305.151246) (xy 8.142169 -305.1133) (xy 8.206428 -305.082355)
			(xy 8.273748 -305.058798) (xy 8.343283 -305.042928) (xy 8.414157 -305.034942) (xy 8.485479 -305.034942)
			(xy 8.556353 -305.042928) (xy 8.625888 -305.058798) (xy 8.693208 -305.082355) (xy 8.757467 -305.1133)
			(xy 8.817858 -305.151246) (xy 8.87362 -305.195715) (xy 8.924053 -305.246148) (xy 8.968522 -305.30191)
			(xy 9.006468 -305.362301) (xy 9.037413 -305.42656) (xy 9.06097 -305.49388) (xy 9.07684 -305.563415)
			(xy 9.084826 -305.634289) (xy 9.085326 -305.66995) (xy 9.084826 -305.705611) (xy 9.07684 -305.776485)
			(xy 9.06097 -305.84602) (xy 9.037413 -305.91334) (xy 9.006468 -305.977599) (xy 8.968522 -306.03799)
			(xy 8.924053 -306.093752) (xy 8.87362 -306.144185) (xy 8.817858 -306.188654) (xy 8.757467 -306.2266)
			(xy 8.693208 -306.257545) (xy 8.625888 -306.281102) (xy 8.556353 -306.296972) (xy 8.485479 -306.304958)
			(xy 8.414157 -306.304958) (xy 8.343283 -306.296972) (xy 8.273748 -306.281102) (xy 8.206428 -306.257545)
			(xy 8.142169 -306.2266) (xy 8.081778 -306.188654) (xy 8.026016 -306.144185) (xy 7.975583 -306.093752)
			(xy 7.931114 -306.03799) (xy 7.893168 -305.977599) (xy 7.862223 -305.91334) (xy 7.838666 -305.84602)
			(xy 7.822796 -305.776485) (xy 7.81481 -305.705611) (xy 2.583898 -305.705611) (xy 2.581851 -305.74175)
			(xy 2.569705 -305.812631) (xy 2.549634 -305.881688) (xy 2.521894 -305.948038) (xy 2.486841 -306.010831)
			(xy 2.444923 -306.069266) (xy 2.396676 -306.122594) (xy 2.342716 -306.170134) (xy 2.283734 -306.211279)
			(xy 2.220484 -306.245501) (xy 2.153774 -306.272363) (xy 2.084459 -306.291522) (xy 2.013423 -306.302733)
			(xy 1.941576 -306.305852) (xy 1.869836 -306.30084) (xy 1.834388 -306.29479) (xy 1.812377 -306.291193)
			(xy 1.767783 -306.290863) (xy 1.723816 -306.298319) (xy 1.681825 -306.313334) (xy 1.643098 -306.335447)
			(xy 1.608825 -306.363979) (xy 1.580056 -306.398054) (xy 1.557676 -306.436627) (xy 1.542371 -306.478513)
			(xy 1.53461 -306.522428) (xy 1.53416 -306.544726) (xy 1.53416 -306.705609) (xy 5.814814 -306.705609)
			(xy 5.814814 -306.634287) (xy 5.8228 -306.563413) (xy 5.83867 -306.493878) (xy 5.862227 -306.426558)
			(xy 5.893172 -306.362299) (xy 5.931118 -306.301908) (xy 5.975587 -306.246146) (xy 6.02602 -306.195713)
			(xy 6.081782 -306.151244) (xy 6.142173 -306.113298) (xy 6.206432 -306.082353) (xy 6.273752 -306.058796)
			(xy 6.343287 -306.042926) (xy 6.414161 -306.03494) (xy 6.485483 -306.03494) (xy 6.556357 -306.042926)
			(xy 6.625892 -306.058796) (xy 6.693212 -306.082353) (xy 6.757471 -306.113298) (xy 6.817862 -306.151244)
			(xy 6.873624 -306.195713) (xy 6.924057 -306.246146) (xy 6.968526 -306.301908) (xy 7.006472 -306.362299)
			(xy 7.037417 -306.426558) (xy 7.060974 -306.493878) (xy 7.076844 -306.563413) (xy 7.08483 -306.634287)
			(xy 7.08533 -306.669948) (xy 7.08483 -306.705609) (xy 7.076844 -306.776483) (xy 7.060974 -306.846018)
			(xy 7.037417 -306.913338) (xy 7.006472 -306.977597) (xy 6.968526 -307.037988) (xy 6.924057 -307.09375)
			(xy 6.873624 -307.144183) (xy 6.817862 -307.188652) (xy 6.757471 -307.226598) (xy 6.693212 -307.257543)
			(xy 6.625892 -307.2811) (xy 6.556357 -307.29697) (xy 6.485483 -307.304956) (xy 6.414161 -307.304956)
			(xy 6.343287 -307.29697) (xy 6.273752 -307.2811) (xy 6.206432 -307.257543) (xy 6.142173 -307.226598)
			(xy 6.081782 -307.188652) (xy 6.02602 -307.144183) (xy 5.975587 -307.09375) (xy 5.931118 -307.037988)
			(xy 5.893172 -306.977597) (xy 5.862227 -306.913338) (xy 5.83867 -306.846018) (xy 5.8228 -306.776483)
			(xy 5.814814 -306.705609) (xy 1.53416 -306.705609) (xy 1.53416 -306.79517) (xy 1.5346 -306.817473)
			(xy 1.542338 -306.861401) (xy 1.557629 -306.903302) (xy 1.580003 -306.941889) (xy 1.608772 -306.975975)
			(xy 1.643052 -307.004513) (xy 1.68179 -307.026625) (xy 1.723794 -307.041632) (xy 1.767773 -307.049073)
			(xy 1.812376 -307.048719) (xy 1.834388 -307.045106) (xy 1.869836 -307.039056) (xy 1.941576 -307.034044)
			(xy 2.013423 -307.037164) (xy 2.084458 -307.048375) (xy 2.153774 -307.067534) (xy 2.220483 -307.094396)
			(xy 2.283733 -307.128618) (xy 2.342715 -307.169762) (xy 2.396674 -307.217303) (xy 2.444921 -307.270631)
			(xy 2.486839 -307.329065) (xy 2.521892 -307.391859) (xy 2.549632 -307.458208) (xy 2.569703 -307.527265)
			(xy 2.581849 -307.598146) (xy 2.585915 -307.669946) (xy 2.581849 -307.741746) (xy 2.569703 -307.812627)
			(xy 2.549632 -307.881684) (xy 2.521892 -307.948033) (xy 2.486839 -308.010827) (xy 2.444921 -308.069261)
			(xy 2.396674 -308.122589) (xy 2.342715 -308.17013) (xy 2.283733 -308.211274) (xy 2.220483 -308.245496)
			(xy 2.153774 -308.272358) (xy 2.084458 -308.291517) (xy 2.013423 -308.302728) (xy 1.941576 -308.305848)
			(xy 1.869836 -308.300836) (xy 1.834388 -308.294786) (xy 1.812377 -308.291189) (xy 1.767783 -308.290859)
			(xy 1.723816 -308.298315) (xy 1.681824 -308.31333) (xy 1.643097 -308.335443) (xy 1.608823 -308.363975)
			(xy 1.580054 -308.39805) (xy 1.557674 -308.436623) (xy 1.542368 -308.478509) (xy 1.534606 -308.522424)
			(xy 1.53416 -308.544722) (xy 1.53416 -308.705605) (xy 3.314946 -308.705605) (xy 3.314946 -308.634283)
			(xy 3.322932 -308.563409) (xy 3.338802 -308.493874) (xy 3.362359 -308.426554) (xy 3.393304 -308.362295)
			(xy 3.43125 -308.301904) (xy 3.475719 -308.246142) (xy 3.526152 -308.195709) (xy 3.581914 -308.15124)
			(xy 3.642305 -308.113294) (xy 3.706564 -308.082349) (xy 3.773884 -308.058792) (xy 3.843419 -308.042922)
			(xy 3.914293 -308.034936) (xy 3.985615 -308.034936) (xy 4.056489 -308.042922) (xy 4.126024 -308.058792)
			(xy 4.193344 -308.082349) (xy 4.257603 -308.113294) (xy 4.317994 -308.15124) (xy 4.373756 -308.195709)
			(xy 4.424189 -308.246142) (xy 4.468658 -308.301904) (xy 4.506604 -308.362295) (xy 4.537549 -308.426554)
			(xy 4.561106 -308.493874) (xy 4.576976 -308.563409) (xy 4.584962 -308.634283) (xy 4.585462 -308.669944)
			(xy 4.584962 -308.705605) (xy 5.814814 -308.705605) (xy 5.814814 -308.634283) (xy 5.8228 -308.563409)
			(xy 5.83867 -308.493874) (xy 5.862227 -308.426554) (xy 5.893172 -308.362295) (xy 5.931118 -308.301904)
			(xy 5.975587 -308.246142) (xy 6.02602 -308.195709) (xy 6.081782 -308.15124) (xy 6.142173 -308.113294)
			(xy 6.206432 -308.082349) (xy 6.273752 -308.058792) (xy 6.343287 -308.042922) (xy 6.414161 -308.034936)
			(xy 6.485483 -308.034936) (xy 6.556357 -308.042922) (xy 6.625892 -308.058792) (xy 6.693212 -308.082349)
			(xy 6.757471 -308.113294) (xy 6.817862 -308.15124) (xy 6.873624 -308.195709) (xy 6.924057 -308.246142)
			(xy 6.968526 -308.301904) (xy 7.006472 -308.362295) (xy 7.037417 -308.426554) (xy 7.060974 -308.493874)
			(xy 7.076844 -308.563409) (xy 7.08483 -308.634283) (xy 7.08533 -308.669944) (xy 7.08483 -308.705605)
			(xy 7.076844 -308.776479) (xy 7.060974 -308.846014) (xy 7.037417 -308.913334) (xy 7.006472 -308.977593)
			(xy 6.968526 -309.037984) (xy 6.924057 -309.093746) (xy 6.873624 -309.144179) (xy 6.817862 -309.188648)
			(xy 6.757471 -309.226594) (xy 6.693212 -309.257539) (xy 6.625892 -309.281096) (xy 6.556357 -309.296966)
			(xy 6.485483 -309.304952) (xy 6.414161 -309.304952) (xy 6.343287 -309.296966) (xy 6.273752 -309.281096)
			(xy 6.206432 -309.257539) (xy 6.142173 -309.226594) (xy 6.081782 -309.188648) (xy 6.02602 -309.144179)
			(xy 5.975587 -309.093746) (xy 5.931118 -309.037984) (xy 5.893172 -308.977593) (xy 5.862227 -308.913334)
			(xy 5.83867 -308.846014) (xy 5.8228 -308.776479) (xy 5.814814 -308.705605) (xy 4.584962 -308.705605)
			(xy 4.576976 -308.776479) (xy 4.561106 -308.846014) (xy 4.537549 -308.913334) (xy 4.506604 -308.977593)
			(xy 4.468658 -309.037984) (xy 4.424189 -309.093746) (xy 4.373756 -309.144179) (xy 4.317994 -309.188648)
			(xy 4.257603 -309.226594) (xy 4.193344 -309.257539) (xy 4.126024 -309.281096) (xy 4.056489 -309.296966)
			(xy 3.985615 -309.304952) (xy 3.914293 -309.304952) (xy 3.843419 -309.296966) (xy 3.773884 -309.281096)
			(xy 3.706564 -309.257539) (xy 3.642305 -309.226594) (xy 3.581914 -309.188648) (xy 3.526152 -309.144179)
			(xy 3.475719 -309.093746) (xy 3.43125 -309.037984) (xy 3.393304 -308.977593) (xy 3.362359 -308.913334)
			(xy 3.338802 -308.846014) (xy 3.322932 -308.776479) (xy 3.314946 -308.705605) (xy 1.53416 -308.705605)
			(xy 1.53416 -308.795166) (xy 1.5346 -308.817469) (xy 1.542337 -308.861397) (xy 1.557628 -308.903299)
			(xy 1.580002 -308.941887) (xy 1.608771 -308.975974) (xy 1.643051 -309.004512) (xy 1.681789 -309.026625)
			(xy 1.723793 -309.041632) (xy 1.767773 -309.049073) (xy 1.812376 -309.048718) (xy 1.834388 -309.045102)
			(xy 1.869836 -309.039052) (xy 1.941576 -309.03404) (xy 2.013423 -309.037159) (xy 2.084458 -309.04837)
			(xy 2.153773 -309.067529) (xy 2.220483 -309.094391) (xy 2.283733 -309.128613) (xy 2.342715 -309.169757)
			(xy 2.396674 -309.217297) (xy 2.444921 -309.270625) (xy 2.48684 -309.329059) (xy 2.521892 -309.391853)
			(xy 2.549632 -309.458202) (xy 2.569703 -309.527259) (xy 2.581849 -309.59814) (xy 2.585915 -309.66994)
			(xy 2.583895 -309.705603) (xy 7.81481 -309.705603) (xy 7.81481 -309.634281) (xy 7.822796 -309.563407)
			(xy 7.838666 -309.493872) (xy 7.862223 -309.426552) (xy 7.893168 -309.362293) (xy 7.931114 -309.301902)
			(xy 7.975583 -309.24614) (xy 8.026016 -309.195707) (xy 8.081778 -309.151238) (xy 8.142169 -309.113292)
			(xy 8.206428 -309.082347) (xy 8.273748 -309.05879) (xy 8.343283 -309.04292) (xy 8.414157 -309.034934)
			(xy 8.485479 -309.034934) (xy 8.556353 -309.04292) (xy 8.625888 -309.05879) (xy 8.693208 -309.082347)
			(xy 8.757467 -309.113292) (xy 8.817858 -309.151238) (xy 8.87362 -309.195707) (xy 8.924053 -309.24614)
			(xy 8.968522 -309.301902) (xy 9.006468 -309.362293) (xy 9.037413 -309.426552) (xy 9.06097 -309.493872)
			(xy 9.07684 -309.563407) (xy 9.084826 -309.634281) (xy 9.085326 -309.669942) (xy 9.084826 -309.705603)
			(xy 9.07684 -309.776477) (xy 9.06097 -309.846012) (xy 9.037413 -309.913332) (xy 9.006468 -309.977591)
			(xy 8.968522 -310.037982) (xy 8.924053 -310.093744) (xy 8.87362 -310.144177) (xy 8.817858 -310.188646)
			(xy 8.757467 -310.226592) (xy 8.693208 -310.257537) (xy 8.625888 -310.281094) (xy 8.556353 -310.296964)
			(xy 8.485479 -310.30495) (xy 8.414157 -310.30495) (xy 8.343283 -310.296964) (xy 8.273748 -310.281094)
			(xy 8.206428 -310.257537) (xy 8.142169 -310.226592) (xy 8.081778 -310.188646) (xy 8.026016 -310.144177)
			(xy 7.975583 -310.093744) (xy 7.931114 -310.037982) (xy 7.893168 -309.977591) (xy 7.862223 -309.913332)
			(xy 7.838666 -309.846012) (xy 7.822796 -309.776477) (xy 7.81481 -309.705603) (xy 2.583895 -309.705603)
			(xy 2.581849 -309.741739) (xy 2.569703 -309.81262) (xy 2.549632 -309.881677) (xy 2.521893 -309.948027)
			(xy 2.48684 -310.01082) (xy 2.444922 -310.069254) (xy 2.396675 -310.122583) (xy 2.342715 -310.170123)
			(xy 2.283733 -310.211267) (xy 2.220483 -310.245489) (xy 2.153774 -310.272351) (xy 2.084459 -310.29151)
			(xy 2.013423 -310.302721) (xy 1.941577 -310.30584) (xy 1.869837 -310.300828) (xy 1.834388 -310.294782)
			(xy 1.812377 -310.291185) (xy 1.767783 -310.290855) (xy 1.723815 -310.298311) (xy 1.681823 -310.313326)
			(xy 1.643096 -310.335439) (xy 1.608822 -310.363971) (xy 1.580052 -310.398046) (xy 1.557671 -310.436618)
			(xy 1.542365 -310.478505) (xy 1.534603 -310.52242) (xy 1.53416 -310.544718) (xy 1.53416 -310.705601)
			(xy 3.314946 -310.705601) (xy 3.314946 -310.634279) (xy 3.322932 -310.563405) (xy 3.338802 -310.49387)
			(xy 3.362359 -310.42655) (xy 3.393304 -310.362291) (xy 3.43125 -310.3019) (xy 3.475719 -310.246138)
			(xy 3.526152 -310.195705) (xy 3.581914 -310.151236) (xy 3.642305 -310.11329) (xy 3.706564 -310.082345)
			(xy 3.773884 -310.058788) (xy 3.843419 -310.042918) (xy 3.914293 -310.034932) (xy 3.985615 -310.034932)
			(xy 4.056489 -310.042918) (xy 4.126024 -310.058788) (xy 4.193344 -310.082345) (xy 4.257603 -310.11329)
			(xy 4.317994 -310.151236) (xy 4.373756 -310.195705) (xy 4.424189 -310.246138) (xy 4.468658 -310.3019)
			(xy 4.506604 -310.362291) (xy 4.537549 -310.42655) (xy 4.561106 -310.49387) (xy 4.576976 -310.563405)
			(xy 4.584962 -310.634279) (xy 4.585462 -310.66994) (xy 4.584962 -310.705601) (xy 5.814814 -310.705601)
			(xy 5.814814 -310.634279) (xy 5.8228 -310.563405) (xy 5.83867 -310.49387) (xy 5.862227 -310.42655)
			(xy 5.893172 -310.362291) (xy 5.931118 -310.3019) (xy 5.975587 -310.246138) (xy 6.02602 -310.195705)
			(xy 6.081782 -310.151236) (xy 6.142173 -310.11329) (xy 6.206432 -310.082345) (xy 6.273752 -310.058788)
			(xy 6.343287 -310.042918) (xy 6.414161 -310.034932) (xy 6.485483 -310.034932) (xy 6.556357 -310.042918)
			(xy 6.625892 -310.058788) (xy 6.693212 -310.082345) (xy 6.757471 -310.11329) (xy 6.817862 -310.151236)
			(xy 6.873624 -310.195705) (xy 6.924057 -310.246138) (xy 6.968526 -310.3019) (xy 7.006472 -310.362291)
			(xy 7.037417 -310.42655) (xy 7.060974 -310.49387) (xy 7.076844 -310.563405) (xy 7.08483 -310.634279)
			(xy 7.08533 -310.66994) (xy 7.08483 -310.705601) (xy 7.076844 -310.776475) (xy 7.060974 -310.84601)
			(xy 7.037417 -310.91333) (xy 7.006472 -310.977589) (xy 6.968526 -311.03798) (xy 6.924057 -311.093742)
			(xy 6.873624 -311.144175) (xy 6.817862 -311.188644) (xy 6.757471 -311.22659) (xy 6.693212 -311.257535)
			(xy 6.625892 -311.281092) (xy 6.556357 -311.296962) (xy 6.485483 -311.304948) (xy 6.414161 -311.304948)
			(xy 6.343287 -311.296962) (xy 6.273752 -311.281092) (xy 6.206432 -311.257535) (xy 6.142173 -311.22659)
			(xy 6.081782 -311.188644) (xy 6.02602 -311.144175) (xy 5.975587 -311.093742) (xy 5.931118 -311.03798)
			(xy 5.893172 -310.977589) (xy 5.862227 -310.91333) (xy 5.83867 -310.84601) (xy 5.8228 -310.776475)
			(xy 5.814814 -310.705601) (xy 4.584962 -310.705601) (xy 4.576976 -310.776475) (xy 4.561106 -310.84601)
			(xy 4.537549 -310.91333) (xy 4.506604 -310.977589) (xy 4.468658 -311.03798) (xy 4.424189 -311.093742)
			(xy 4.373756 -311.144175) (xy 4.317994 -311.188644) (xy 4.257603 -311.22659) (xy 4.193344 -311.257535)
			(xy 4.126024 -311.281092) (xy 4.056489 -311.296962) (xy 3.985615 -311.304948) (xy 3.914293 -311.304948)
			(xy 3.843419 -311.296962) (xy 3.773884 -311.281092) (xy 3.706564 -311.257535) (xy 3.642305 -311.22659)
			(xy 3.581914 -311.188644) (xy 3.526152 -311.144175) (xy 3.475719 -311.093742) (xy 3.43125 -311.03798)
			(xy 3.393304 -310.977589) (xy 3.362359 -310.91333) (xy 3.338802 -310.84601) (xy 3.322932 -310.776475)
			(xy 3.314946 -310.705601) (xy 1.53416 -310.705601) (xy 1.53416 -311.705599) (xy 7.81481 -311.705599)
			(xy 7.81481 -311.634277) (xy 7.822796 -311.563403) (xy 7.838666 -311.493868) (xy 7.862223 -311.426548)
			(xy 7.893168 -311.362289) (xy 7.931114 -311.301898) (xy 7.975583 -311.246136) (xy 8.026016 -311.195703)
			(xy 8.081778 -311.151234) (xy 8.142169 -311.113288) (xy 8.206428 -311.082343) (xy 8.273748 -311.058786)
			(xy 8.343283 -311.042916) (xy 8.414157 -311.03493) (xy 8.485479 -311.03493) (xy 8.556353 -311.042916)
			(xy 8.625888 -311.058786) (xy 8.693208 -311.082343) (xy 8.757467 -311.113288) (xy 8.817858 -311.151234)
			(xy 8.87362 -311.195703) (xy 8.924053 -311.246136) (xy 8.968522 -311.301898) (xy 9.006468 -311.362289)
			(xy 9.037413 -311.426548) (xy 9.06097 -311.493868) (xy 9.07684 -311.563403) (xy 9.084826 -311.634277)
			(xy 9.085326 -311.669938) (xy 9.084826 -311.705599) (xy 9.07684 -311.776473) (xy 9.06097 -311.846008)
			(xy 9.037413 -311.913328) (xy 9.006468 -311.977587) (xy 8.968522 -312.037978) (xy 8.924053 -312.09374)
			(xy 8.87362 -312.144173) (xy 8.817858 -312.188642) (xy 8.757467 -312.226588) (xy 8.693208 -312.257533)
			(xy 8.625888 -312.28109) (xy 8.556353 -312.29696) (xy 8.485479 -312.304946) (xy 8.414157 -312.304946)
			(xy 8.343283 -312.29696) (xy 8.273748 -312.28109) (xy 8.206428 -312.257533) (xy 8.142169 -312.226588)
			(xy 8.081778 -312.188642) (xy 8.026016 -312.144173) (xy 7.975583 -312.09374) (xy 7.931114 -312.037978)
			(xy 7.893168 -311.977587) (xy 7.862223 -311.913328) (xy 7.838666 -311.846008) (xy 7.822796 -311.776473)
			(xy 7.81481 -311.705599) (xy 1.53416 -311.705599) (xy 1.53416 -312.705597) (xy 3.314946 -312.705597)
			(xy 3.314946 -312.634275) (xy 3.322932 -312.563401) (xy 3.338802 -312.493866) (xy 3.362359 -312.426546)
			(xy 3.393304 -312.362287) (xy 3.43125 -312.301896) (xy 3.475719 -312.246134) (xy 3.526152 -312.195701)
			(xy 3.581914 -312.151232) (xy 3.642305 -312.113286) (xy 3.706564 -312.082341) (xy 3.773884 -312.058784)
			(xy 3.843419 -312.042914) (xy 3.914293 -312.034928) (xy 3.985615 -312.034928) (xy 4.056489 -312.042914)
			(xy 4.126024 -312.058784) (xy 4.193344 -312.082341) (xy 4.257603 -312.113286) (xy 4.317994 -312.151232)
			(xy 4.373756 -312.195701) (xy 4.424189 -312.246134) (xy 4.468658 -312.301896) (xy 4.506604 -312.362287)
			(xy 4.537549 -312.426546) (xy 4.561106 -312.493866) (xy 4.576976 -312.563401) (xy 4.584962 -312.634275)
			(xy 4.585462 -312.669936) (xy 4.584962 -312.705597) (xy 4.576976 -312.776471) (xy 4.561106 -312.846006)
			(xy 4.537549 -312.913326) (xy 4.506604 -312.977585) (xy 4.468658 -313.037976) (xy 4.424189 -313.093738)
			(xy 4.373756 -313.144171) (xy 4.317994 -313.18864) (xy 4.257603 -313.226586) (xy 4.193344 -313.257531)
			(xy 4.126024 -313.281088) (xy 4.056489 -313.296958) (xy 3.985615 -313.304944) (xy 3.914293 -313.304944)
			(xy 3.843419 -313.296958) (xy 3.773884 -313.281088) (xy 3.706564 -313.257531) (xy 3.642305 -313.226586)
			(xy 3.581914 -313.18864) (xy 3.526152 -313.144171) (xy 3.475719 -313.093738) (xy 3.43125 -313.037976)
			(xy 3.393304 -312.977585) (xy 3.362359 -312.913326) (xy 3.338802 -312.846006) (xy 3.322932 -312.776471)
			(xy 3.314946 -312.705597) (xy 1.53416 -312.705597) (xy 1.53416 -312.795158) (xy 1.5346 -312.817461)
			(xy 1.542338 -312.861389) (xy 1.557629 -312.903291) (xy 1.580002 -312.941878) (xy 1.608772 -312.975964)
			(xy 1.643052 -313.004502) (xy 1.681789 -313.026615) (xy 1.723793 -313.041622) (xy 1.767773 -313.049063)
			(xy 1.812376 -313.048709) (xy 1.834388 -313.045094) (xy 1.869836 -313.039044) (xy 1.941576 -313.034032)
			(xy 2.013423 -313.037152) (xy 2.084458 -313.048363) (xy 2.153774 -313.067522) (xy 2.220483 -313.094384)
			(xy 2.283733 -313.128606) (xy 2.342715 -313.16975) (xy 2.396674 -313.217291) (xy 2.444921 -313.270619)
			(xy 2.486839 -313.329053) (xy 2.521892 -313.391847) (xy 2.549632 -313.458196) (xy 2.569703 -313.527253)
			(xy 2.581849 -313.598134) (xy 2.585915 -313.669934) (xy 2.583896 -313.705595) (xy 7.81481 -313.705595)
			(xy 7.81481 -313.634273) (xy 7.822796 -313.563399) (xy 7.838666 -313.493864) (xy 7.862223 -313.426544)
			(xy 7.893168 -313.362285) (xy 7.931114 -313.301894) (xy 7.975583 -313.246132) (xy 8.026016 -313.195699)
			(xy 8.081778 -313.15123) (xy 8.142169 -313.113284) (xy 8.206428 -313.082339) (xy 8.273748 -313.058782)
			(xy 8.343283 -313.042912) (xy 8.414157 -313.034926) (xy 8.485479 -313.034926) (xy 8.556353 -313.042912)
			(xy 8.625888 -313.058782) (xy 8.693208 -313.082339) (xy 8.757467 -313.113284) (xy 8.817858 -313.15123)
			(xy 8.87362 -313.195699) (xy 8.924053 -313.246132) (xy 8.968522 -313.301894) (xy 9.006468 -313.362285)
			(xy 9.037413 -313.426544) (xy 9.06097 -313.493864) (xy 9.07684 -313.563399) (xy 9.084826 -313.634273)
			(xy 9.085326 -313.669934) (xy 9.084826 -313.705595) (xy 9.07684 -313.776469) (xy 9.06097 -313.846004)
			(xy 9.037413 -313.913324) (xy 9.006468 -313.977583) (xy 8.968522 -314.037974) (xy 8.924053 -314.093736)
			(xy 8.87362 -314.144169) (xy 8.817858 -314.188638) (xy 8.757467 -314.226584) (xy 8.693208 -314.257529)
			(xy 8.625888 -314.281086) (xy 8.556353 -314.296956) (xy 8.485479 -314.304942) (xy 8.414157 -314.304942)
			(xy 8.343283 -314.296956) (xy 8.273748 -314.281086) (xy 8.206428 -314.257529) (xy 8.142169 -314.226584)
			(xy 8.081778 -314.188638) (xy 8.026016 -314.144169) (xy 7.975583 -314.093736) (xy 7.931114 -314.037974)
			(xy 7.893168 -313.977583) (xy 7.862223 -313.913324) (xy 7.838666 -313.846004) (xy 7.822796 -313.776469)
			(xy 7.81481 -313.705595) (xy 2.583896 -313.705595) (xy 2.581849 -313.741734) (xy 2.569703 -313.812615)
			(xy 2.549632 -313.881672) (xy 2.521892 -313.948021) (xy 2.486839 -314.010815) (xy 2.444921 -314.069249)
			(xy 2.396674 -314.122577) (xy 2.342715 -314.170118) (xy 2.283733 -314.211262) (xy 2.220483 -314.245484)
			(xy 2.153774 -314.272346) (xy 2.084458 -314.291505) (xy 2.013423 -314.302716) (xy 1.941576 -314.305836)
			(xy 1.869836 -314.300824) (xy 1.834388 -314.294774) (xy 1.812377 -314.291177) (xy 1.767782 -314.290847)
			(xy 1.723814 -314.298303) (xy 1.681821 -314.313318) (xy 1.643094 -314.335431) (xy 1.608819 -314.363962)
			(xy 1.580049 -314.398037) (xy 1.557666 -314.43661) (xy 1.542359 -314.478497) (xy 1.534596 -314.522412)
			(xy 1.53416 -314.54471) (xy 1.53416 -314.705593) (xy 3.314946 -314.705593) (xy 3.314946 -314.634271)
			(xy 3.322932 -314.563397) (xy 3.338802 -314.493862) (xy 3.362359 -314.426542) (xy 3.393304 -314.362283)
			(xy 3.43125 -314.301892) (xy 3.475719 -314.24613) (xy 3.526152 -314.195697) (xy 3.581914 -314.151228)
			(xy 3.642305 -314.113282) (xy 3.706564 -314.082337) (xy 3.773884 -314.05878) (xy 3.843419 -314.04291)
			(xy 3.914293 -314.034924) (xy 3.985615 -314.034924) (xy 4.056489 -314.04291) (xy 4.126024 -314.05878)
			(xy 4.193344 -314.082337) (xy 4.257603 -314.113282) (xy 4.317994 -314.151228) (xy 4.373756 -314.195697)
			(xy 4.424189 -314.24613) (xy 4.468658 -314.301892) (xy 4.506604 -314.362283) (xy 4.537549 -314.426542)
			(xy 4.561106 -314.493862) (xy 4.576976 -314.563397) (xy 4.584962 -314.634271) (xy 4.585462 -314.669932)
			(xy 4.584962 -314.705593) (xy 5.814814 -314.705593) (xy 5.814814 -314.634271) (xy 5.8228 -314.563397)
			(xy 5.83867 -314.493862) (xy 5.862227 -314.426542) (xy 5.893172 -314.362283) (xy 5.931118 -314.301892)
			(xy 5.975587 -314.24613) (xy 6.02602 -314.195697) (xy 6.081782 -314.151228) (xy 6.142173 -314.113282)
			(xy 6.206432 -314.082337) (xy 6.273752 -314.05878) (xy 6.343287 -314.04291) (xy 6.414161 -314.034924)
			(xy 6.485483 -314.034924) (xy 6.556357 -314.04291) (xy 6.625892 -314.05878) (xy 6.693212 -314.082337)
			(xy 6.757471 -314.113282) (xy 6.817862 -314.151228) (xy 6.873624 -314.195697) (xy 6.924057 -314.24613)
			(xy 6.968526 -314.301892) (xy 7.006472 -314.362283) (xy 7.037417 -314.426542) (xy 7.060974 -314.493862)
			(xy 7.076844 -314.563397) (xy 7.08483 -314.634271) (xy 7.08533 -314.669932) (xy 7.08483 -314.705593)
			(xy 7.082495 -314.726316) (xy 12.100796 -314.726316) (xy 12.100796 -314.66638) (xy 12.108619 -314.606958)
			(xy 12.124132 -314.549065) (xy 12.147068 -314.493692) (xy 12.177035 -314.441786) (xy 12.213522 -314.394236)
			(xy 12.255902 -314.351856) (xy 12.303452 -314.315369) (xy 12.355358 -314.285402) (xy 12.410731 -314.262466)
			(xy 12.468624 -314.246953) (xy 12.528046 -314.23913) (xy 12.587982 -314.23913) (xy 12.647404 -314.246953)
			(xy 12.705297 -314.262466) (xy 12.76067 -314.285402) (xy 12.812576 -314.315369) (xy 12.860126 -314.351856)
			(xy 12.902506 -314.394236) (xy 12.938993 -314.441786) (xy 12.96896 -314.493692) (xy 12.991896 -314.549065)
			(xy 13.007409 -314.606958) (xy 13.015232 -314.66638) (xy 13.015722 -314.696348) (xy 13.015232 -314.726316)
			(xy 13.007409 -314.785738) (xy 12.991896 -314.843631) (xy 12.96896 -314.899004) (xy 12.938993 -314.95091)
			(xy 12.902506 -314.99846) (xy 12.860126 -315.04084) (xy 12.812576 -315.077327) (xy 12.76067 -315.107294)
			(xy 12.705297 -315.13023) (xy 12.647404 -315.145743) (xy 12.587982 -315.153566) (xy 12.528046 -315.153566)
			(xy 12.468624 -315.145743) (xy 12.410731 -315.13023) (xy 12.355358 -315.107294) (xy 12.303452 -315.077327)
			(xy 12.255902 -315.04084) (xy 12.213522 -314.99846) (xy 12.177035 -314.95091) (xy 12.147068 -314.899004)
			(xy 12.124132 -314.843631) (xy 12.108619 -314.785738) (xy 12.100796 -314.726316) (xy 7.082495 -314.726316)
			(xy 7.076844 -314.776467) (xy 7.060974 -314.846002) (xy 7.037417 -314.913322) (xy 7.006472 -314.977581)
			(xy 6.968526 -315.037972) (xy 6.924057 -315.093734) (xy 6.873624 -315.144167) (xy 6.817862 -315.188636)
			(xy 6.757471 -315.226582) (xy 6.693212 -315.257527) (xy 6.625892 -315.281084) (xy 6.556357 -315.296954)
			(xy 6.485483 -315.30494) (xy 6.414161 -315.30494) (xy 6.343287 -315.296954) (xy 6.273752 -315.281084)
			(xy 6.206432 -315.257527) (xy 6.142173 -315.226582) (xy 6.081782 -315.188636) (xy 6.02602 -315.144167)
			(xy 5.975587 -315.093734) (xy 5.931118 -315.037972) (xy 5.893172 -314.977581) (xy 5.862227 -314.913322)
			(xy 5.83867 -314.846002) (xy 5.8228 -314.776467) (xy 5.814814 -314.705593) (xy 4.584962 -314.705593)
			(xy 4.576976 -314.776467) (xy 4.561106 -314.846002) (xy 4.537549 -314.913322) (xy 4.506604 -314.977581)
			(xy 4.468658 -315.037972) (xy 4.424189 -315.093734) (xy 4.373756 -315.144167) (xy 4.317994 -315.188636)
			(xy 4.257603 -315.226582) (xy 4.193344 -315.257527) (xy 4.126024 -315.281084) (xy 4.056489 -315.296954)
			(xy 3.985615 -315.30494) (xy 3.914293 -315.30494) (xy 3.843419 -315.296954) (xy 3.773884 -315.281084)
			(xy 3.706564 -315.257527) (xy 3.642305 -315.226582) (xy 3.581914 -315.188636) (xy 3.526152 -315.144167)
			(xy 3.475719 -315.093734) (xy 3.43125 -315.037972) (xy 3.393304 -314.977581) (xy 3.362359 -314.913322)
			(xy 3.338802 -314.846002) (xy 3.322932 -314.776467) (xy 3.314946 -314.705593) (xy 1.53416 -314.705593)
			(xy 1.53416 -314.795154) (xy 1.5346 -314.817457) (xy 1.542337 -314.861386) (xy 1.557627 -314.903288)
			(xy 1.580001 -314.941876) (xy 1.60877 -314.975963) (xy 1.643051 -315.004502) (xy 1.681788 -315.026615)
			(xy 1.723793 -315.041622) (xy 1.767773 -315.049063) (xy 1.812376 -315.048708) (xy 1.834388 -315.04509)
			(xy 1.869836 -315.03904) (xy 1.941576 -315.034028) (xy 2.013423 -315.037147) (xy 2.084459 -315.048358)
			(xy 2.153774 -315.067517) (xy 2.220484 -315.094379) (xy 2.283734 -315.128601) (xy 2.342716 -315.169746)
			(xy 2.396676 -315.217286) (xy 2.444923 -315.270614) (xy 2.486841 -315.329049) (xy 2.521894 -315.391842)
			(xy 2.549634 -315.458192) (xy 2.569705 -315.527249) (xy 2.581851 -315.59813) (xy 2.585917 -315.66993)
			(xy 2.583898 -315.705591) (xy 7.81481 -315.705591) (xy 7.81481 -315.634269) (xy 7.822796 -315.563395)
			(xy 7.838666 -315.49386) (xy 7.862223 -315.42654) (xy 7.893168 -315.362281) (xy 7.931114 -315.30189)
			(xy 7.975583 -315.246128) (xy 8.026016 -315.195695) (xy 8.081778 -315.151226) (xy 8.142169 -315.11328)
			(xy 8.206428 -315.082335) (xy 8.273748 -315.058778) (xy 8.343283 -315.042908) (xy 8.414157 -315.034922)
			(xy 8.485479 -315.034922) (xy 8.556353 -315.042908) (xy 8.625888 -315.058778) (xy 8.693208 -315.082335)
			(xy 8.757467 -315.11328) (xy 8.817858 -315.151226) (xy 8.87362 -315.195695) (xy 8.924053 -315.246128)
			(xy 8.968522 -315.30189) (xy 9.006468 -315.362281) (xy 9.037413 -315.42654) (xy 9.06097 -315.49386)
			(xy 9.07684 -315.563395) (xy 9.084826 -315.634269) (xy 9.085326 -315.66993) (xy 9.084826 -315.705591)
			(xy 9.07684 -315.776465) (xy 9.06097 -315.846) (xy 9.037413 -315.91332) (xy 9.006468 -315.977579)
			(xy 8.968522 -316.03797) (xy 8.924053 -316.093732) (xy 8.87362 -316.144165) (xy 8.817858 -316.188634)
			(xy 8.757467 -316.22658) (xy 8.693208 -316.257525) (xy 8.625888 -316.281082) (xy 8.556353 -316.296952)
			(xy 8.485479 -316.304938) (xy 8.414157 -316.304938) (xy 8.343283 -316.296952) (xy 8.273748 -316.281082)
			(xy 8.206428 -316.257525) (xy 8.142169 -316.22658) (xy 8.081778 -316.188634) (xy 8.026016 -316.144165)
			(xy 7.975583 -316.093732) (xy 7.931114 -316.03797) (xy 7.893168 -315.977579) (xy 7.862223 -315.91332)
			(xy 7.838666 -315.846) (xy 7.822796 -315.776465) (xy 7.81481 -315.705591) (xy 2.583898 -315.705591)
			(xy 2.581851 -315.74173) (xy 2.569705 -315.812611) (xy 2.549634 -315.881668) (xy 2.521894 -315.948018)
			(xy 2.486841 -316.010811) (xy 2.444923 -316.069246) (xy 2.396676 -316.122574) (xy 2.342716 -316.170114)
			(xy 2.283734 -316.211259) (xy 2.220484 -316.245481) (xy 2.153774 -316.272343) (xy 2.084459 -316.291502)
			(xy 2.013423 -316.302713) (xy 1.941576 -316.305832) (xy 1.869836 -316.30082) (xy 1.834388 -316.29477)
			(xy 1.812377 -316.291173) (xy 1.767782 -316.290843) (xy 1.723813 -316.2983) (xy 1.681821 -316.313314)
			(xy 1.643093 -316.335427) (xy 1.608817 -316.363958) (xy 1.580047 -316.398033) (xy 1.557664 -316.436606)
			(xy 1.542356 -316.478492) (xy 1.534592 -316.522408) (xy 1.53416 -316.544706) (xy 1.53416 -316.705589)
			(xy 5.814814 -316.705589) (xy 5.814814 -316.634267) (xy 5.8228 -316.563393) (xy 5.83867 -316.493858)
			(xy 5.862227 -316.426538) (xy 5.893172 -316.362279) (xy 5.931118 -316.301888) (xy 5.975587 -316.246126)
			(xy 6.02602 -316.195693) (xy 6.081782 -316.151224) (xy 6.142173 -316.113278) (xy 6.206432 -316.082333)
			(xy 6.273752 -316.058776) (xy 6.343287 -316.042906) (xy 6.414161 -316.03492) (xy 6.485483 -316.03492)
			(xy 6.556357 -316.042906) (xy 6.625892 -316.058776) (xy 6.693212 -316.082333) (xy 6.757471 -316.113278)
			(xy 6.817862 -316.151224) (xy 6.873624 -316.195693) (xy 6.924057 -316.246126) (xy 6.968526 -316.301888)
			(xy 7.006472 -316.362279) (xy 7.037417 -316.426538) (xy 7.060974 -316.493858) (xy 7.076844 -316.563393)
			(xy 7.08483 -316.634267) (xy 7.08533 -316.669928) (xy 7.08483 -316.705589) (xy 7.076844 -316.776463)
			(xy 7.060974 -316.845998) (xy 7.037417 -316.913318) (xy 7.006472 -316.977577) (xy 6.968526 -317.037968)
			(xy 6.924057 -317.09373) (xy 6.873624 -317.144163) (xy 6.817862 -317.188632) (xy 6.757471 -317.226578)
			(xy 6.693212 -317.257523) (xy 6.625892 -317.28108) (xy 6.556357 -317.29695) (xy 6.485483 -317.304936)
			(xy 6.414161 -317.304936) (xy 6.343287 -317.29695) (xy 6.273752 -317.28108) (xy 6.206432 -317.257523)
			(xy 6.142173 -317.226578) (xy 6.081782 -317.188632) (xy 6.02602 -317.144163) (xy 5.975587 -317.09373)
			(xy 5.931118 -317.037968) (xy 5.893172 -316.977577) (xy 5.862227 -316.913318) (xy 5.83867 -316.845998)
			(xy 5.8228 -316.776463) (xy 5.814814 -316.705589) (xy 1.53416 -316.705589) (xy 1.53416 -316.79515)
			(xy 1.5346 -316.817453) (xy 1.542338 -316.861381) (xy 1.557629 -316.903282) (xy 1.580003 -316.941869)
			(xy 1.608772 -316.975955) (xy 1.643052 -317.004493) (xy 1.68179 -317.026605) (xy 1.723794 -317.041612)
			(xy 1.767773 -317.049053) (xy 1.812376 -317.048699) (xy 1.834388 -317.045086) (xy 1.869836 -317.039036)
			(xy 1.941576 -317.034024) (xy 2.013423 -317.037144) (xy 2.084458 -317.048355) (xy 2.153774 -317.067514)
			(xy 2.220483 -317.094376) (xy 2.283733 -317.128598) (xy 2.342715 -317.169742) (xy 2.396674 -317.217283)
			(xy 2.444921 -317.270611) (xy 2.486839 -317.329045) (xy 2.521892 -317.391839) (xy 2.549632 -317.458188)
			(xy 2.569703 -317.527245) (xy 2.581849 -317.598126) (xy 2.585915 -317.669926) (xy 2.581849 -317.741726)
			(xy 2.569703 -317.812607) (xy 2.549632 -317.881664) (xy 2.521892 -317.948013) (xy 2.486839 -318.010807)
			(xy 2.444921 -318.069241) (xy 2.396674 -318.122569) (xy 2.342715 -318.17011) (xy 2.283733 -318.211254)
			(xy 2.220483 -318.245476) (xy 2.153774 -318.272338) (xy 2.084458 -318.291497) (xy 2.013423 -318.302708)
			(xy 1.941576 -318.305828) (xy 1.869836 -318.300816) (xy 1.834388 -318.294766) (xy 1.812377 -318.291169)
			(xy 1.767781 -318.290839) (xy 1.723813 -318.298296) (xy 1.68182 -318.313311) (xy 1.643091 -318.335423)
			(xy 1.608816 -318.363954) (xy 1.580045 -318.398029) (xy 1.557662 -318.436602) (xy 1.542353 -318.478488)
			(xy 1.534588 -318.522404) (xy 1.53416 -318.544702) (xy 1.53416 -318.705585) (xy 3.314946 -318.705585)
			(xy 3.314946 -318.634263) (xy 3.322932 -318.563389) (xy 3.338802 -318.493854) (xy 3.362359 -318.426534)
			(xy 3.393304 -318.362275) (xy 3.43125 -318.301884) (xy 3.475719 -318.246122) (xy 3.526152 -318.195689)
			(xy 3.581914 -318.15122) (xy 3.642305 -318.113274) (xy 3.706564 -318.082329) (xy 3.773884 -318.058772)
			(xy 3.843419 -318.042902) (xy 3.914293 -318.034916) (xy 3.985615 -318.034916) (xy 4.056489 -318.042902)
			(xy 4.126024 -318.058772) (xy 4.193344 -318.082329) (xy 4.257603 -318.113274) (xy 4.317994 -318.15122)
			(xy 4.373756 -318.195689) (xy 4.424189 -318.246122) (xy 4.468658 -318.301884) (xy 4.506604 -318.362275)
			(xy 4.537549 -318.426534) (xy 4.561106 -318.493854) (xy 4.576976 -318.563389) (xy 4.584962 -318.634263)
			(xy 4.585462 -318.669924) (xy 4.584962 -318.705585) (xy 5.814814 -318.705585) (xy 5.814814 -318.634263)
			(xy 5.8228 -318.563389) (xy 5.83867 -318.493854) (xy 5.862227 -318.426534) (xy 5.893172 -318.362275)
			(xy 5.931118 -318.301884) (xy 5.975587 -318.246122) (xy 6.02602 -318.195689) (xy 6.081782 -318.15122)
			(xy 6.142173 -318.113274) (xy 6.206432 -318.082329) (xy 6.273752 -318.058772) (xy 6.343287 -318.042902)
			(xy 6.414161 -318.034916) (xy 6.485483 -318.034916) (xy 6.556357 -318.042902) (xy 6.625892 -318.058772)
			(xy 6.693212 -318.082329) (xy 6.757471 -318.113274) (xy 6.817862 -318.15122) (xy 6.873624 -318.195689)
			(xy 6.924057 -318.246122) (xy 6.968526 -318.301884) (xy 7.006472 -318.362275) (xy 7.037417 -318.426534)
			(xy 7.060974 -318.493854) (xy 7.076844 -318.563389) (xy 7.08483 -318.634263) (xy 7.08533 -318.669924)
			(xy 7.08483 -318.705585) (xy 7.076844 -318.776459) (xy 7.060974 -318.845994) (xy 7.037417 -318.913314)
			(xy 7.006472 -318.977573) (xy 6.968526 -319.037964) (xy 6.924057 -319.093726) (xy 6.873624 -319.144159)
			(xy 6.817862 -319.188628) (xy 6.757471 -319.226574) (xy 6.693212 -319.257519) (xy 6.625892 -319.281076)
			(xy 6.556357 -319.296946) (xy 6.485483 -319.304932) (xy 6.414161 -319.304932) (xy 6.343287 -319.296946)
			(xy 6.273752 -319.281076) (xy 6.206432 -319.257519) (xy 6.142173 -319.226574) (xy 6.081782 -319.188628)
			(xy 6.02602 -319.144159) (xy 5.975587 -319.093726) (xy 5.931118 -319.037964) (xy 5.893172 -318.977573)
			(xy 5.862227 -318.913314) (xy 5.83867 -318.845994) (xy 5.8228 -318.776459) (xy 5.814814 -318.705585)
			(xy 4.584962 -318.705585) (xy 4.576976 -318.776459) (xy 4.561106 -318.845994) (xy 4.537549 -318.913314)
			(xy 4.506604 -318.977573) (xy 4.468658 -319.037964) (xy 4.424189 -319.093726) (xy 4.373756 -319.144159)
			(xy 4.317994 -319.188628) (xy 4.257603 -319.226574) (xy 4.193344 -319.257519) (xy 4.126024 -319.281076)
			(xy 4.056489 -319.296946) (xy 3.985615 -319.304932) (xy 3.914293 -319.304932) (xy 3.843419 -319.296946)
			(xy 3.773884 -319.281076) (xy 3.706564 -319.257519) (xy 3.642305 -319.226574) (xy 3.581914 -319.188628)
			(xy 3.526152 -319.144159) (xy 3.475719 -319.093726) (xy 3.43125 -319.037964) (xy 3.393304 -318.977573)
			(xy 3.362359 -318.913314) (xy 3.338802 -318.845994) (xy 3.322932 -318.776459) (xy 3.314946 -318.705585)
			(xy 1.53416 -318.705585) (xy 1.53416 -318.795146) (xy 1.5346 -318.817449) (xy 1.542337 -318.861377)
			(xy 1.557628 -318.903279) (xy 1.580002 -318.941867) (xy 1.608771 -318.975954) (xy 1.643051 -319.004492)
			(xy 1.681789 -319.026605) (xy 1.723793 -319.041612) (xy 1.767773 -319.049053) (xy 1.812376 -319.048698)
			(xy 1.834388 -319.045082) (xy 1.869836 -319.039032) (xy 1.941576 -319.03402) (xy 2.013423 -319.037139)
			(xy 2.084458 -319.04835) (xy 2.153773 -319.067509) (xy 2.220483 -319.094371) (xy 2.283733 -319.128593)
			(xy 2.342715 -319.169737) (xy 2.396674 -319.217277) (xy 2.444921 -319.270605) (xy 2.48684 -319.329039)
			(xy 2.521892 -319.391833) (xy 2.549632 -319.458182) (xy 2.569703 -319.527239) (xy 2.581849 -319.59812)
			(xy 2.585915 -319.66992) (xy 2.581849 -319.741719) (xy 2.569703 -319.8126) (xy 2.549632 -319.881657)
			(xy 2.521893 -319.948007) (xy 2.48684 -320.0108) (xy 2.444922 -320.069234) (xy 2.396675 -320.122563)
			(xy 2.342715 -320.170103) (xy 2.283733 -320.211247) (xy 2.220483 -320.245469) (xy 2.153774 -320.272331)
			(xy 2.084459 -320.29149) (xy 2.013423 -320.302701) (xy 1.941577 -320.30582) (xy 1.869837 -320.300808)
			(xy 1.834388 -320.294762) (xy 1.812377 -320.291166) (xy 1.767781 -320.290835) (xy 1.723812 -320.298292)
			(xy 1.681819 -320.313307) (xy 1.64309 -320.335419) (xy 1.608814 -320.36395) (xy 1.580043 -320.398025)
			(xy 1.557659 -320.436597) (xy 1.54235 -320.478484) (xy 1.534585 -320.522399) (xy 1.53416 -320.544698)
			(xy 1.53416 -320.705581) (xy 3.314946 -320.705581) (xy 3.314946 -320.634259) (xy 3.322932 -320.563385)
			(xy 3.338802 -320.49385) (xy 3.362359 -320.42653) (xy 3.393304 -320.362271) (xy 3.43125 -320.30188)
			(xy 3.475719 -320.246118) (xy 3.526152 -320.195685) (xy 3.581914 -320.151216) (xy 3.642305 -320.11327)
			(xy 3.706564 -320.082325) (xy 3.773884 -320.058768) (xy 3.843419 -320.042898) (xy 3.914293 -320.034912)
			(xy 3.985615 -320.034912) (xy 4.056489 -320.042898) (xy 4.126024 -320.058768) (xy 4.193344 -320.082325)
			(xy 4.257603 -320.11327) (xy 4.317994 -320.151216) (xy 4.373756 -320.195685) (xy 4.424189 -320.246118)
			(xy 4.468658 -320.30188) (xy 4.506604 -320.362271) (xy 4.537549 -320.42653) (xy 4.561106 -320.49385)
			(xy 4.576976 -320.563385) (xy 4.584962 -320.634259) (xy 4.585462 -320.66992) (xy 4.584962 -320.705581)
			(xy 4.576976 -320.776455) (xy 4.561106 -320.84599) (xy 4.537549 -320.91331) (xy 4.506604 -320.977569)
			(xy 4.468658 -321.03796) (xy 4.424189 -321.093722) (xy 4.373756 -321.144155) (xy 4.317994 -321.188624)
			(xy 4.257603 -321.22657) (xy 4.193344 -321.257515) (xy 4.126024 -321.281072) (xy 4.056489 -321.296942)
			(xy 3.985615 -321.304928) (xy 3.914293 -321.304928) (xy 3.843419 -321.296942) (xy 3.773884 -321.281072)
			(xy 3.706564 -321.257515) (xy 3.642305 -321.22657) (xy 3.581914 -321.188624) (xy 3.526152 -321.144155)
			(xy 3.475719 -321.093722) (xy 3.43125 -321.03796) (xy 3.393304 -320.977569) (xy 3.362359 -320.91331)
			(xy 3.338802 -320.84599) (xy 3.322932 -320.776455) (xy 3.314946 -320.705581) (xy 1.53416 -320.705581)
			(xy 1.53416 -322.795138) (xy 1.5346 -322.817441) (xy 1.542338 -322.861369) (xy 1.557629 -322.903271)
			(xy 1.580002 -322.941858) (xy 1.608772 -322.975944) (xy 1.643052 -323.004482) (xy 1.681789 -323.026595)
			(xy 1.723793 -323.041602) (xy 1.767773 -323.049043) (xy 1.812376 -323.048689) (xy 1.834388 -323.045074)
			(xy 1.869121 -323.039134) (xy 1.939406 -323.034066) (xy 2.00982 -323.03681) (xy 2.079498 -323.047333)
			(xy 2.147582 -323.065506) (xy 2.18059 -323.07784) (xy 2.210946 -323.0901) (xy 2.269202 -323.119979)
			(xy 2.324082 -323.155683) (xy 2.375004 -323.196834) (xy 2.421432 -323.242997) (xy 2.442464 -323.268086)
			(xy 2.459736 -323.289168) (xy 2.559812 -323.33946) (xy 3.174746 -323.33946) (xy 3.197652 -323.33797)
			(xy 3.242404 -323.327771) (xy 3.284597 -323.309702) (xy 3.322858 -323.284349) (xy 3.355945 -323.252537)
			(xy 3.382781 -323.2153) (xy 3.402494 -323.17385) (xy 3.414442 -323.129533) (xy 3.418237 -323.083791)
			(xy 3.413756 -323.038112) (xy 3.401145 -322.993979) (xy 3.391408 -322.973192) (xy 3.374631 -322.941235)
			(xy 3.347596 -322.874311) (xy 3.328317 -322.804754) (xy 3.317043 -322.733461) (xy 3.313917 -322.66135)
			(xy 3.318982 -322.589349) (xy 3.332171 -322.518386) (xy 3.353315 -322.449373) (xy 3.382141 -322.383201)
			(xy 3.418278 -322.32072) (xy 3.461262 -322.262735) (xy 3.510537 -322.209993) (xy 3.565471 -322.163174)
			(xy 3.625355 -322.122879) (xy 3.689419 -322.089628) (xy 3.756837 -322.06385) (xy 3.826742 -322.045875)
			(xy 3.898233 -322.035935) (xy 3.97039 -322.034159) (xy 4.042284 -322.040569) (xy 4.112988 -322.055082)
			(xy 4.181593 -322.077513) (xy 4.247216 -322.107571) (xy 4.30901 -322.14487) (xy 4.366181 -322.18893)
			(xy 4.417992 -322.239183) (xy 4.463776 -322.294983) (xy 4.502944 -322.35561) (xy 4.519422 -322.387722)
			(xy 4.53083 -322.408151) (xy 4.559905 -322.444803) (xy 4.5952 -322.47551) (xy 4.635522 -322.499235)
			(xy 4.679506 -322.515175) (xy 4.725666 -322.52279) (xy 4.77244 -322.521824) (xy 4.818246 -322.512308)
			(xy 4.861534 -322.494565) (xy 4.900842 -322.469195) (xy 4.918202 -322.453508) (xy 5.21716 -322.15455)
			(xy 5.960618 -321.411346) (xy 6.159246 -321.212464) (xy 6.963918 -321.212464) (xy 7.074408 -321.101974)
			(xy 7.650988 -320.525648) (xy 7.805928 -320.525648) (xy 7.827979 -320.524213) (xy 7.871126 -320.514688)
			(xy 7.911974 -320.497842) (xy 7.949293 -320.474184) (xy 7.981957 -320.444428) (xy 8.008981 -320.40947)
			(xy 8.029551 -320.370364) (xy 8.043046 -320.32829) (xy 8.04906 -320.284515) (xy 8.04741 -320.24036)
			(xy 8.038148 -320.197157) (xy 8.021552 -320.156206) (xy 7.998123 -320.118744) (xy 7.983728 -320.101976)
			(xy 7.959656 -320.075276) (xy 7.917044 -320.017373) (xy 7.881238 -319.955031) (xy 7.852696 -319.889047)
			(xy 7.831782 -319.820263) (xy 7.818765 -319.749559) (xy 7.813809 -319.677837) (xy 7.816978 -319.606014)
			(xy 7.828232 -319.535008) (xy 7.847428 -319.465725) (xy 7.874319 -319.399051) (xy 7.908562 -319.335838)
			(xy 7.94972 -319.276892) (xy 7.997267 -319.222968) (xy 8.050595 -319.174754) (xy 8.109024 -319.132865)
			(xy 8.171807 -319.097838) (xy 8.238141 -319.070119) (xy 8.307179 -319.050063) (xy 8.37804 -319.037926)
			(xy 8.449818 -319.033863) (xy 8.521596 -319.037926) (xy 8.592457 -319.050063) (xy 8.661495 -319.070119)
			(xy 8.727829 -319.097838) (xy 8.790612 -319.132865) (xy 8.849041 -319.174754) (xy 8.902369 -319.222968)
			(xy 8.949916 -319.276892) (xy 8.991074 -319.335838) (xy 9.025317 -319.399051) (xy 9.042776 -319.442338)
			(xy 14.63624 -319.442338) (xy 14.640311 -319.386716) (xy 14.652437 -319.332279) (xy 14.67236 -319.280188)
			(xy 14.699656 -319.231553) (xy 14.733742 -319.18741) (xy 14.773891 -319.148701) (xy 14.819249 -319.11625)
			(xy 14.868849 -319.090749) (xy 14.921633 -319.072742) (xy 14.976476 -319.062612) (xy 15.03221 -319.060575)
			(xy 15.087647 -319.066675) (xy 15.141604 -319.080781) (xy 15.192933 -319.102593) (xy 15.240539 -319.131647)
			(xy 15.283407 -319.167322) (xy 15.320624 -319.208859) (xy 15.351397 -319.255372) (xy 15.375069 -319.305869)
			(xy 15.391137 -319.359276) (xy 15.399257 -319.414452) (xy 15.399766 -319.442338) (xy 15.399257 -319.470224)
			(xy 15.391137 -319.5254) (xy 15.375069 -319.578807) (xy 15.351397 -319.629304) (xy 15.320624 -319.675817)
			(xy 15.283407 -319.717354) (xy 15.240539 -319.753029) (xy 15.192933 -319.782083) (xy 15.141604 -319.803895)
			(xy 15.087647 -319.818001) (xy 15.03221 -319.824101) (xy 14.976476 -319.822064) (xy 14.921633 -319.811934)
			(xy 14.868849 -319.793927) (xy 14.819249 -319.768426) (xy 14.773891 -319.735975) (xy 14.733742 -319.697266)
			(xy 14.699656 -319.653123) (xy 14.67236 -319.604488) (xy 14.652437 -319.552397) (xy 14.640311 -319.49796)
			(xy 14.63624 -319.442338) (xy 9.042776 -319.442338) (xy 9.052208 -319.465725) (xy 9.071404 -319.535008)
			(xy 9.082658 -319.606014) (xy 9.085827 -319.677837) (xy 9.080871 -319.749559) (xy 9.067854 -319.820263)
			(xy 9.04694 -319.889047) (xy 9.018398 -319.955031) (xy 8.982592 -320.017373) (xy 8.93998 -320.075276)
			(xy 8.915908 -320.101976) (xy 8.901521 -320.118731) (xy 8.878162 -320.156207) (xy 8.861627 -320.197154)
			(xy 8.852413 -320.240341) (xy 8.850795 -320.284471) (xy 8.856824 -320.328217) (xy 8.870317 -320.370264)
			(xy 8.890869 -320.409349) (xy 8.917863 -320.444297) (xy 8.950487 -320.474058) (xy 8.987761 -320.497737)
			(xy 9.028564 -320.514623) (xy 9.071671 -320.524209) (xy 9.093708 -320.525648) (xy 9.29513 -320.525648)
			(xy 9.786366 -321.01663) (xy 10.664444 -321.894708) (xy 10.664444 -323.185282) (xy 14.455646 -323.185282)
			(xy 14.459717 -323.12966) (xy 14.471843 -323.075223) (xy 14.491766 -323.023132) (xy 14.519062 -322.974497)
			(xy 14.553148 -322.930354) (xy 14.593297 -322.891645) (xy 14.638655 -322.859194) (xy 14.688255 -322.833693)
			(xy 14.741039 -322.815686) (xy 14.795882 -322.805556) (xy 14.851616 -322.803519) (xy 14.907053 -322.809619)
			(xy 14.96101 -322.823725) (xy 15.012339 -322.845537) (xy 15.059945 -322.874591) (xy 15.102813 -322.910266)
			(xy 15.14003 -322.951803) (xy 15.170803 -322.998316) (xy 15.194475 -323.048813) (xy 15.210543 -323.10222)
			(xy 15.218663 -323.157396) (xy 15.219172 -323.185282) (xy 15.218663 -323.213168) (xy 15.210543 -323.268344)
			(xy 15.194475 -323.321751) (xy 15.170803 -323.372248) (xy 15.14003 -323.418761) (xy 15.102813 -323.460298)
			(xy 15.059945 -323.495973) (xy 15.012339 -323.525027) (xy 14.96101 -323.546839) (xy 14.907053 -323.560945)
			(xy 14.851616 -323.567045) (xy 14.795882 -323.565008) (xy 14.741039 -323.554878) (xy 14.688255 -323.536871)
			(xy 14.638655 -323.51137) (xy 14.593297 -323.478919) (xy 14.553148 -323.44021) (xy 14.519062 -323.396067)
			(xy 14.491766 -323.347432) (xy 14.471843 -323.295341) (xy 14.459717 -323.240904) (xy 14.455646 -323.185282)
			(xy 10.664444 -323.185282) (xy 10.664444 -324.65391) (xy 10.83564 -324.82536) (xy 10.910062 -324.899782)
			(xy 10.922194 -324.911243) (xy 10.951073 -324.927952) (xy 10.983296 -324.936603) (xy 11.01666 -324.936603)
			(xy 11.048883 -324.927952) (xy 11.077762 -324.911243) (xy 11.089894 -324.899782) (xy 11.100172 -324.888872)
			(xy 11.115789 -324.863298) (xy 11.125026 -324.834792) (xy 11.127375 -324.804919) (xy 11.125454 -324.790054)
			(xy 11.12124 -324.760312) (xy 11.119717 -324.700261) (xy 11.126063 -324.640527) (xy 11.140168 -324.582137)
			(xy 11.161789 -324.526093) (xy 11.190555 -324.473358) (xy 11.225972 -324.424839) (xy 11.267431 -324.38137)
			(xy 11.31422 -324.343697) (xy 11.365534 -324.312468) (xy 11.420492 -324.288219) (xy 11.47815 -324.271368)
			(xy 11.537517 -324.262203) (xy 11.597573 -324.260882) (xy 11.657285 -324.267428) (xy 11.715628 -324.281728)
			(xy 11.7716 -324.303537) (xy 11.824238 -324.332479) (xy 11.872637 -324.368059) (xy 11.915967 -324.409663)
			(xy 11.953483 -324.456578) (xy 11.98454 -324.507996) (xy 12.008605 -324.563036) (xy 12.025263 -324.62075)
			(xy 12.034229 -324.680147) (xy 12.035349 -324.740207) (xy 12.028603 -324.799897) (xy 12.014107 -324.858192)
			(xy 11.992111 -324.91409) (xy 11.962992 -324.96663) (xy 11.927251 -325.014911) (xy 11.885501 -325.058101)
			(xy 11.867688 -325.072248) (xy 14.440406 -325.072248) (xy 14.444477 -325.016626) (xy 14.456603 -324.962189)
			(xy 14.476526 -324.910098) (xy 14.503822 -324.861463) (xy 14.537908 -324.81732) (xy 14.578057 -324.778611)
			(xy 14.623415 -324.74616) (xy 14.673015 -324.720659) (xy 14.725799 -324.702652) (xy 14.780642 -324.692522)
			(xy 14.836376 -324.690485) (xy 14.891813 -324.696585) (xy 14.94577 -324.710691) (xy 14.997099 -324.732503)
			(xy 15.044705 -324.761557) (xy 15.087573 -324.797232) (xy 15.12479 -324.838769) (xy 15.155563 -324.885282)
			(xy 15.179235 -324.935779) (xy 15.195303 -324.989186) (xy 15.203423 -325.044362) (xy 15.203932 -325.072248)
			(xy 15.203423 -325.100134) (xy 15.195303 -325.15531) (xy 15.179235 -325.208717) (xy 15.155563 -325.259214)
			(xy 15.12479 -325.305727) (xy 15.087573 -325.347264) (xy 15.044705 -325.382939) (xy 14.997099 -325.411993)
			(xy 14.94577 -325.433805) (xy 14.891813 -325.447911) (xy 14.836376 -325.454011) (xy 14.780642 -325.451974)
			(xy 14.725799 -325.441844) (xy 14.673015 -325.423837) (xy 14.623415 -325.398336) (xy 14.578057 -325.365885)
			(xy 14.537908 -325.327176) (xy 14.503822 -325.283033) (xy 14.476526 -325.234398) (xy 14.456603 -325.182307)
			(xy 14.444477 -325.12787) (xy 14.440406 -325.072248) (xy 11.867688 -325.072248) (xy 11.838461 -325.09546)
			(xy 11.786939 -325.126344) (xy 11.731819 -325.150224) (xy 11.70305 -325.158862) (xy 11.682005 -325.165343)
			(xy 11.642372 -325.184521) (xy 11.606639 -325.210246) (xy 11.575875 -325.241745) (xy 11.551003 -325.278077)
			(xy 11.532767 -325.318153) (xy 11.521713 -325.360772) (xy 11.518172 -325.404659) (xy 11.522251 -325.4485)
			(xy 11.533826 -325.490981) (xy 11.552552 -325.53083) (xy 11.577868 -325.566854) (xy 11.593068 -325.582788)
			(xy 11.626596 -325.616316) (xy 11.6586 -325.625206) (xy 11.688112 -325.634012) (xy 11.744639 -325.65846)
			(xy 11.797378 -325.690266) (xy 11.845376 -325.728856) (xy 11.887767 -325.773533) (xy 11.923784 -325.82349)
			(xy 11.952779 -325.877825) (xy 11.974226 -325.935558) (xy 11.987739 -325.995644) (xy 11.993073 -326.057)
			(xy 11.990133 -326.118517) (xy 11.978972 -326.179085) (xy 11.95979 -326.237609) (xy 11.932935 -326.293033)
			(xy 11.898891 -326.344355) (xy 11.858273 -326.39065) (xy 11.811815 -326.431081) (xy 11.786362 -326.44842)
			(xy 11.759438 -326.465946) (xy 11.729212 -326.522334) (xy 11.729212 -326.965564) (xy 11.729573 -326.979851)
			(xy 11.735935 -327.007707) (xy 11.748367 -327.033434) (xy 11.766239 -327.055728) (xy 11.777218 -327.064878)
			(xy 11.799923 -327.083539) (xy 11.840832 -327.125735) (xy 11.876006 -327.17282) (xy 11.904864 -327.224019)
			(xy 11.926934 -327.278489) (xy 11.941851 -327.335337) (xy 11.94937 -327.393625) (xy 11.949369 -327.452397)
			(xy 11.941846 -327.510685) (xy 11.926926 -327.567532) (xy 11.904854 -327.622002) (xy 11.875993 -327.673199)
			(xy 11.840818 -327.720282) (xy 11.799906 -327.762476) (xy 11.777218 -327.781158) (xy 11.7663 -327.790364)
			(xy 11.748475 -327.812669) (xy 11.736047 -327.838374) (xy 11.729637 -327.866197) (xy 11.729212 -327.880472)
			(xy 11.729212 -328.295) (xy 11.75512 -328.347832) (xy 11.778488 -328.365866) (xy 11.801736 -328.384512)
			(xy 11.84368 -328.426848) (xy 11.879776 -328.474268) (xy 11.909413 -328.525971) (xy 11.932091 -328.581083)
			(xy 11.947426 -328.638672) (xy 11.955159 -328.697764) (xy 11.955159 -328.757359) (xy 11.947426 -328.81645)
			(xy 11.93209 -328.874039) (xy 11.909412 -328.929151) (xy 11.879774 -328.980854) (xy 11.843678 -329.028274)
			(xy 11.801734 -329.07061) (xy 11.778488 -329.089258) (xy 11.75512 -329.107292) (xy 11.729212 -329.160124)
			(xy 11.729212 -329.676506) (xy 11.75766 -329.73137) (xy 11.78306 -329.74915) (xy 11.808286 -329.767625)
			(xy 11.853967 -329.810319) (xy 11.893412 -329.858834) (xy 11.925887 -329.912266) (xy 11.950788 -329.969621)
			(xy 11.96765 -330.029831) (xy 11.97616 -330.091776) (xy 11.97616 -330.154302) (xy 11.96765 -330.216247)
			(xy 11.950788 -330.276457) (xy 11.925888 -330.333812) (xy 11.893414 -330.387244) (xy 11.853969 -330.435759)
			(xy 11.808288 -330.478454) (xy 11.78306 -330.496926) (xy 11.75766 -330.514706) (xy 11.729212 -330.56957)
			(xy 11.729212 -331.212444) (xy 11.729571 -331.226732) (xy 11.735929 -331.254591) (xy 11.748359 -331.280322)
			(xy 11.76623 -331.302619) (xy 11.777218 -331.311758) (xy 11.799924 -331.330419) (xy 11.840836 -331.372615)
			(xy 11.876012 -331.419701) (xy 11.904873 -331.4709) (xy 11.926944 -331.525373) (xy 11.941864 -331.582221)
			(xy 11.949385 -331.640512) (xy 11.949385 -331.699286) (xy 11.941864 -331.757576) (xy 11.926945 -331.814425)
			(xy 11.904874 -331.868897) (xy 11.876013 -331.920097) (xy 11.840838 -331.967183) (xy 11.799926 -332.00938)
			(xy 11.777218 -332.028038) (xy 11.766298 -332.037243) (xy 11.74847 -332.059547) (xy 11.736038 -332.085253)
			(xy 11.729624 -332.113076) (xy 11.729212 -332.127352) (xy 11.729212 -332.514698) (xy 13.396704 -332.514698)
			(xy 13.396704 -332.454762) (xy 13.404527 -332.39534) (xy 13.42004 -332.337447) (xy 13.442976 -332.282074)
			(xy 13.472943 -332.230168) (xy 13.50943 -332.182618) (xy 13.55181 -332.140238) (xy 13.59936 -332.103751)
			(xy 13.651266 -332.073784) (xy 13.706639 -332.050848) (xy 13.764532 -332.035335) (xy 13.823954 -332.027512)
			(xy 13.88389 -332.027512) (xy 13.943312 -332.035335) (xy 14.001205 -332.050848) (xy 14.056578 -332.073784)
			(xy 14.108484 -332.103751) (xy 14.156034 -332.140238) (xy 14.198414 -332.182618) (xy 14.234901 -332.230168)
			(xy 14.264868 -332.282074) (xy 14.287804 -332.337447) (xy 14.303317 -332.39534) (xy 14.31114 -332.454762)
			(xy 14.31163 -332.48473) (xy 14.31114 -332.514698) (xy 14.304619 -332.564228) (xy 15.256746 -332.564228)
			(xy 15.256746 -332.504292) (xy 15.264569 -332.44487) (xy 15.280082 -332.386977) (xy 15.303018 -332.331604)
			(xy 15.332985 -332.279698) (xy 15.369472 -332.232148) (xy 15.411852 -332.189768) (xy 15.459402 -332.153281)
			(xy 15.511308 -332.123314) (xy 15.566681 -332.100378) (xy 15.624574 -332.084865) (xy 15.683996 -332.077042)
			(xy 15.743932 -332.077042) (xy 15.803354 -332.084865) (xy 15.861247 -332.100378) (xy 15.91662 -332.123314)
			(xy 15.968526 -332.153281) (xy 16.016076 -332.189768) (xy 16.044842 -332.218534) (xy 16.705054 -332.218534)
			(xy 16.705054 -332.158598) (xy 16.712877 -332.099176) (xy 16.72839 -332.041283) (xy 16.751326 -331.98591)
			(xy 16.781293 -331.934004) (xy 16.81778 -331.886454) (xy 16.86016 -331.844074) (xy 16.90771 -331.807587)
			(xy 16.959616 -331.77762) (xy 17.014989 -331.754684) (xy 17.072882 -331.739171) (xy 17.132304 -331.731348)
			(xy 17.19224 -331.731348) (xy 17.251662 -331.739171) (xy 17.309555 -331.754684) (xy 17.364928 -331.77762)
			(xy 17.416834 -331.807587) (xy 17.464384 -331.844074) (xy 17.506764 -331.886454) (xy 17.543251 -331.934004)
			(xy 17.573218 -331.98591) (xy 17.596154 -332.041283) (xy 17.611667 -332.099176) (xy 17.61949 -332.158598)
			(xy 17.61998 -332.188566) (xy 17.61949 -332.218534) (xy 17.611667 -332.277956) (xy 17.596154 -332.335849)
			(xy 17.573218 -332.391222) (xy 17.543251 -332.443128) (xy 17.506764 -332.490678) (xy 17.464384 -332.533058)
			(xy 17.416834 -332.569545) (xy 17.364928 -332.599512) (xy 17.309555 -332.622448) (xy 17.251662 -332.637961)
			(xy 17.19224 -332.645784) (xy 17.132304 -332.645784) (xy 17.072882 -332.637961) (xy 17.014989 -332.622448)
			(xy 16.959616 -332.599512) (xy 16.90771 -332.569545) (xy 16.86016 -332.533058) (xy 16.81778 -332.490678)
			(xy 16.781293 -332.443128) (xy 16.751326 -332.391222) (xy 16.72839 -332.335849) (xy 16.712877 -332.277956)
			(xy 16.705054 -332.218534) (xy 16.044842 -332.218534) (xy 16.058456 -332.232148) (xy 16.094943 -332.279698)
			(xy 16.12491 -332.331604) (xy 16.147846 -332.386977) (xy 16.163359 -332.44487) (xy 16.171182 -332.504292)
			(xy 16.171672 -332.53426) (xy 16.171182 -332.564228) (xy 16.163359 -332.62365) (xy 16.147846 -332.681543)
			(xy 16.12491 -332.736916) (xy 16.094943 -332.788822) (xy 16.058456 -332.836372) (xy 16.016076 -332.878752)
			(xy 15.968526 -332.915239) (xy 15.91662 -332.945206) (xy 15.861247 -332.968142) (xy 15.803354 -332.983655)
			(xy 15.743932 -332.991478) (xy 15.683996 -332.991478) (xy 15.624574 -332.983655) (xy 15.566681 -332.968142)
			(xy 15.511308 -332.945206) (xy 15.459402 -332.915239) (xy 15.411852 -332.878752) (xy 15.369472 -332.836372)
			(xy 15.332985 -332.788822) (xy 15.303018 -332.736916) (xy 15.280082 -332.681543) (xy 15.264569 -332.62365)
			(xy 15.256746 -332.564228) (xy 14.304619 -332.564228) (xy 14.303317 -332.57412) (xy 14.287804 -332.632013)
			(xy 14.264868 -332.687386) (xy 14.234901 -332.739292) (xy 14.198414 -332.786842) (xy 14.156034 -332.829222)
			(xy 14.108484 -332.865709) (xy 14.056578 -332.895676) (xy 14.001205 -332.918612) (xy 13.943312 -332.934125)
			(xy 13.88389 -332.941948) (xy 13.823954 -332.941948) (xy 13.764532 -332.934125) (xy 13.706639 -332.918612)
			(xy 13.651266 -332.895676) (xy 13.59936 -332.865709) (xy 13.55181 -332.829222) (xy 13.50943 -332.786842)
			(xy 13.472943 -332.739292) (xy 13.442976 -332.687386) (xy 13.42004 -332.632013) (xy 13.404527 -332.57412)
			(xy 13.396704 -332.514698) (xy 11.729212 -332.514698) (xy 11.729212 -332.531974) (xy 11.755374 -332.58506)
			(xy 11.77925 -332.603094) (xy 11.802833 -332.621707) (xy 11.845391 -332.664112) (xy 11.882036 -332.71172)
			(xy 11.912138 -332.763713) (xy 11.935179 -332.819198) (xy 11.950764 -332.87722) (xy 11.958623 -332.936782)
			(xy 11.958623 -332.99686) (xy 11.950763 -333.056423) (xy 11.935179 -333.114444) (xy 11.912137 -333.169929)
			(xy 11.882035 -333.221922) (xy 11.84539 -333.26953) (xy 11.802831 -333.311935) (xy 11.77925 -333.33055)
			(xy 11.755374 -333.348584) (xy 11.729212 -333.40167) (xy 11.729212 -333.52232) (xy 11.730439 -333.545257)
			(xy 11.740128 -333.590152) (xy 11.757723 -333.632577) (xy 11.782653 -333.671152) (xy 11.814106 -333.704621)
			(xy 11.851059 -333.731896) (xy 11.89231 -333.75209) (xy 11.936518 -333.764547) (xy 11.959336 -333.767176)
			(xy 11.990088 -333.769444) (xy 12.050619 -333.781208) (xy 12.109022 -333.800992) (xy 12.164241 -333.828436)
			(xy 12.215276 -333.863046) (xy 12.261203 -333.904193) (xy 12.30119 -333.951133) (xy 12.334513 -334.003017)
			(xy 12.36057 -334.058904) (xy 12.378889 -334.117783) (xy 12.389137 -334.178589) (xy 12.39113 -334.24022)
			(xy 12.38483 -334.301561) (xy 12.370354 -334.3615) (xy 12.347961 -334.418954) (xy 12.318058 -334.472882)
			(xy 12.281187 -334.522307) (xy 12.238014 -334.566334) (xy 12.189321 -334.604168) (xy 12.13599 -334.635122)
			(xy 12.078987 -334.658637) (xy 12.019342 -334.674286) (xy 11.9888 -334.678528) (xy 11.959911 -334.68156)
			(xy 11.901823 -334.681176) (xy 11.872976 -334.677766) (xy 11.864594 -334.67675) (xy 11.856212 -334.67675)
			(xy 11.839559 -334.677243) (xy 11.807387 -334.685863) (xy 11.778543 -334.702519) (xy 11.754995 -334.726074)
			(xy 11.738349 -334.754922) (xy 11.729738 -334.787096) (xy 11.729212 -334.80375) (xy 11.729212 -334.914494)
			(xy 11.729706 -334.931149) (xy 11.738326 -334.963323) (xy 11.754981 -334.99217) (xy 11.778535 -335.015723)
			(xy 11.807382 -335.032376) (xy 11.839557 -335.040995) (xy 11.856212 -335.041494) (xy 11.864594 -335.041494)
			(xy 11.872976 -335.040478) (xy 11.902749 -335.037017) (xy 11.962687 -335.036991) (xy 12.022117 -335.04479)
			(xy 12.080019 -335.060282) (xy 12.135403 -335.083202) (xy 12.18732 -335.113156) (xy 12.234882 -335.149632)
			(xy 12.277275 -335.192006) (xy 12.313772 -335.239552) (xy 12.343749 -335.291456) (xy 12.366693 -335.346829)
			(xy 12.38221 -335.404725) (xy 12.390036 -335.46415) (xy 12.390036 -335.524089) (xy 12.38221 -335.583515)
			(xy 12.366693 -335.64141) (xy 12.343749 -335.696784) (xy 12.313772 -335.748688) (xy 12.277275 -335.796234)
			(xy 12.234882 -335.838608) (xy 12.18732 -335.875084) (xy 12.135403 -335.905038) (xy 12.080019 -335.927958)
			(xy 12.022117 -335.94345) (xy 11.962688 -335.951249) (xy 11.902749 -335.951223) (xy 11.872976 -335.947766)
			(xy 11.864594 -335.94675) (xy 11.856212 -335.94675) (xy 11.839559 -335.947243) (xy 11.807387 -335.955863)
			(xy 11.778543 -335.972519) (xy 11.754995 -335.996074) (xy 11.738349 -336.024922) (xy 11.729738 -336.057096)
			(xy 11.729212 -336.07375) (xy 11.729212 -336.184494) (xy 11.729706 -336.201149) (xy 11.738326 -336.233323)
			(xy 11.754981 -336.26217) (xy 11.778535 -336.285723) (xy 11.807382 -336.302376) (xy 11.839557 -336.310995)
			(xy 11.856212 -336.311494) (xy 11.864594 -336.311494) (xy 11.872976 -336.310478) (xy 11.902749 -336.307017)
			(xy 11.962687 -336.306991) (xy 12.022117 -336.31479) (xy 12.080019 -336.330282) (xy 12.135403 -336.353202)
			(xy 12.18732 -336.383156) (xy 12.234882 -336.419632) (xy 12.277275 -336.462006) (xy 12.313772 -336.509552)
			(xy 12.343749 -336.561456) (xy 12.366693 -336.616829) (xy 12.38221 -336.674725) (xy 12.390036 -336.73415)
			(xy 12.390036 -336.794089) (xy 12.38221 -336.853515) (xy 12.366693 -336.91141) (xy 12.343749 -336.966784)
			(xy 12.313772 -337.018688) (xy 12.277275 -337.066234) (xy 12.234882 -337.108608) (xy 12.18732 -337.145084)
			(xy 12.135403 -337.175038) (xy 12.080019 -337.197958) (xy 12.022117 -337.21345) (xy 11.962688 -337.221249)
			(xy 11.902749 -337.221223) (xy 11.872976 -337.217766) (xy 11.864594 -337.21675) (xy 11.856212 -337.21675)
			(xy 11.839559 -337.217243) (xy 11.807387 -337.225863) (xy 11.778543 -337.242519) (xy 11.754995 -337.266074)
			(xy 11.738349 -337.294922) (xy 11.729738 -337.327096) (xy 11.729212 -337.34375) (xy 11.729212 -337.363562)
			(xy 17.484342 -337.363562) (xy 17.488413 -337.30794) (xy 17.500539 -337.253503) (xy 17.520462 -337.201412)
			(xy 17.547758 -337.152777) (xy 17.581844 -337.108634) (xy 17.621993 -337.069925) (xy 17.667351 -337.037474)
			(xy 17.716951 -337.011973) (xy 17.769735 -336.993966) (xy 17.824578 -336.983836) (xy 17.880312 -336.981799)
			(xy 17.935749 -336.987899) (xy 17.989706 -337.002005) (xy 18.041035 -337.023817) (xy 18.088641 -337.052871)
			(xy 18.131509 -337.088546) (xy 18.168726 -337.130083) (xy 18.199499 -337.176596) (xy 18.223171 -337.227093)
			(xy 18.239239 -337.2805) (xy 18.247359 -337.335676) (xy 18.247868 -337.363562) (xy 18.247359 -337.391448)
			(xy 18.239239 -337.446624) (xy 18.223171 -337.500031) (xy 18.199499 -337.550528) (xy 18.168726 -337.597041)
			(xy 18.131509 -337.638578) (xy 18.088641 -337.674253) (xy 18.041035 -337.703307) (xy 17.989706 -337.725119)
			(xy 17.935749 -337.739225) (xy 17.880312 -337.745325) (xy 17.824578 -337.743288) (xy 17.769735 -337.733158)
			(xy 17.716951 -337.715151) (xy 17.667351 -337.68965) (xy 17.621993 -337.657199) (xy 17.581844 -337.61849)
			(xy 17.547758 -337.574347) (xy 17.520462 -337.525712) (xy 17.500539 -337.473621) (xy 17.488413 -337.419184)
			(xy 17.484342 -337.363562) (xy 11.729212 -337.363562) (xy 11.729212 -337.454494) (xy 11.729706 -337.471149)
			(xy 11.738326 -337.503323) (xy 11.754981 -337.53217) (xy 11.778535 -337.555723) (xy 11.807382 -337.572376)
			(xy 11.839557 -337.580995) (xy 11.856212 -337.581494) (xy 11.864594 -337.581494) (xy 11.872976 -337.580478)
			(xy 11.902749 -337.577017) (xy 11.962687 -337.576991) (xy 12.022117 -337.58479) (xy 12.080019 -337.600282)
			(xy 12.135403 -337.623202) (xy 12.18732 -337.653156) (xy 12.234882 -337.689632) (xy 12.277275 -337.732006)
			(xy 12.313772 -337.779552) (xy 12.343749 -337.831456) (xy 12.366693 -337.886829) (xy 12.38221 -337.944725)
			(xy 12.390036 -338.00415) (xy 12.390036 -338.064089) (xy 12.38221 -338.123515) (xy 12.366693 -338.18141)
			(xy 12.343749 -338.236784) (xy 12.313772 -338.288688) (xy 12.277275 -338.336234) (xy 12.234882 -338.378608)
			(xy 12.18732 -338.415084) (xy 12.135403 -338.445038) (xy 12.080019 -338.467958) (xy 12.022117 -338.48345)
			(xy 11.962688 -338.491249) (xy 11.902749 -338.491223) (xy 11.872976 -338.487766) (xy 11.864594 -338.48675)
			(xy 11.856212 -338.48675) (xy 11.839559 -338.487243) (xy 11.807387 -338.495863) (xy 11.778543 -338.512519)
			(xy 11.754995 -338.536074) (xy 11.738349 -338.564922) (xy 11.729738 -338.597096) (xy 11.729212 -338.61375)
			(xy 11.729212 -338.724494) (xy 11.729706 -338.741149) (xy 11.738326 -338.773323) (xy 11.754981 -338.80217)
			(xy 11.778535 -338.825723) (xy 11.807382 -338.842376) (xy 11.839557 -338.850995) (xy 11.856212 -338.851494)
			(xy 11.864594 -338.851494) (xy 11.872976 -338.850478) (xy 11.902749 -338.847017) (xy 11.962687 -338.846991)
			(xy 12.022117 -338.85479) (xy 12.080019 -338.870282) (xy 12.135403 -338.893202) (xy 12.18732 -338.923156)
			(xy 12.234882 -338.959632) (xy 12.277275 -339.002006) (xy 12.313772 -339.049552) (xy 12.343749 -339.101456)
			(xy 12.366693 -339.156829) (xy 12.38221 -339.214725) (xy 12.390036 -339.27415) (xy 12.390036 -339.334089)
			(xy 12.38221 -339.393515) (xy 12.366693 -339.45141) (xy 12.343749 -339.506784) (xy 12.313772 -339.558688)
			(xy 12.277275 -339.606234) (xy 12.234882 -339.648608) (xy 12.18732 -339.685084) (xy 12.135403 -339.715038)
			(xy 12.080019 -339.737958) (xy 12.022117 -339.75345) (xy 11.962688 -339.761249) (xy 11.902749 -339.761223)
			(xy 11.872976 -339.757766) (xy 11.864594 -339.75675) (xy 11.856212 -339.75675) (xy 11.839559 -339.757243)
			(xy 11.807387 -339.765863) (xy 11.778543 -339.782519) (xy 11.754995 -339.806074) (xy 11.738349 -339.834922)
			(xy 11.729738 -339.867096) (xy 11.729212 -339.88375) (xy 11.729212 -339.994494) (xy 11.729706 -340.011149)
			(xy 11.738326 -340.043323) (xy 11.754981 -340.07217) (xy 11.778535 -340.095723) (xy 11.807382 -340.112376)
			(xy 11.839557 -340.120995) (xy 11.856212 -340.121494) (xy 11.864594 -340.121494) (xy 11.872976 -340.120478)
			(xy 11.902749 -340.117017) (xy 11.962687 -340.116991) (xy 12.022117 -340.12479) (xy 12.080019 -340.140282)
			(xy 12.135403 -340.163202) (xy 12.18732 -340.193156) (xy 12.234882 -340.229632) (xy 12.277275 -340.272006)
			(xy 12.313772 -340.319552) (xy 12.343749 -340.371456) (xy 12.366693 -340.426829) (xy 12.38221 -340.484725)
			(xy 12.390036 -340.54415) (xy 12.390036 -340.604089) (xy 12.38221 -340.663515) (xy 12.366693 -340.72141)
			(xy 12.343749 -340.776784) (xy 12.313772 -340.828688) (xy 12.277275 -340.876234) (xy 12.234882 -340.918608)
			(xy 12.227351 -340.924384) (xy 15.256746 -340.924384) (xy 15.256746 -340.864448) (xy 15.264569 -340.805026)
			(xy 15.280082 -340.747133) (xy 15.303018 -340.69176) (xy 15.332985 -340.639854) (xy 15.369472 -340.592304)
			(xy 15.411852 -340.549924) (xy 15.459402 -340.513437) (xy 15.511308 -340.48347) (xy 15.566681 -340.460534)
			(xy 15.624574 -340.445021) (xy 15.683996 -340.437198) (xy 15.743932 -340.437198) (xy 15.803354 -340.445021)
			(xy 15.861247 -340.460534) (xy 15.91662 -340.48347) (xy 15.968526 -340.513437) (xy 16.016076 -340.549924)
			(xy 16.058456 -340.592304) (xy 16.094943 -340.639854) (xy 16.12491 -340.69176) (xy 16.147846 -340.747133)
			(xy 16.163359 -340.805026) (xy 16.171182 -340.864448) (xy 16.171672 -340.894416) (xy 16.171182 -340.924384)
			(xy 16.163359 -340.983806) (xy 16.147846 -341.041699) (xy 16.12491 -341.097072) (xy 16.094943 -341.148978)
			(xy 16.058456 -341.196528) (xy 16.016076 -341.238908) (xy 15.968526 -341.275395) (xy 15.91662 -341.305362)
			(xy 15.861247 -341.328298) (xy 15.803354 -341.343811) (xy 15.743932 -341.351634) (xy 15.683996 -341.351634)
			(xy 15.624574 -341.343811) (xy 15.566681 -341.328298) (xy 15.511308 -341.305362) (xy 15.459402 -341.275395)
			(xy 15.411852 -341.238908) (xy 15.369472 -341.196528) (xy 15.332985 -341.148978) (xy 15.303018 -341.097072)
			(xy 15.280082 -341.041699) (xy 15.264569 -340.983806) (xy 15.256746 -340.924384) (xy 12.227351 -340.924384)
			(xy 12.18732 -340.955084) (xy 12.135403 -340.985038) (xy 12.080019 -341.007958) (xy 12.022117 -341.02345)
			(xy 11.962688 -341.031249) (xy 11.902749 -341.031223) (xy 11.872976 -341.027766) (xy 11.864594 -341.02675)
			(xy 11.856212 -341.02675) (xy 11.839559 -341.027243) (xy 11.807387 -341.035863) (xy 11.778543 -341.052519)
			(xy 11.754995 -341.076074) (xy 11.738349 -341.104922) (xy 11.729738 -341.137096) (xy 11.729212 -341.15375)
			(xy 11.729212 -341.264494) (xy 11.729706 -341.281149) (xy 11.738326 -341.313323) (xy 11.754981 -341.34217)
			(xy 11.778535 -341.365723) (xy 11.807382 -341.382376) (xy 11.839557 -341.390995) (xy 11.856212 -341.391494)
			(xy 11.864594 -341.391494) (xy 11.872976 -341.390478) (xy 11.893322 -341.387984) (xy 11.934278 -341.386201)
			(xy 11.954764 -341.386922) (xy 11.985486 -341.388873) (xy 12.046032 -341.399991) (xy 12.104541 -341.419127)
			(xy 12.159956 -341.445934) (xy 12.211277 -341.479929) (xy 12.257577 -341.520497) (xy 12.298021 -341.566907)
			(xy 12.331876 -341.618319) (xy 12.358534 -341.673807) (xy 12.377512 -341.732367) (xy 12.388467 -341.792943)
			(xy 12.391202 -341.854441) (xy 12.385667 -341.915751) (xy 12.371963 -341.975765) (xy 12.350336 -342.033399)
			(xy 12.336272 -342.060784) (xy 12.336272 -342.061038) (xy 12.329033 -342.0756) (xy 12.321419 -342.107205)
			(xy 12.322023 -342.139708) (xy 12.330806 -342.171008) (xy 12.347201 -342.199081) (xy 12.35837 -342.210898)
			(xy 14.04239 -343.894918) (xy 14.04239 -371.823488)
		)
		(stroke
			(width 0)
			(type solid)
		)
		(fill yes)
		(layer "B.Cu")
		(net "GND")
	)
	(gr_poly
		(pts
			(xy 101.000052 -528.47494) (xy 101.031153 -528.474456) (xy 101.092824 -528.466343) (xy 101.152907 -528.450248)
			(xy 101.210376 -528.426447) (xy 101.264245 -528.395348) (xy 101.313594 -528.357483) (xy 101.357578 -528.3135)
			(xy 101.395444 -528.264152) (xy 101.426544 -528.210283) (xy 101.450345 -528.152815) (xy 101.466441 -528.092731)
			(xy 101.474556 -528.031061) (xy 101.475032 -527.99996) (xy 101.475032 -219.137484) (xy 101.47453 -219.114453)
			(xy 101.466224 -219.069147) (xy 101.449888 -219.026081) (xy 101.426055 -218.986664) (xy 101.395508 -218.95219)
			(xy 101.359247 -218.923786) (xy 101.318459 -218.902385) (xy 101.274482 -218.888686) (xy 101.228756 -218.883139)
			(xy 101.18278 -218.885926) (xy 101.138058 -218.896955) (xy 101.096057 -218.915864) (xy 101.058154 -218.942035)
			(xy 101.041454 -218.957906) (xy 98.392996 -221.606364) (xy 98.392996 -281.150822) (xy 99.57562 -282.333446)
			(xy 99.57562 -291.008562) (xy 93.838268 -296.745914) (xy 93.829466 -296.756393) (xy 93.816122 -296.78028)
			(xy 93.808206 -296.806472) (xy 93.806772 -296.820082) (xy 93.806772 -299.709582) (xy 97.794046 -299.709582)
			(xy 97.794046 -299.649646) (xy 97.801869 -299.590224) (xy 97.817382 -299.532331) (xy 97.840318 -299.476958)
			(xy 97.870285 -299.425052) (xy 97.906772 -299.377502) (xy 97.949152 -299.335122) (xy 97.996702 -299.298635)
			(xy 98.048608 -299.268668) (xy 98.103981 -299.245732) (xy 98.161874 -299.230219) (xy 98.221296 -299.222396)
			(xy 98.281232 -299.222396) (xy 98.340654 -299.230219) (xy 98.398547 -299.245732) (xy 98.45392 -299.268668)
			(xy 98.505826 -299.298635) (xy 98.553376 -299.335122) (xy 98.595756 -299.377502) (xy 98.632243 -299.425052)
			(xy 98.66221 -299.476958) (xy 98.685146 -299.532331) (xy 98.700659 -299.590224) (xy 98.708482 -299.649646)
			(xy 98.708972 -299.679614) (xy 98.708482 -299.709582) (xy 98.700659 -299.769004) (xy 98.685146 -299.826897)
			(xy 98.66221 -299.88227) (xy 98.632243 -299.934176) (xy 98.595756 -299.981726) (xy 98.553376 -300.024106)
			(xy 98.505826 -300.060593) (xy 98.45392 -300.09056) (xy 98.398547 -300.113496) (xy 98.340654 -300.129009)
			(xy 98.281232 -300.136832) (xy 98.221296 -300.136832) (xy 98.161874 -300.129009) (xy 98.103981 -300.113496)
			(xy 98.048608 -300.09056) (xy 97.996702 -300.060593) (xy 97.949152 -300.024106) (xy 97.906772 -299.981726)
			(xy 97.870285 -299.934176) (xy 97.840318 -299.88227) (xy 97.817382 -299.826897) (xy 97.801869 -299.769004)
			(xy 97.794046 -299.709582) (xy 93.806772 -299.709582) (xy 93.806772 -300.800512) (xy 96.894886 -300.800512)
			(xy 96.894886 -300.740576) (xy 96.902709 -300.681154) (xy 96.918222 -300.623261) (xy 96.941158 -300.567888)
			(xy 96.971125 -300.515982) (xy 97.007612 -300.468432) (xy 97.049992 -300.426052) (xy 97.097542 -300.389565)
			(xy 97.149448 -300.359598) (xy 97.204821 -300.336662) (xy 97.262714 -300.321149) (xy 97.322136 -300.313326)
			(xy 97.382072 -300.313326) (xy 97.441494 -300.321149) (xy 97.499387 -300.336662) (xy 97.55476 -300.359598)
			(xy 97.606666 -300.389565) (xy 97.654216 -300.426052) (xy 97.696596 -300.468432) (xy 97.733083 -300.515982)
			(xy 97.76305 -300.567888) (xy 97.785986 -300.623261) (xy 97.801499 -300.681154) (xy 97.809322 -300.740576)
			(xy 97.809812 -300.770544) (xy 97.809322 -300.800512) (xy 97.801499 -300.859934) (xy 97.785986 -300.917827)
			(xy 97.76305 -300.9732) (xy 97.733083 -301.025106) (xy 97.696596 -301.072656) (xy 97.654216 -301.115036)
			(xy 97.606666 -301.151523) (xy 97.55476 -301.18149) (xy 97.499387 -301.204426) (xy 97.441494 -301.219939)
			(xy 97.382072 -301.227762) (xy 97.322136 -301.227762) (xy 97.262714 -301.219939) (xy 97.204821 -301.204426)
			(xy 97.149448 -301.18149) (xy 97.097542 -301.151523) (xy 97.049992 -301.115036) (xy 97.007612 -301.072656)
			(xy 96.971125 -301.025106) (xy 96.941158 -300.9732) (xy 96.918222 -300.917827) (xy 96.902709 -300.859934)
			(xy 96.894886 -300.800512) (xy 93.806772 -300.800512) (xy 93.806772 -302.23358) (xy 95.893872 -302.23358)
			(xy 95.893872 -302.173644) (xy 95.901695 -302.114222) (xy 95.917208 -302.056329) (xy 95.940144 -302.000956)
			(xy 95.970111 -301.94905) (xy 96.006598 -301.9015) (xy 96.048978 -301.85912) (xy 96.096528 -301.822633)
			(xy 96.148434 -301.792666) (xy 96.203807 -301.76973) (xy 96.2617 -301.754217) (xy 96.321122 -301.746394)
			(xy 96.381058 -301.746394) (xy 96.44048 -301.754217) (xy 96.498373 -301.76973) (xy 96.553746 -301.792666)
			(xy 96.605652 -301.822633) (xy 96.653202 -301.85912) (xy 96.695582 -301.9015) (xy 96.732069 -301.94905)
			(xy 96.762036 -302.000956) (xy 96.784972 -302.056329) (xy 96.800485 -302.114222) (xy 96.808308 -302.173644)
			(xy 96.808798 -302.203612) (xy 96.808308 -302.23358) (xy 96.800485 -302.293002) (xy 96.784972 -302.350895)
			(xy 96.762036 -302.406268) (xy 96.732069 -302.458174) (xy 96.695582 -302.505724) (xy 96.653202 -302.548104)
			(xy 96.605652 -302.584591) (xy 96.553746 -302.614558) (xy 96.498373 -302.637494) (xy 96.44048 -302.653007)
			(xy 96.381058 -302.66083) (xy 96.321122 -302.66083) (xy 96.2617 -302.653007) (xy 96.203807 -302.637494)
			(xy 96.148434 -302.614558) (xy 96.096528 -302.584591) (xy 96.048978 -302.548104) (xy 96.006598 -302.505724)
			(xy 95.970111 -302.458174) (xy 95.940144 -302.406268) (xy 95.917208 -302.350895) (xy 95.901695 -302.293002)
			(xy 95.893872 -302.23358) (xy 93.806772 -302.23358) (xy 93.806772 -303.559714) (xy 95.16667 -303.559714)
			(xy 95.16667 -303.499778) (xy 95.174493 -303.440356) (xy 95.190006 -303.382463) (xy 95.212942 -303.32709)
			(xy 95.242909 -303.275184) (xy 95.279396 -303.227634) (xy 95.321776 -303.185254) (xy 95.369326 -303.148767)
			(xy 95.421232 -303.1188) (xy 95.476605 -303.095864) (xy 95.534498 -303.080351) (xy 95.59392 -303.072528)
			(xy 95.653856 -303.072528) (xy 95.713278 -303.080351) (xy 95.771171 -303.095864) (xy 95.826544 -303.1188)
			(xy 95.87845 -303.148767) (xy 95.926 -303.185254) (xy 95.96838 -303.227634) (xy 96.004867 -303.275184)
			(xy 96.034834 -303.32709) (xy 96.05777 -303.382463) (xy 96.073283 -303.440356) (xy 96.081106 -303.499778)
			(xy 96.081596 -303.529746) (xy 96.081106 -303.559714) (xy 96.073283 -303.619136) (xy 96.05777 -303.677029)
			(xy 96.034834 -303.732402) (xy 96.004867 -303.784308) (xy 95.96838 -303.831858) (xy 95.926 -303.874238)
			(xy 95.87845 -303.910725) (xy 95.826544 -303.940692) (xy 95.771171 -303.963628) (xy 95.713278 -303.979141)
			(xy 95.653856 -303.986964) (xy 95.59392 -303.986964) (xy 95.534498 -303.979141) (xy 95.476605 -303.963628)
			(xy 95.421232 -303.940692) (xy 95.369326 -303.910725) (xy 95.321776 -303.874238) (xy 95.279396 -303.831858)
			(xy 95.242909 -303.784308) (xy 95.212942 -303.732402) (xy 95.190006 -303.677029) (xy 95.174493 -303.619136)
			(xy 95.16667 -303.559714) (xy 93.806772 -303.559714) (xy 93.806772 -304.821586) (xy 94.455978 -304.821586)
			(xy 94.455978 -304.76165) (xy 94.463801 -304.702228) (xy 94.479314 -304.644335) (xy 94.50225 -304.588962)
			(xy 94.532217 -304.537056) (xy 94.568704 -304.489506) (xy 94.611084 -304.447126) (xy 94.658634 -304.410639)
			(xy 94.71054 -304.380672) (xy 94.765913 -304.357736) (xy 94.823806 -304.342223) (xy 94.883228 -304.3344)
			(xy 94.943164 -304.3344) (xy 95.002586 -304.342223) (xy 95.060479 -304.357736) (xy 95.115852 -304.380672)
			(xy 95.167758 -304.410639) (xy 95.215308 -304.447126) (xy 95.257688 -304.489506) (xy 95.294175 -304.537056)
			(xy 95.324142 -304.588962) (xy 95.347078 -304.644335) (xy 95.362591 -304.702228) (xy 95.370414 -304.76165)
			(xy 95.370904 -304.791618) (xy 95.370414 -304.821586) (xy 95.362591 -304.881008) (xy 95.347078 -304.938901)
			(xy 95.324142 -304.994274) (xy 95.294175 -305.04618) (xy 95.257688 -305.09373) (xy 95.215308 -305.13611)
			(xy 95.167758 -305.172597) (xy 95.115852 -305.202564) (xy 95.060479 -305.2255) (xy 95.002586 -305.241013)
			(xy 94.943164 -305.248836) (xy 94.883228 -305.248836) (xy 94.823806 -305.241013) (xy 94.765913 -305.2255)
			(xy 94.71054 -305.202564) (xy 94.658634 -305.172597) (xy 94.611084 -305.13611) (xy 94.568704 -305.09373)
			(xy 94.532217 -305.04618) (xy 94.50225 -304.994274) (xy 94.479314 -304.938901) (xy 94.463801 -304.881008)
			(xy 94.455978 -304.821586) (xy 93.806772 -304.821586) (xy 93.806772 -305.3715) (xy 93.808517 -305.394105)
			(xy 93.819002 -305.438209) (xy 93.837142 -305.479755) (xy 93.862361 -305.517426) (xy 93.893861 -305.550027)
			(xy 93.930643 -305.576526) (xy 93.971541 -305.596082) (xy 94.015259 -305.608076) (xy 94.060411 -305.612127)
			(xy 94.105566 -305.608108) (xy 94.149292 -305.596144) (xy 94.169992 -305.586892) (xy 94.197975 -305.574116)
			(xy 94.256556 -305.555342) (xy 94.317123 -305.544583) (xy 94.378585 -305.542034) (xy 94.439835 -305.54774)
			(xy 94.499769 -305.561599) (xy 94.557307 -305.583361) (xy 94.61141 -305.612635) (xy 94.661106 -305.648891)
			(xy 94.705497 -305.691477) (xy 94.743784 -305.739625) (xy 94.775276 -305.792468) (xy 94.799407 -305.849053)
			(xy 94.815741 -305.90836) (xy 94.823983 -305.969321) (xy 94.823986 -306.030836) (xy 94.815749 -306.091798)
			(xy 94.799421 -306.151106) (xy 94.775296 -306.207694) (xy 94.743808 -306.260539) (xy 94.705526 -306.308691)
			(xy 94.661139 -306.351282) (xy 94.611447 -306.387542) (xy 94.557346 -306.416821) (xy 94.49981 -306.438588)
			(xy 94.439878 -306.452453) (xy 94.378628 -306.458165) (xy 94.317166 -306.455622) (xy 94.256597 -306.444869)
			(xy 94.198015 -306.426099) (xy 94.169992 -306.413408) (xy 94.149319 -306.404088) (xy 94.105585 -306.392117)
			(xy 94.060422 -306.388093) (xy 94.01526 -306.392145) (xy 93.971534 -306.404143) (xy 93.930629 -306.423707)
			(xy 93.893843 -306.450216) (xy 93.862343 -306.48283) (xy 93.837128 -306.520514) (xy 93.818996 -306.562074)
			(xy 93.808525 -306.606191) (xy 93.806772 -306.6288) (xy 93.806772 -307.081174) (xy 93.80731 -307.097792)
			(xy 93.815901 -307.129897) (xy 93.832505 -307.158687) (xy 93.843856 -307.170836) (xy 99.801172 -313.127898)
			(xy 99.801172 -339.637624) (xy 100.010468 -339.84692) (xy 100.176584 -340.01329) (xy 100.176584 -346.03436)
			(xy 100.176161 -346.070791) (xy 100.169211 -346.14332) (xy 100.155372 -346.214855) (xy 100.134769 -346.284743)
			(xy 100.107591 -346.352346) (xy 100.074085 -346.417047) (xy 100.054664 -346.447872) (xy 100.032242 -346.481659)
			(xy 99.981314 -346.544765) (xy 99.923973 -346.602106) (xy 99.860868 -346.653036) (xy 99.82708 -346.675456)
			(xy 99.796063 -346.694907) (xy 99.730984 -346.728454) (xy 99.662988 -346.755609) (xy 99.592704 -346.776123)
			(xy 99.556824 -346.783406) (xy 99.521104 -346.789752) (xy 99.448858 -346.796425) (xy 99.376305 -346.796194)
			(xy 99.340162 -346.793058) (xy 99.334066 -346.79255) (xy 99.267518 -346.79255) (xy 98.851212 -347.208856)
			(xy 98.851212 -349.512128) (xy 98.912172 -349.573088) (xy 98.912172 -349.706692) (xy 98.929444 -349.736156)
			(xy 98.943668 -349.762826) (xy 98.948979 -349.77376) (xy 98.958507 -349.796127) (xy 98.962718 -349.80753)
			(xy 98.966528 -349.818198) (xy 98.976769 -349.851362) (xy 98.98775 -349.919893) (xy 98.988372 -349.954596)
			(xy 98.988372 -350.429322) (xy 98.988764 -350.443491) (xy 98.995036 -350.471125) (xy 99.007265 -350.496688)
			(xy 99.024845 -350.518914) (xy 99.035616 -350.528128) (xy 99.064666 -350.552219) (xy 99.118367 -350.605251)
			(xy 99.166565 -350.66333) (xy 99.208789 -350.725887) (xy 99.244625 -350.79231) (xy 99.273723 -350.861949)
			(xy 99.295797 -350.934122) (xy 99.310632 -351.008123) (xy 99.318083 -351.083227) (xy 99.318572 -351.120964)
			(xy 99.318572 -469.817704) (xy 95.265748 -473.870528) (xy 95.265748 -480.632008) (xy 95.867728 -481.233988)
			(xy 95.867728 -482.418136) (xy 95.869036 -482.430295) (xy 95.875689 -482.453825) (xy 95.880936 -482.464872)
			(xy 96.209358 -482.464872) (xy 96.243063 -482.465341) (xy 96.310016 -482.473162) (xy 96.375609 -482.488704)
			(xy 96.438954 -482.511755) (xy 96.499194 -482.542005) (xy 96.555516 -482.579044) (xy 96.607156 -482.622372)
			(xy 96.653416 -482.671402) (xy 96.693672 -482.725471) (xy 96.727377 -482.783848) (xy 96.754078 -482.845744)
			(xy 96.773412 -482.91032) (xy 96.785118 -482.976705) (xy 96.789038 -483.044) (xy 96.785118 -483.111295)
			(xy 96.773412 -483.17768) (xy 96.754078 -483.242256) (xy 96.727377 -483.304152) (xy 96.693672 -483.362529)
			(xy 96.653416 -483.416598) (xy 96.607156 -483.465628) (xy 96.555516 -483.508956) (xy 96.499194 -483.545995)
			(xy 96.438954 -483.576245) (xy 96.375609 -483.599296) (xy 96.310016 -483.614838) (xy 96.243063 -483.622659)
			(xy 96.209358 -483.623112) (xy 95.480124 -483.623112) (xy 95.462765 -483.638631) (xy 95.43347 -483.674816)
			(xy 95.411256 -483.715733) (xy 95.396867 -483.760011) (xy 95.390785 -483.806169) (xy 95.393213 -483.852663)
			(xy 95.404069 -483.897937) (xy 95.422991 -483.940476) (xy 95.449346 -483.978856) (xy 95.465392 -483.99573)
			(xy 95.487744 -484.018082) (xy 95.487744 -484.902764) (xy 94.721934 -485.668574) (xy 92.021406 -485.668574)
			(xy 91.929712 -485.760014) (xy 91.924632 -485.80421) (xy 91.920653 -485.834715) (xy 91.90556 -485.894355)
			(xy 91.882613 -485.951434) (xy 91.852225 -486.004924) (xy 91.814943 -486.05386) (xy 91.771441 -486.097359)
			(xy 91.722503 -486.134638) (xy 91.669012 -486.165024) (xy 91.611931 -486.187968) (xy 91.552291 -486.203057)
			(xy 91.521788 -486.207054) (xy 91.477592 -486.212134) (xy 91.282774 -486.407206) (xy 90.570304 -487.119676)
			(xy 90.570304 -487.28147) (xy 91.836476 -487.28147) (xy 91.836476 -487.221534) (xy 91.844299 -487.162112)
			(xy 91.859812 -487.104219) (xy 91.882748 -487.048846) (xy 91.912715 -486.99694) (xy 91.949202 -486.94939)
			(xy 91.991582 -486.90701) (xy 92.039132 -486.870523) (xy 92.091038 -486.840556) (xy 92.146411 -486.81762)
			(xy 92.204304 -486.802107) (xy 92.263726 -486.794284) (xy 92.323662 -486.794284) (xy 92.383084 -486.802107)
			(xy 92.440977 -486.81762) (xy 92.49635 -486.840556) (xy 92.548256 -486.870523) (xy 92.595806 -486.90701)
			(xy 92.638186 -486.94939) (xy 92.674673 -486.99694) (xy 92.684674 -487.014262) (xy 95.911144 -487.014262)
			(xy 95.911144 -486.954326) (xy 95.918967 -486.894904) (xy 95.93448 -486.837011) (xy 95.957416 -486.781638)
			(xy 95.987383 -486.729732) (xy 96.02387 -486.682182) (xy 96.06625 -486.639802) (xy 96.1138 -486.603315)
			(xy 96.165706 -486.573348) (xy 96.221079 -486.550412) (xy 96.278972 -486.534899) (xy 96.338394 -486.527076)
			(xy 96.39833 -486.527076) (xy 96.457752 -486.534899) (xy 96.515645 -486.550412) (xy 96.571018 -486.573348)
			(xy 96.622924 -486.603315) (xy 96.670474 -486.639802) (xy 96.712854 -486.682182) (xy 96.749341 -486.729732)
			(xy 96.779308 -486.781638) (xy 96.802244 -486.837011) (xy 96.817757 -486.894904) (xy 96.82558 -486.954326)
			(xy 96.82607 -486.984294) (xy 96.82558 -487.014262) (xy 96.817757 -487.073684) (xy 96.802244 -487.131577)
			(xy 96.779308 -487.18695) (xy 96.749341 -487.238856) (xy 96.712854 -487.286406) (xy 96.670474 -487.328786)
			(xy 96.622924 -487.365273) (xy 96.571018 -487.39524) (xy 96.515645 -487.418176) (xy 96.457752 -487.433689)
			(xy 96.39833 -487.441512) (xy 96.338394 -487.441512) (xy 96.278972 -487.433689) (xy 96.221079 -487.418176)
			(xy 96.165706 -487.39524) (xy 96.1138 -487.365273) (xy 96.06625 -487.328786) (xy 96.02387 -487.286406)
			(xy 95.987383 -487.238856) (xy 95.957416 -487.18695) (xy 95.93448 -487.131577) (xy 95.918967 -487.073684)
			(xy 95.911144 -487.014262) (xy 92.684674 -487.014262) (xy 92.70464 -487.048846) (xy 92.727576 -487.104219)
			(xy 92.743089 -487.162112) (xy 92.750912 -487.221534) (xy 92.751402 -487.251502) (xy 92.750912 -487.28147)
			(xy 92.743089 -487.340892) (xy 92.727576 -487.398785) (xy 92.70464 -487.454158) (xy 92.674673 -487.506064)
			(xy 92.665752 -487.51769) (xy 94.735632 -487.51769) (xy 94.735632 -487.457754) (xy 94.743455 -487.398332)
			(xy 94.758968 -487.340439) (xy 94.781904 -487.285066) (xy 94.811871 -487.23316) (xy 94.848358 -487.18561)
			(xy 94.890738 -487.14323) (xy 94.938288 -487.106743) (xy 94.990194 -487.076776) (xy 95.045567 -487.05384)
			(xy 95.10346 -487.038327) (xy 95.162882 -487.030504) (xy 95.222818 -487.030504) (xy 95.28224 -487.038327)
			(xy 95.340133 -487.05384) (xy 95.395506 -487.076776) (xy 95.447412 -487.106743) (xy 95.494962 -487.14323)
			(xy 95.537342 -487.18561) (xy 95.573829 -487.23316) (xy 95.603796 -487.285066) (xy 95.626732 -487.340439)
			(xy 95.642245 -487.398332) (xy 95.650068 -487.457754) (xy 95.650558 -487.487722) (xy 95.650068 -487.51769)
			(xy 95.642245 -487.577112) (xy 95.626732 -487.635005) (xy 95.603796 -487.690378) (xy 95.573829 -487.742284)
			(xy 95.537342 -487.789834) (xy 95.494962 -487.832214) (xy 95.447412 -487.868701) (xy 95.395506 -487.898668)
			(xy 95.340133 -487.921604) (xy 95.28224 -487.937117) (xy 95.222818 -487.94494) (xy 95.162882 -487.94494)
			(xy 95.10346 -487.937117) (xy 95.045567 -487.921604) (xy 94.990194 -487.898668) (xy 94.938288 -487.868701)
			(xy 94.890738 -487.832214) (xy 94.848358 -487.789834) (xy 94.811871 -487.742284) (xy 94.781904 -487.690378)
			(xy 94.758968 -487.635005) (xy 94.743455 -487.577112) (xy 94.735632 -487.51769) (xy 92.665752 -487.51769)
			(xy 92.638186 -487.553614) (xy 92.595806 -487.595994) (xy 92.548256 -487.632481) (xy 92.49635 -487.662448)
			(xy 92.440977 -487.685384) (xy 92.383084 -487.700897) (xy 92.323662 -487.70872) (xy 92.263726 -487.70872)
			(xy 92.204304 -487.700897) (xy 92.146411 -487.685384) (xy 92.091038 -487.662448) (xy 92.039132 -487.632481)
			(xy 91.991582 -487.595994) (xy 91.949202 -487.553614) (xy 91.912715 -487.506064) (xy 91.882748 -487.454158)
			(xy 91.859812 -487.398785) (xy 91.844299 -487.340892) (xy 91.836476 -487.28147) (xy 90.570304 -487.28147)
			(xy 90.570304 -487.360468) (xy 90.570795 -487.377125) (xy 90.579411 -487.409306) (xy 90.596063 -487.43816)
			(xy 90.619618 -487.46172) (xy 90.648468 -487.478379) (xy 90.680647 -487.487002) (xy 90.697304 -487.487468)
			(xy 90.734388 -487.487468) (xy 90.765884 -487.467402) (xy 90.791541 -487.451535) (xy 90.846171 -487.425948)
			(xy 90.903689 -487.407762) (xy 90.9631 -487.397293) (xy 90.993214 -487.39552) (xy 91.015243 -487.394805)
			(xy 91.059261 -487.3971) (xy 91.081098 -487.400092) (xy 91.110201 -487.404948) (xy 91.166929 -487.421176)
			(xy 91.221101 -487.444559) (xy 91.27182 -487.474709) (xy 91.318244 -487.511127) (xy 91.359603 -487.553208)
			(xy 91.395213 -487.600254) (xy 91.424481 -487.651487) (xy 91.446924 -487.706055) (xy 91.462169 -487.763055)
			(xy 91.469962 -487.821542) (xy 91.470176 -487.880545) (xy 91.466924 -487.90987) (xy 91.46267 -487.939761)
			(xy 91.447312 -487.998151) (xy 91.424414 -488.054017) (xy 91.394373 -488.106389) (xy 91.35771 -488.154359)
			(xy 91.315061 -488.197095) (xy 91.267166 -488.233856) (xy 91.214855 -488.264003) (xy 91.159036 -488.287015)
			(xy 91.100677 -488.302491) (xy 91.04079 -488.310164) (xy 90.980415 -488.309901) (xy 90.920597 -488.301705)
			(xy 90.89136 -488.294172) (xy 90.868695 -488.288518) (xy 90.822149 -488.284626) (xy 90.775676 -488.289304)
			(xy 90.73084 -488.302393) (xy 90.68915 -488.323453) (xy 90.652009 -488.351775) (xy 90.620667 -488.386406)
			(xy 90.596179 -488.42618) (xy 90.579371 -488.469759) (xy 90.570806 -488.515674) (xy 90.570304 -488.539028)
			(xy 90.570304 -488.588554) (xy 91.849176 -488.588554) (xy 91.849176 -488.528618) (xy 91.856999 -488.469196)
			(xy 91.872512 -488.411303) (xy 91.895448 -488.35593) (xy 91.925415 -488.304024) (xy 91.961902 -488.256474)
			(xy 92.004282 -488.214094) (xy 92.051832 -488.177607) (xy 92.103738 -488.14764) (xy 92.159111 -488.124704)
			(xy 92.217004 -488.109191) (xy 92.276426 -488.101368) (xy 92.336362 -488.101368) (xy 92.395784 -488.109191)
			(xy 92.453677 -488.124704) (xy 92.50905 -488.14764) (xy 92.540675 -488.165898) (xy 93.458774 -488.165898)
			(xy 93.458774 -488.105962) (xy 93.466597 -488.04654) (xy 93.48211 -487.988647) (xy 93.505046 -487.933274)
			(xy 93.535013 -487.881368) (xy 93.5715 -487.833818) (xy 93.61388 -487.791438) (xy 93.66143 -487.754951)
			(xy 93.713336 -487.724984) (xy 93.768709 -487.702048) (xy 93.826602 -487.686535) (xy 93.886024 -487.678712)
			(xy 93.94596 -487.678712) (xy 94.005382 -487.686535) (xy 94.063275 -487.702048) (xy 94.118648 -487.724984)
			(xy 94.170554 -487.754951) (xy 94.218104 -487.791438) (xy 94.260484 -487.833818) (xy 94.296971 -487.881368)
			(xy 94.326938 -487.933274) (xy 94.349874 -487.988647) (xy 94.365387 -488.04654) (xy 94.37321 -488.105962)
			(xy 94.3737 -488.13593) (xy 94.37321 -488.165898) (xy 94.365387 -488.22532) (xy 94.349874 -488.283213)
			(xy 94.326938 -488.338586) (xy 94.296971 -488.390492) (xy 94.260484 -488.438042) (xy 94.218104 -488.480422)
			(xy 94.170554 -488.516909) (xy 94.118648 -488.546876) (xy 94.063275 -488.569812) (xy 94.005382 -488.585325)
			(xy 93.94596 -488.593148) (xy 93.886024 -488.593148) (xy 93.826602 -488.585325) (xy 93.768709 -488.569812)
			(xy 93.713336 -488.546876) (xy 93.66143 -488.516909) (xy 93.61388 -488.480422) (xy 93.5715 -488.438042)
			(xy 93.535013 -488.390492) (xy 93.505046 -488.338586) (xy 93.48211 -488.283213) (xy 93.466597 -488.22532)
			(xy 93.458774 -488.165898) (xy 92.540675 -488.165898) (xy 92.560956 -488.177607) (xy 92.608506 -488.214094)
			(xy 92.650886 -488.256474) (xy 92.687373 -488.304024) (xy 92.71734 -488.35593) (xy 92.740276 -488.411303)
			(xy 92.755789 -488.469196) (xy 92.763612 -488.528618) (xy 92.764102 -488.558586) (xy 92.763612 -488.588554)
			(xy 92.755789 -488.647976) (xy 92.740276 -488.705869) (xy 92.71734 -488.761242) (xy 92.687373 -488.813148)
			(xy 92.650886 -488.860698) (xy 92.608506 -488.903078) (xy 92.560956 -488.939565) (xy 92.50905 -488.969532)
			(xy 92.453677 -488.992468) (xy 92.395784 -489.007981) (xy 92.336362 -489.015804) (xy 92.276426 -489.015804)
			(xy 92.217004 -489.007981) (xy 92.159111 -488.992468) (xy 92.103738 -488.969532) (xy 92.051832 -488.939565)
			(xy 92.004282 -488.903078) (xy 91.961902 -488.860698) (xy 91.925415 -488.813148) (xy 91.895448 -488.761242)
			(xy 91.872512 -488.705869) (xy 91.856999 -488.647976) (xy 91.849176 -488.588554) (xy 90.570304 -488.588554)
			(xy 90.570304 -493.30229) (xy 90.376502 -493.496092) (xy 90.180668 -493.691672) (xy 90.169806 -493.703166)
			(xy 90.153592 -493.730305) (xy 90.144567 -493.760604) (xy 90.14329 -493.792193) (xy 90.146124 -493.80775)
			(xy 90.146124 -493.808004) (xy 90.153379 -493.844642) (xy 90.161079 -493.918936) (xy 90.161019 -493.95507)
			(xy 91.277697 -493.95507) (xy 91.281732 -493.879366) (xy 91.293791 -493.804521) (xy 91.313737 -493.73138)
			(xy 91.341344 -493.660775) (xy 91.3763 -493.593504) (xy 91.418208 -493.530329) (xy 91.466594 -493.471967)
			(xy 91.52091 -493.419079) (xy 91.580539 -493.372264) (xy 91.644807 -493.332052) (xy 91.712984 -493.2989)
			(xy 91.7843 -493.273182) (xy 91.857945 -493.25519) (xy 91.933085 -493.245128) (xy 92.008869 -493.243109)
			(xy 92.084439 -493.249158) (xy 92.158937 -493.263205) (xy 92.23152 -493.285091) (xy 92.301366 -493.314568)
			(xy 92.367683 -493.351303) (xy 92.429719 -493.394878) (xy 92.486772 -493.4448) (xy 92.538196 -493.500504)
			(xy 92.583407 -493.561359) (xy 92.621894 -493.626674) (xy 92.65322 -493.69571) (xy 92.67703 -493.767685)
			(xy 92.693055 -493.841783) (xy 92.701114 -493.917164) (xy 92.701618 -493.95507) (xy 92.701114 -493.992976)
			(xy 92.693055 -494.068357) (xy 92.67703 -494.142455) (xy 92.65322 -494.21443) (xy 92.621894 -494.283466)
			(xy 92.583407 -494.348781) (xy 92.538196 -494.409636) (xy 92.486772 -494.46534) (xy 92.429719 -494.515262)
			(xy 92.367683 -494.558837) (xy 92.301366 -494.595572) (xy 92.23152 -494.625049) (xy 92.158937 -494.646935)
			(xy 92.084439 -494.660982) (xy 92.008869 -494.667031) (xy 91.933085 -494.665012) (xy 91.857945 -494.65495)
			(xy 91.7843 -494.636958) (xy 91.712984 -494.61124) (xy 91.644807 -494.578088) (xy 91.580539 -494.537876)
			(xy 91.52091 -494.491061) (xy 91.466594 -494.438173) (xy 91.418208 -494.379811) (xy 91.3763 -494.316636)
			(xy 91.341344 -494.249365) (xy 91.313737 -494.17876) (xy 91.293791 -494.105619) (xy 91.281732 -494.030774)
			(xy 91.277697 -493.95507) (xy 90.161019 -493.95507) (xy 90.160955 -493.993628) (xy 90.153008 -494.067896)
			(xy 90.137325 -494.140924) (xy 90.11408 -494.211906) (xy 90.083527 -494.280064) (xy 90.046002 -494.344646)
			(xy 90.00192 -494.404942) (xy 89.951764 -494.46029) (xy 89.896087 -494.510079) (xy 89.8355 -494.553762)
			(xy 89.770672 -494.590859) (xy 89.736676 -494.606326) (xy 89.704926 -494.619534) (xy 89.68411 -494.628243)
			(xy 89.645694 -494.651904) (xy 89.612059 -494.681976) (xy 89.584259 -494.717512) (xy 89.563168 -494.757397)
			(xy 89.549449 -494.800379) (xy 89.543532 -494.845107) (xy 89.545604 -494.890178) (xy 89.555598 -494.934175)
			(xy 89.573202 -494.975717) (xy 89.597862 -495.0135) (xy 89.612978 -495.030252) (xy 89.644728 -495.062002)
			(xy 89.661481 -495.077121) (xy 89.699264 -495.101786) (xy 89.740807 -495.119394) (xy 89.784807 -495.129393)
			(xy 89.829881 -495.131466) (xy 89.874613 -495.125551) (xy 89.917598 -495.111832) (xy 89.957486 -495.09074)
			(xy 89.993025 -495.062939) (xy 90.023098 -495.0293) (xy 90.04676 -494.990881) (xy 90.055446 -494.970054)
			(xy 90.061434 -494.954679) (xy 90.074647 -494.924441) (xy 90.081862 -494.909602) (xy 90.098792 -494.876434)
			(xy 90.138571 -494.813477) (xy 90.184706 -494.755018) (xy 90.236694 -494.701695) (xy 90.293964 -494.654092)
			(xy 90.355892 -494.612729) (xy 90.4218 -494.578057) (xy 90.490968 -494.550457) (xy 90.56264 -494.53023)
			(xy 90.636032 -494.517597) (xy 90.710341 -494.512695) (xy 90.784757 -494.51558) (xy 90.858464 -494.526218)
			(xy 90.930658 -494.544494) (xy 91.000549 -494.570209) (xy 91.067373 -494.60308) (xy 91.1304 -494.642748)
			(xy 91.18894 -494.688781) (xy 91.242354 -494.740674) (xy 91.290058 -494.797861) (xy 91.33153 -494.859716)
			(xy 91.366317 -494.925563) (xy 91.394039 -494.994683) (xy 91.414392 -495.066319) (xy 91.427155 -495.139688)
			(xy 91.430094 -495.17681) (xy 91.432202 -495.215075) (xy 91.429189 -495.291655) (xy 91.417963 -495.367467)
			(xy 91.398657 -495.441634) (xy 91.371492 -495.513297) (xy 91.336784 -495.581627) (xy 91.294934 -495.645831)
			(xy 91.246428 -495.705166) (xy 91.191826 -495.758945) (xy 91.131762 -495.806546) (xy 91.066931 -495.847417)
			(xy 90.998083 -495.881084) (xy 90.926016 -495.907159) (xy 90.851564 -495.925338) (xy 90.77559 -495.935412)
			(xy 90.698974 -495.937264) (xy 90.622602 -495.930872) (xy 90.547359 -495.91631) (xy 90.474116 -495.893748)
			(xy 90.403722 -495.863445) (xy 90.336992 -495.825754) (xy 90.274699 -495.78111) (xy 90.217563 -495.730032)
			(xy 90.166247 -495.673109) (xy 90.14333 -495.642392) (xy 90.124056 -495.615099) (xy 90.09014 -495.557524)
			(xy 90.061774 -495.497023) (xy 90.039207 -495.434127) (xy 90.030554 -495.401854) (xy 90.030554 -495.4016)
			(xy 90.025864 -495.385498) (xy 90.009304 -495.356347) (xy 89.985723 -495.332516) (xy 89.956749 -495.315649)
			(xy 89.924381 -495.306912) (xy 89.907618 -495.30635) (xy 89.907364 -495.30635) (xy 89.890715 -495.306849)
			(xy 89.858553 -495.315477) (xy 89.829721 -495.332136) (xy 89.806183 -495.355689) (xy 89.789544 -495.384533)
			(xy 89.780938 -495.4167) (xy 89.780364 -495.43335) (xy 89.780364 -495.792252) (xy 89.780846 -495.808043)
			(xy 89.788613 -495.838655) (xy 89.803658 -495.866423) (xy 89.82506 -495.889647) (xy 89.838022 -495.898678)
			(xy 89.869627 -495.919834) (xy 89.928586 -495.967882) (xy 89.982085 -496.021944) (xy 90.029512 -496.081404)
			(xy 90.070327 -496.145583) (xy 90.104063 -496.213749) (xy 90.130337 -496.285124) (xy 90.148848 -496.358895)
			(xy 90.159385 -496.43422) (xy 90.161341 -496.49507) (xy 91.277697 -496.49507) (xy 91.281732 -496.419366)
			(xy 91.293791 -496.344521) (xy 91.313737 -496.27138) (xy 91.341344 -496.200775) (xy 91.3763 -496.133504)
			(xy 91.418208 -496.070329) (xy 91.466594 -496.011967) (xy 91.52091 -495.959079) (xy 91.580539 -495.912264)
			(xy 91.644807 -495.872052) (xy 91.712984 -495.8389) (xy 91.7843 -495.813182) (xy 91.857945 -495.79519)
			(xy 91.933085 -495.785128) (xy 92.008869 -495.783109) (xy 92.084439 -495.789158) (xy 92.158937 -495.803205)
			(xy 92.23152 -495.825091) (xy 92.301366 -495.854568) (xy 92.367683 -495.891303) (xy 92.429719 -495.934878)
			(xy 92.486772 -495.9848) (xy 92.538196 -496.040504) (xy 92.583407 -496.101359) (xy 92.621894 -496.166674)
			(xy 92.65322 -496.23571) (xy 92.67703 -496.307685) (xy 92.693055 -496.381783) (xy 92.701114 -496.457164)
			(xy 92.701618 -496.49507) (xy 92.701114 -496.532976) (xy 92.693055 -496.608357) (xy 92.67703 -496.682455)
			(xy 92.65322 -496.75443) (xy 92.621894 -496.823466) (xy 92.583407 -496.888781) (xy 92.538196 -496.949636)
			(xy 92.486772 -497.00534) (xy 92.429719 -497.055262) (xy 92.367683 -497.098837) (xy 92.301366 -497.135572)
			(xy 92.23152 -497.165049) (xy 92.158937 -497.186935) (xy 92.084439 -497.200982) (xy 92.008869 -497.207031)
			(xy 91.933085 -497.205012) (xy 91.857945 -497.19495) (xy 91.7843 -497.176958) (xy 91.712984 -497.15124)
			(xy 91.644807 -497.118088) (xy 91.580539 -497.077876) (xy 91.52091 -497.031061) (xy 91.466594 -496.978173)
			(xy 91.418208 -496.919811) (xy 91.3763 -496.856636) (xy 91.341344 -496.789365) (xy 91.313737 -496.71876)
			(xy 91.293791 -496.645619) (xy 91.281732 -496.570774) (xy 91.277697 -496.49507) (xy 90.161341 -496.49507)
			(xy 90.161829 -496.510238) (xy 90.15615 -496.586084) (xy 90.142414 -496.660891) (xy 90.120777 -496.733806)
			(xy 90.091487 -496.803998) (xy 90.054878 -496.870666) (xy 90.011367 -496.933048) (xy 89.96145 -496.990434)
			(xy 89.905697 -497.042168) (xy 89.844745 -497.087661) (xy 89.779288 -497.126393) (xy 89.710073 -497.157922)
			(xy 89.63789 -497.18189) (xy 89.563563 -497.198022) (xy 89.487939 -497.206134) (xy 89.411881 -497.206134)
			(xy 89.336257 -497.198022) (xy 89.26193 -497.18189) (xy 89.189747 -497.157922) (xy 89.120532 -497.126393)
			(xy 89.055075 -497.087661) (xy 88.994123 -497.042168) (xy 88.93837 -496.990434) (xy 88.888453 -496.933048)
			(xy 88.844942 -496.870666) (xy 88.808333 -496.803998) (xy 88.779043 -496.733806) (xy 88.757406 -496.660891)
			(xy 88.74367 -496.586084) (xy 88.737991 -496.510238) (xy 88.740435 -496.43422) (xy 88.750972 -496.358895)
			(xy 88.769483 -496.285124) (xy 88.795757 -496.213749) (xy 88.829493 -496.145583) (xy 88.870308 -496.081404)
			(xy 88.917735 -496.021944) (xy 88.971234 -495.967882) (xy 89.030193 -495.919834) (xy 89.061798 -495.898678)
			(xy 89.07477 -495.889657) (xy 89.096184 -495.866438) (xy 89.111231 -495.838665) (xy 89.118987 -495.808045)
			(xy 89.119456 -495.792252) (xy 89.119456 -495.472212) (xy 89.073736 -495.425984) (xy 89.061036 -495.413284)
			(xy 89.049351 -495.402244) (xy 89.021683 -495.385897) (xy 88.990809 -495.376978) (xy 88.958685 -495.376053)
			(xy 88.927349 -495.383179) (xy 88.898785 -495.397906) (xy 88.874805 -495.4193) (xy 88.856927 -495.446006)
			(xy 88.851232 -495.461036) (xy 88.838637 -495.495445) (xy 88.80736 -495.561712) (xy 88.76944 -495.624414)
			(xy 88.725277 -495.682888) (xy 88.67534 -495.736514) (xy 88.620157 -495.784725) (xy 88.560312 -495.827011)
			(xy 88.496438 -495.862924) (xy 88.429213 -495.892083) (xy 88.359347 -495.91418) (xy 88.287581 -495.928982)
			(xy 88.214673 -495.93633) (xy 88.141396 -495.936148) (xy 88.068526 -495.928438) (xy 88.03259 -495.921284)
			(xy 87.996853 -495.913269) (xy 87.927118 -495.890873) (xy 87.893398 -495.87658) (xy 87.855461 -495.859243)
			(xy 87.783556 -495.816966) (xy 87.717084 -495.766578) (xy 87.656953 -495.708768) (xy 87.63 -495.676936)
			(xy 87.607131 -495.648364) (xy 87.566717 -495.587348) (xy 87.532775 -495.522507) (xy 87.505662 -495.454527)
			(xy 87.485666 -495.384125) (xy 87.472997 -495.312042) (xy 87.467789 -495.239041) (xy 87.470096 -495.16589)
			(xy 87.474552 -495.129566) (xy 87.48007 -495.092441) (xy 87.497913 -495.019533) (xy 87.523324 -494.948906)
			(xy 87.556021 -494.881342) (xy 87.595641 -494.817591) (xy 87.618316 -494.787682) (xy 87.641593 -494.75862)
			(xy 87.693261 -494.704998) (xy 87.75024 -494.65706) (xy 87.81191 -494.615327) (xy 87.877597 -494.580256)
			(xy 87.946585 -494.552229) (xy 88.01812 -494.531553) (xy 88.054688 -494.524538) (xy 88.069145 -494.521517)
			(xy 88.096233 -494.509765) (xy 88.119889 -494.492096) (xy 88.138845 -494.469457) (xy 88.152083 -494.443064)
			(xy 88.158893 -494.414333) (xy 88.159336 -494.39957) (xy 88.159336 -493.625124) (xy 89.515696 -492.268764)
			(xy 89.515696 -486.527856) (xy 89.48801 -486.493058) (xy 89.472465 -486.472896) (xy 89.445445 -486.429743)
			(xy 89.423365 -486.383866) (xy 89.414604 -486.359962) (xy 89.405764 -486.333556) (xy 89.393824 -486.279163)
			(xy 89.388584 -486.223722) (xy 89.38895 -486.195878) (xy 89.390222 -486.166133) (xy 89.399518 -486.107325)
			(xy 89.416361 -486.05022) (xy 89.440469 -485.995781) (xy 89.471433 -485.944929) (xy 89.50873 -485.898522)
			(xy 89.551731 -485.857344) (xy 89.59971 -485.822091) (xy 89.651855 -485.793357) (xy 89.707286 -485.771629)
			(xy 89.765067 -485.757274) (xy 89.794588 -485.75341) (xy 89.838784 -485.74833) (xy 90.3732 -485.213914)
			(xy 90.3732 -484.86568) (xy 90.371453 -484.849912) (xy 90.361226 -484.819893) (xy 90.343939 -484.793305)
			(xy 90.32065 -484.771778) (xy 90.292786 -484.756631) (xy 90.262056 -484.748793) (xy 90.2462 -484.748332)
			(xy 89.098374 -484.748332) (xy 89.098374 -484.000302) (xy 89.091262 -483.979982) (xy 89.086838 -483.966728)
			(xy 89.07997 -483.939641) (xy 89.077546 -483.92588) (xy 89.07526 -483.909878) (xy 89.07399 -483.895908)
			(xy 89.073228 -483.871524) (xy 89.073228 -482.767132) (xy 89.055956 -482.74986) (xy 89.055956 -481.611178)
			(xy 89.013284 -481.568252) (xy 88.392 -480.946968) (xy 88.392 -476.993204) (xy 88.15705 -476.758254)
			(xy 88.112854 -476.753174) (xy 88.083192 -476.749309) (xy 88.025147 -476.734858) (xy 87.96948 -476.712968)
			(xy 87.917139 -476.684011) (xy 87.869018 -476.648481) (xy 87.825936 -476.606984) (xy 87.788629 -476.560228)
			(xy 87.757732 -476.509009) (xy 87.733772 -476.4542) (xy 87.717157 -476.396737) (xy 87.708172 -476.337599)
			(xy 87.706968 -476.277795) (xy 87.713567 -476.218343) (xy 87.727857 -476.160258) (xy 87.749592 -476.10453)
			(xy 87.778404 -476.052109) (xy 87.8138 -476.00389) (xy 87.834216 -475.98203) (xy 87.834216 -474.735144)
			(xy 84.741512 -471.64244) (xy 84.741512 -458.103732) (xy 88.754204 -454.09104) (xy 88.754204 -454.024746)
			(xy 88.753661 -454.007784) (xy 88.744709 -453.975064) (xy 88.727451 -453.945858) (xy 88.703107 -453.922232)
			(xy 88.673398 -453.905856) (xy 88.640424 -453.897886) (xy 88.606515 -453.898887) (xy 88.574068 -453.908787)
			(xy 88.559386 -453.917304) (xy 88.527598 -453.936763) (xy 88.460732 -453.969698) (xy 88.390791 -453.995464)
			(xy 88.318539 -454.01378) (xy 88.24477 -454.024444) (xy 88.170289 -454.027339) (xy 88.095914 -454.022435)
			(xy 88.022459 -454.009784) (xy 87.950728 -453.989525) (xy 87.881508 -453.961881) (xy 87.815556 -453.927154)
			(xy 87.753594 -453.885724) (xy 87.696301 -453.838045) (xy 87.644306 -453.784639) (xy 87.598177 -453.726092)
			(xy 87.57793 -453.6948) (xy 87.556781 -453.660184) (xy 87.521588 -453.587094) (xy 87.494925 -453.510479)
			(xy 87.477136 -453.431331) (xy 87.468453 -453.350675) (xy 87.468987 -453.269555) (xy 87.473282 -453.229218)
			(xy 87.478576 -453.190332) (xy 87.496601 -453.113948) (xy 87.522913 -453.040009) (xy 87.557195 -452.96941)
			(xy 87.599029 -452.903008) (xy 87.64791 -452.841607) (xy 87.703245 -452.785952) (xy 87.764363 -452.736718)
			(xy 87.797132 -452.715122) (xy 87.831829 -452.693657) (xy 87.905183 -452.657928) (xy 87.982142 -452.630825)
			(xy 88.061696 -452.612705) (xy 88.102186 -452.60768) (xy 88.1507 -452.602346) (xy 88.215216 -452.53021)
			(xy 88.215216 -451.55993) (xy 88.1507 -451.487794) (xy 88.102186 -451.48246) (xy 88.06469 -451.47784)
			(xy 87.990888 -451.461679) (xy 87.919212 -451.43779) (xy 87.850471 -451.406442) (xy 87.785438 -451.367988)
			(xy 87.724845 -451.32286) (xy 87.669373 -451.271567) (xy 87.619649 -451.214685) (xy 87.57623 -451.152856)
			(xy 87.539607 -451.086774) (xy 87.51019 -451.017185) (xy 87.488312 -450.94487) (xy 87.474218 -450.870645)
			(xy 87.468067 -450.795344) (xy 87.469928 -450.719815) (xy 87.479781 -450.644909) (xy 87.497514 -450.571468)
			(xy 87.522928 -450.500319) (xy 87.555737 -450.432263) (xy 87.595571 -450.368066) (xy 87.641983 -450.30845)
			(xy 87.694449 -450.254087) (xy 87.75238 -450.205589) (xy 87.815122 -450.163501) (xy 87.881971 -450.128296)
			(xy 87.952173 -450.100373) (xy 88.024938 -450.080044) (xy 88.099447 -450.067538) (xy 88.174862 -450.062997)
			(xy 88.250334 -450.066471) (xy 88.325013 -450.077921) (xy 88.398059 -450.097218) (xy 88.468649 -450.124146)
			(xy 88.535988 -450.158401) (xy 88.59932 -450.199597) (xy 88.657931 -450.247271) (xy 88.711161 -450.300887)
			(xy 88.758411 -450.35984) (xy 88.79915 -450.423467) (xy 88.832919 -450.491052) (xy 88.859337 -450.561834)
			(xy 88.869266 -450.598286) (xy 88.869266 -450.59854) (xy 88.873958 -450.614643) (xy 88.890519 -450.643797)
			(xy 88.914098 -450.667635) (xy 88.943071 -450.684513) (xy 88.975438 -450.693266) (xy 88.992202 -450.69379)
			(xy 88.992456 -450.69379) (xy 89.009114 -450.693301) (xy 89.041297 -450.684687) (xy 89.070153 -450.668035)
			(xy 89.093714 -450.64448) (xy 89.110374 -450.615629) (xy 89.118996 -450.583448) (xy 89.119456 -450.56679)
			(xy 89.119456 -450.207888) (xy 89.118978 -450.192096) (xy 89.111216 -450.161482) (xy 89.09617 -450.133713)
			(xy 89.074762 -450.110492) (xy 89.061798 -450.101462) (xy 89.030193 -450.080306) (xy 88.971234 -450.032258)
			(xy 88.917735 -449.978196) (xy 88.870308 -449.918736) (xy 88.829493 -449.854557) (xy 88.795757 -449.786391)
			(xy 88.769483 -449.715016) (xy 88.750972 -449.641245) (xy 88.740435 -449.56592) (xy 88.737991 -449.489902)
			(xy 88.74367 -449.414056) (xy 88.757406 -449.339249) (xy 88.779043 -449.266334) (xy 88.808333 -449.196142)
			(xy 88.844942 -449.129474) (xy 88.888453 -449.067092) (xy 88.93837 -449.009706) (xy 88.994123 -448.957972)
			(xy 89.055075 -448.912479) (xy 89.120532 -448.873747) (xy 89.189747 -448.842218) (xy 89.26193 -448.81825)
			(xy 89.336257 -448.802118) (xy 89.411881 -448.794006) (xy 89.487939 -448.794006) (xy 89.563563 -448.802118)
			(xy 89.63789 -448.81825) (xy 89.710073 -448.842218) (xy 89.779288 -448.873747) (xy 89.844745 -448.912479)
			(xy 89.905697 -448.957972) (xy 89.96145 -449.009706) (xy 90.011367 -449.067092) (xy 90.054878 -449.129474)
			(xy 90.091487 -449.196142) (xy 90.120777 -449.266334) (xy 90.142414 -449.339249) (xy 90.15615 -449.414056)
			(xy 90.161829 -449.489902) (xy 90.161341 -449.50507) (xy 91.277697 -449.50507) (xy 91.281732 -449.429366)
			(xy 91.293791 -449.354521) (xy 91.313737 -449.28138) (xy 91.341344 -449.210775) (xy 91.3763 -449.143504)
			(xy 91.418208 -449.080329) (xy 91.466594 -449.021967) (xy 91.52091 -448.969079) (xy 91.580539 -448.922264)
			(xy 91.644807 -448.882052) (xy 91.712984 -448.8489) (xy 91.7843 -448.823182) (xy 91.857945 -448.80519)
			(xy 91.933085 -448.795128) (xy 92.008869 -448.793109) (xy 92.084439 -448.799158) (xy 92.158937 -448.813205)
			(xy 92.23152 -448.835091) (xy 92.301366 -448.864568) (xy 92.367683 -448.901303) (xy 92.429719 -448.944878)
			(xy 92.486772 -448.9948) (xy 92.538196 -449.050504) (xy 92.583407 -449.111359) (xy 92.621894 -449.176674)
			(xy 92.65322 -449.24571) (xy 92.67703 -449.317685) (xy 92.693055 -449.391783) (xy 92.701114 -449.467164)
			(xy 92.701618 -449.50507) (xy 92.701114 -449.542976) (xy 92.693055 -449.618357) (xy 92.67703 -449.692455)
			(xy 92.65322 -449.76443) (xy 92.621894 -449.833466) (xy 92.583407 -449.898781) (xy 92.538196 -449.959636)
			(xy 92.486772 -450.01534) (xy 92.429719 -450.065262) (xy 92.367683 -450.108837) (xy 92.301366 -450.145572)
			(xy 92.23152 -450.175049) (xy 92.158937 -450.196935) (xy 92.084439 -450.210982) (xy 92.008869 -450.217031)
			(xy 91.933085 -450.215012) (xy 91.857945 -450.20495) (xy 91.7843 -450.186958) (xy 91.712984 -450.16124)
			(xy 91.644807 -450.128088) (xy 91.580539 -450.087876) (xy 91.52091 -450.041061) (xy 91.466594 -449.988173)
			(xy 91.418208 -449.929811) (xy 91.3763 -449.866636) (xy 91.341344 -449.799365) (xy 91.313737 -449.72876)
			(xy 91.293791 -449.655619) (xy 91.281732 -449.580774) (xy 91.277697 -449.50507) (xy 90.161341 -449.50507)
			(xy 90.159385 -449.56592) (xy 90.148848 -449.641245) (xy 90.130337 -449.715016) (xy 90.104063 -449.786391)
			(xy 90.070327 -449.854557) (xy 90.029512 -449.918736) (xy 89.982085 -449.978196) (xy 89.928586 -450.032258)
			(xy 89.869627 -450.080306) (xy 89.838022 -450.101462) (xy 89.825051 -450.110483) (xy 89.803641 -450.133703)
			(xy 89.7886 -450.161476) (xy 89.780853 -450.192096) (xy 89.780364 -450.207888) (xy 89.780364 -450.56679)
			(xy 89.780906 -450.583441) (xy 89.789521 -450.615609) (xy 89.806168 -450.644452) (xy 89.829712 -450.668004)
			(xy 89.858548 -450.684661) (xy 89.890713 -450.693288) (xy 89.907364 -450.69379) (xy 89.907618 -450.69379)
			(xy 89.924382 -450.693277) (xy 89.956749 -450.684531) (xy 89.985717 -450.66765) (xy 90.009282 -450.643799)
			(xy 90.025814 -450.614631) (xy 90.030554 -450.59854) (xy 90.030554 -450.598286) (xy 90.040312 -450.562167)
			(xy 90.066403 -450.492041) (xy 90.099708 -450.42504) (xy 90.139858 -450.361903) (xy 90.186411 -450.303327)
			(xy 90.238852 -450.249959) (xy 90.296604 -450.202387) (xy 90.359028 -450.161136) (xy 90.425435 -450.126663)
			(xy 90.495093 -450.099347) (xy 90.567232 -450.079491) (xy 90.641056 -450.067312) (xy 90.71575 -450.062946)
			(xy 90.790491 -450.066441) (xy 90.864452 -450.077759) (xy 90.936817 -450.096773) (xy 91.006788 -450.123275)
			(xy 91.073593 -450.156973) (xy 91.136493 -450.197493) (xy 91.194795 -450.244388) (xy 91.247855 -450.297142)
			(xy 91.295087 -450.355172) (xy 91.335971 -450.417837) (xy 91.370054 -450.484445) (xy 91.39696 -450.554262)
			(xy 91.416393 -450.626516) (xy 91.428138 -450.70041) (xy 91.432066 -450.775129) (xy 91.428132 -450.849848)
			(xy 91.416381 -450.923741) (xy 91.396942 -450.995994) (xy 91.37003 -451.065808) (xy 91.335941 -451.132414)
			(xy 91.295053 -451.195075) (xy 91.247816 -451.253101) (xy 91.194752 -451.30585) (xy 91.136446 -451.352741)
			(xy 91.073542 -451.393256) (xy 91.006735 -451.426948) (xy 90.936762 -451.453444) (xy 90.864395 -451.472453)
			(xy 90.790433 -451.483764) (xy 90.715692 -451.487253) (xy 90.640998 -451.482881) (xy 90.567175 -451.470697)
			(xy 90.495037 -451.450834) (xy 90.425382 -451.423513) (xy 90.358978 -451.389034) (xy 90.296557 -451.347779)
			(xy 90.23881 -451.300202) (xy 90.186372 -451.246829) (xy 90.139824 -451.188249) (xy 90.099679 -451.125109)
			(xy 90.06638 -451.058105) (xy 90.040295 -450.987978) (xy 90.030554 -450.951854) (xy 90.030554 -450.9516)
			(xy 90.025864 -450.935498) (xy 90.009304 -450.906347) (xy 89.985723 -450.882516) (xy 89.956749 -450.865649)
			(xy 89.924381 -450.856912) (xy 89.907618 -450.85635) (xy 89.907364 -450.85635) (xy 89.890715 -450.856849)
			(xy 89.858553 -450.865477) (xy 89.829721 -450.882136) (xy 89.806183 -450.905689) (xy 89.789544 -450.934533)
			(xy 89.780938 -450.9667) (xy 89.780364 -450.98335) (xy 89.780364 -451.065138) (xy 89.766334 -451.081886)
			(xy 89.74364 -451.119216) (xy 89.727662 -451.159876) (xy 89.718873 -451.20267) (xy 89.71753 -451.246336)
			(xy 89.723673 -451.289589) (xy 89.737121 -451.331154) (xy 89.757478 -451.369808) (xy 89.784145 -451.404412)
			(xy 89.816335 -451.433947) (xy 89.834466 -451.446138) (xy 89.863786 -451.465468) (xy 89.918857 -451.509052)
			(xy 89.969367 -451.557849) (xy 90.014824 -451.611385) (xy 90.054785 -451.66914) (xy 90.07221 -451.69963)
			(xy 90.084975 -451.723189) (xy 90.107348 -451.771883) (xy 90.116914 -451.796912) (xy 90.129367 -451.831717)
			(xy 90.147833 -451.903299) (xy 90.158777 -451.97641) (xy 90.161848 -452.04507) (xy 91.277697 -452.04507)
			(xy 91.281732 -451.969366) (xy 91.293791 -451.894521) (xy 91.313737 -451.82138) (xy 91.341344 -451.750775)
			(xy 91.3763 -451.683504) (xy 91.418208 -451.620329) (xy 91.466594 -451.561967) (xy 91.52091 -451.509079)
			(xy 91.580539 -451.462264) (xy 91.644807 -451.422052) (xy 91.712984 -451.3889) (xy 91.7843 -451.363182)
			(xy 91.857945 -451.34519) (xy 91.933085 -451.335128) (xy 92.008869 -451.333109) (xy 92.084439 -451.339158)
			(xy 92.158937 -451.353205) (xy 92.23152 -451.375091) (xy 92.301366 -451.404568) (xy 92.367683 -451.441303)
			(xy 92.429719 -451.484878) (xy 92.486772 -451.5348) (xy 92.538196 -451.590504) (xy 92.583407 -451.651359)
			(xy 92.621894 -451.716674) (xy 92.65322 -451.78571) (xy 92.67703 -451.857685) (xy 92.693055 -451.931783)
			(xy 92.701114 -452.007164) (xy 92.701618 -452.04507) (xy 92.701114 -452.082976) (xy 92.693055 -452.158357)
			(xy 92.67703 -452.232455) (xy 92.65322 -452.30443) (xy 92.621894 -452.373466) (xy 92.583407 -452.438781)
			(xy 92.538196 -452.499636) (xy 92.486772 -452.55534) (xy 92.429719 -452.605262) (xy 92.367683 -452.648837)
			(xy 92.301366 -452.685572) (xy 92.23152 -452.715049) (xy 92.158937 -452.736935) (xy 92.084439 -452.750982)
			(xy 92.008869 -452.757031) (xy 91.933085 -452.755012) (xy 91.857945 -452.74495) (xy 91.7843 -452.726958)
			(xy 91.712984 -452.70124) (xy 91.644807 -452.668088) (xy 91.580539 -452.627876) (xy 91.52091 -452.581061)
			(xy 91.466594 -452.528173) (xy 91.418208 -452.469811) (xy 91.3763 -452.406636) (xy 91.341344 -452.339365)
			(xy 91.313737 -452.26876) (xy 91.293791 -452.195619) (xy 91.281732 -452.120774) (xy 91.277697 -452.04507)
			(xy 90.161848 -452.04507) (xy 90.16208 -452.050262) (xy 90.157706 -452.124058) (xy 90.145703 -452.197002)
			(xy 90.126201 -452.268309) (xy 90.099409 -452.337209) (xy 90.065616 -452.402958) (xy 90.025187 -452.464849)
			(xy 89.978558 -452.522214) (xy 89.926231 -452.574434) (xy 89.868771 -452.620945) (xy 89.838022 -452.641462)
			(xy 89.825051 -452.650483) (xy 89.803641 -452.673703) (xy 89.7886 -452.701476) (xy 89.780853 -452.732096)
			(xy 89.780364 -452.747888) (xy 89.780364 -453.10679) (xy 89.780906 -453.123441) (xy 89.789521 -453.155609)
			(xy 89.806168 -453.184452) (xy 89.829712 -453.208004) (xy 89.858548 -453.224661) (xy 89.890713 -453.233288)
			(xy 89.907364 -453.23379) (xy 89.907618 -453.23379) (xy 89.924382 -453.233277) (xy 89.956749 -453.224531)
			(xy 89.985717 -453.20765) (xy 90.009282 -453.183799) (xy 90.025814 -453.154631) (xy 90.030554 -453.13854)
			(xy 90.030554 -453.138286) (xy 90.039237 -453.106052) (xy 90.061822 -453.043228) (xy 90.090184 -452.982791)
			(xy 90.124074 -452.925271) (xy 90.14333 -452.898002) (xy 90.166489 -452.866829) (xy 90.218552 -452.809205)
			(xy 90.276583 -452.757595) (xy 90.339891 -452.712614) (xy 90.407722 -452.674798) (xy 90.443304 -452.659242)
			(xy 90.477771 -452.645231) (xy 90.548973 -452.623627) (xy 90.622039 -452.609569) (xy 90.696173 -452.60321)
			(xy 90.770567 -452.604619) (xy 90.844407 -452.613781) (xy 90.916888 -452.630596) (xy 90.987221 -452.65488)
			(xy 91.054636 -452.686369) (xy 91.118398 -452.724719) (xy 91.177812 -452.769511) (xy 91.232229 -452.820256)
			(xy 91.281055 -452.876402) (xy 91.323758 -452.937335) (xy 91.359871 -453.00239) (xy 91.389001 -453.070857)
			(xy 91.400376 -453.106282) (xy 91.411019 -453.142611) (xy 91.425457 -453.216928) (xy 91.431924 -453.292357)
			(xy 91.430349 -453.368047) (xy 91.420748 -453.443141) (xy 91.40323 -453.516792) (xy 91.377992 -453.588168)
			(xy 91.345322 -453.656461) (xy 91.305586 -453.720901) (xy 91.259235 -453.780759) (xy 91.206791 -453.835358)
			(xy 91.148849 -453.884082) (xy 91.086061 -453.92638) (xy 91.019139 -453.961775) (xy 90.948837 -453.989866)
			(xy 90.875951 -454.010335) (xy 90.801304 -454.022953) (xy 90.72574 -454.027575) (xy 90.650111 -454.02415)
			(xy 90.575274 -454.012716) (xy 90.502073 -453.993404) (xy 90.431335 -453.96643) (xy 90.36386 -453.932099)
			(xy 90.300411 -453.890801) (xy 90.241704 -453.843) (xy 90.214704 -453.816466) (xy 90.198477 -453.800773)
			(xy 90.161555 -453.77481) (xy 90.120629 -453.755772) (xy 90.076985 -453.744259) (xy 90.031994 -453.740631)
			(xy 89.987069 -453.745003) (xy 89.943621 -453.757236) (xy 89.903016 -453.776948) (xy 89.866528 -453.803518)
			(xy 89.835304 -453.836113) (xy 89.810324 -453.873707) (xy 89.792373 -453.915121) (xy 89.782015 -453.959054)
			(xy 89.780364 -453.981566) (xy 89.780364 -454.58507) (xy 85.75802 -458.607414) (xy 85.75802 -464.51012)
			(xy 86.39887 -464.51012) (xy 86.402874 -464.310022) (xy 86.414881 -464.110244) (xy 86.434872 -463.911107)
			(xy 86.462814 -463.712929) (xy 86.498662 -463.516027) (xy 86.54236 -463.320718) (xy 86.593837 -463.127313)
			(xy 86.653011 -462.936123) (xy 86.719787 -462.747453) (xy 86.794059 -462.561606) (xy 86.875706 -462.378879)
			(xy 86.964599 -462.199566) (xy 87.060595 -462.023952) (xy 87.16354 -461.85232) (xy 87.27327 -461.684944)
			(xy 87.389608 -461.522093) (xy 87.512369 -461.364026) (xy 87.641356 -461.210998) (xy 87.776363 -461.063253)
			(xy 87.917172 -460.921027) (xy 88.063559 -460.78455) (xy 88.215289 -460.654038) (xy 88.37212 -460.529702)
			(xy 88.533799 -460.41174) (xy 88.700069 -460.300341) (xy 88.870662 -460.195684) (xy 89.045306 -460.097936)
			(xy 89.223722 -460.007253) (xy 89.405622 -459.923782) (xy 89.590717 -459.847655) (xy 89.778709 -459.778995)
			(xy 89.969298 -459.717911) (xy 90.162178 -459.664501) (xy 90.35704 -459.618852) (xy 90.553573 -459.581035)
			(xy 90.751462 -459.551111) (xy 90.950389 -459.529129) (xy 91.150037 -459.515124) (xy 91.350085 -459.509118)
			(xy 91.550213 -459.51112) (xy 91.750101 -459.521128) (xy 91.949428 -459.539125) (xy 92.147876 -459.565083)
			(xy 92.345126 -459.59896) (xy 92.540863 -459.640702) (xy 92.734773 -459.690241) (xy 92.926546 -459.747499)
			(xy 93.115875 -459.812384) (xy 93.302455 -459.884792) (xy 93.48599 -459.964608) (xy 93.666184 -460.051702)
			(xy 93.842749 -460.145936) (xy 94.015402 -460.247159) (xy 94.183867 -460.355209) (xy 94.347875 -460.469912)
			(xy 94.507162 -460.591086) (xy 94.661473 -460.718535) (xy 94.810561 -460.852056) (xy 94.954188 -460.991436)
			(xy 95.092124 -461.13645) (xy 95.224147 -461.286867) (xy 95.350046 -461.442445) (xy 95.46962 -461.602937)
			(xy 95.582676 -461.768083) (xy 95.689035 -461.937621) (xy 95.788526 -462.111279) (xy 95.880989 -462.288778)
			(xy 95.966276 -462.469834) (xy 96.044251 -462.654158) (xy 96.114788 -462.841454) (xy 96.177776 -463.031422)
			(xy 96.233113 -463.223758) (xy 96.28071 -463.418154) (xy 96.320491 -463.614299) (xy 96.352393 -463.811878)
			(xy 96.376364 -464.010575) (xy 96.392366 -464.210073) (xy 96.400373 -464.410051) (xy 96.400874 -464.51012)
			(xy 96.400373 -464.610189) (xy 96.392366 -464.810167) (xy 96.376364 -465.009665) (xy 96.352393 -465.208362)
			(xy 96.320491 -465.405941) (xy 96.28071 -465.602086) (xy 96.233113 -465.796482) (xy 96.177776 -465.988818)
			(xy 96.114788 -466.178786) (xy 96.044251 -466.366082) (xy 95.966276 -466.550406) (xy 95.880989 -466.731462)
			(xy 95.788526 -466.908961) (xy 95.689035 -467.082619) (xy 95.582676 -467.252157) (xy 95.46962 -467.417303)
			(xy 95.350046 -467.577795) (xy 95.224147 -467.733373) (xy 95.092124 -467.88379) (xy 94.954188 -468.028804)
			(xy 94.810561 -468.168184) (xy 94.661473 -468.301705) (xy 94.507162 -468.429154) (xy 94.347875 -468.550328)
			(xy 94.183867 -468.665031) (xy 94.015402 -468.773081) (xy 93.842749 -468.874304) (xy 93.666184 -468.968538)
			(xy 93.48599 -469.055632) (xy 93.302455 -469.135448) (xy 93.115875 -469.207856) (xy 92.926546 -469.272741)
			(xy 92.734773 -469.329999) (xy 92.540863 -469.379538) (xy 92.345126 -469.42128) (xy 92.147876 -469.455157)
			(xy 91.949428 -469.481115) (xy 91.750101 -469.499112) (xy 91.550213 -469.50912) (xy 91.350085 -469.511122)
			(xy 91.150037 -469.505116) (xy 90.950389 -469.491111) (xy 90.751462 -469.469129) (xy 90.553573 -469.439205)
			(xy 90.35704 -469.401388) (xy 90.162178 -469.355739) (xy 89.969298 -469.302329) (xy 89.778709 -469.241245)
			(xy 89.590717 -469.172585) (xy 89.405622 -469.096458) (xy 89.223722 -469.012987) (xy 89.045306 -468.922304)
			(xy 88.870662 -468.824556) (xy 88.700069 -468.719899) (xy 88.533799 -468.6085) (xy 88.37212 -468.490538)
			(xy 88.215289 -468.366202) (xy 88.063559 -468.23569) (xy 87.917172 -468.099213) (xy 87.776363 -467.956987)
			(xy 87.641356 -467.809242) (xy 87.512369 -467.656214) (xy 87.389608 -467.498147) (xy 87.27327 -467.335296)
			(xy 87.16354 -467.16792) (xy 87.060595 -466.996288) (xy 86.964599 -466.820674) (xy 86.875706 -466.641361)
			(xy 86.794059 -466.458634) (xy 86.719787 -466.272787) (xy 86.653011 -466.084117) (xy 86.593837 -465.892927)
			(xy 86.54236 -465.699522) (xy 86.498662 -465.504213) (xy 86.462814 -465.307311) (xy 86.434872 -465.109133)
			(xy 86.414881 -464.909996) (xy 86.402874 -464.710218) (xy 86.39887 -464.51012) (xy 85.75802 -464.51012)
			(xy 85.75802 -471.16873) (xy 85.758552 -471.185351) (xy 85.767131 -471.217465) (xy 85.783724 -471.246268)
			(xy 85.795104 -471.258392) (xy 90.056208 -475.519242) (xy 90.056208 -475.7547) (xy 90.083894 -475.789244)
			(xy 90.106754 -475.820994) (xy 90.121995 -475.844725) (xy 90.147193 -475.895182) (xy 90.166005 -475.948352)
			(xy 90.178146 -476.003429) (xy 90.183433 -476.05958) (xy 90.181785 -476.115956) (xy 90.173228 -476.171702)
			(xy 90.165936 -476.198946) (xy 90.155355 -476.233748) (xy 90.124733 -476.299723) (xy 90.104976 -476.330264)
			(xy 90.083894 -476.358966) (xy 90.056208 -476.393764) (xy 90.056208 -476.545656) (xy 90.384376 -476.873824)
			(xy 90.384376 -477.025716) (xy 90.384921 -477.042364) (xy 90.393541 -477.074525) (xy 90.41019 -477.10336)
			(xy 90.433733 -477.126905) (xy 90.462567 -477.143556) (xy 90.494728 -477.152178) (xy 90.511376 -477.152716)
			(xy 90.895932 -477.152716) (xy 90.912578 -477.152169) (xy 90.944735 -477.143546) (xy 90.973566 -477.126896)
			(xy 90.997106 -477.103353) (xy 91.013752 -477.07452) (xy 91.022371 -477.042362) (xy 91.022932 -477.025716)
			(xy 91.022932 -476.637096) (xy 91.164664 -476.495364) (xy 91.196668 -476.463614) (xy 91.244166 -476.416116)
			(xy 91.249246 -476.37192) (xy 91.253223 -476.341413) (xy 91.268312 -476.281769) (xy 91.291257 -476.224686)
			(xy 91.321643 -476.171191) (xy 91.358924 -476.12225) (xy 91.402425 -476.078745) (xy 91.451363 -476.041462)
			(xy 91.504856 -476.011072) (xy 91.561938 -475.988123) (xy 91.62158 -475.973029) (xy 91.65209 -475.969076)
			(xy 91.696286 -475.963996) (xy 91.83243 -475.827598) (xy 91.967304 -475.692724) (xy 91.967304 -473.803218)
			(xy 96.690688 -469.079834) (xy 96.699337 -469.069384) (xy 96.71244 -469.045638) (xy 96.720239 -469.019663)
			(xy 96.721676 -469.006174) (xy 96.721676 -453.799194) (xy 96.719953 -453.77656) (xy 96.709499 -453.732394)
			(xy 96.691371 -453.690784) (xy 96.666144 -453.653054) (xy 96.634619 -453.6204) (xy 96.597799 -453.593862)
			(xy 96.556853 -453.574282) (xy 96.513081 -453.562281) (xy 96.467874 -453.558241) (xy 96.422668 -453.56229)
			(xy 96.378899 -453.5743) (xy 96.337956 -453.593889) (xy 96.301142 -453.620434) (xy 96.269624 -453.653094)
			(xy 96.256602 -453.671686) (xy 96.224954 -453.719974) (xy 96.155974 -453.81257) (xy 96.080816 -453.900226)
			(xy 95.999832 -453.982529) (xy 95.913403 -454.059094) (xy 95.821933 -454.129561) (xy 95.725853 -454.193599)
			(xy 95.625613 -454.250907) (xy 95.521684 -454.301217) (xy 95.414555 -454.344292) (xy 95.304727 -454.379931)
			(xy 95.192716 -454.407965) (xy 95.079049 -454.428263) (xy 94.964259 -454.44073) (xy 94.848884 -454.445308)
			(xy 94.733467 -454.441975) (xy 94.618549 -454.430746) (xy 94.504669 -454.411674) (xy 94.392363 -454.384849)
			(xy 94.282157 -454.350397) (xy 94.174569 -454.308479) (xy 94.070104 -454.259292) (xy 93.969253 -454.203068)
			(xy 93.872488 -454.140069) (xy 93.780264 -454.070593) (xy 93.693013 -453.994964) (xy 93.611147 -453.913538)
			(xy 93.535048 -453.826698) (xy 93.465075 -453.734851) (xy 93.401555 -453.638427) (xy 93.344786 -453.537881)
			(xy 93.295036 -453.433683) (xy 93.252538 -453.326323) (xy 93.217491 -453.216305) (xy 93.19006 -453.104145)
			(xy 93.170374 -452.99037) (xy 93.158524 -452.875514) (xy 93.154567 -452.760117) (xy 93.158522 -452.644719)
			(xy 93.170369 -452.529863) (xy 93.190053 -452.416088) (xy 93.217482 -452.303928) (xy 93.252527 -452.193909)
			(xy 93.295023 -452.086548) (xy 93.344771 -451.982349) (xy 93.401537 -451.881801) (xy 93.465055 -451.785377)
			(xy 93.535027 -451.693528) (xy 93.611124 -451.606686) (xy 93.692989 -451.525259) (xy 93.780237 -451.449628)
			(xy 93.87246 -451.38015) (xy 93.969224 -451.31715) (xy 94.070074 -451.260923) (xy 94.174538 -451.211735)
			(xy 94.282125 -451.169815) (xy 94.392331 -451.13536) (xy 94.504636 -451.108533) (xy 94.618515 -451.089459)
			(xy 94.733433 -451.078228) (xy 94.84885 -451.074892) (xy 94.964225 -451.079467) (xy 95.079016 -451.091932)
			(xy 95.192683 -451.112228) (xy 95.304694 -451.14026) (xy 95.414523 -451.175896) (xy 95.521654 -451.218969)
			(xy 95.625583 -451.269277) (xy 95.725824 -451.326583) (xy 95.821906 -451.390619) (xy 95.913377 -451.461084)
			(xy 95.999808 -451.537648) (xy 96.080794 -451.619949) (xy 96.155953 -451.707604) (xy 96.224935 -451.800199)
			(xy 96.256602 -451.848474) (xy 96.269625 -451.867066) (xy 96.301139 -451.899729) (xy 96.337952 -451.926279)
			(xy 96.378894 -451.945871) (xy 96.422663 -451.957883) (xy 96.46787 -451.961933) (xy 96.513077 -451.957894)
			(xy 96.55685 -451.945892) (xy 96.597796 -451.92631) (xy 96.634615 -451.899769) (xy 96.666137 -451.867113)
			(xy 96.691361 -451.82938) (xy 96.709485 -451.787768) (xy 96.719933 -451.743599) (xy 96.721676 -451.720966)
			(xy 96.721676 -417.8554) (xy 96.721135 -417.838783) (xy 96.712542 -417.80668) (xy 96.695939 -417.777891)
			(xy 96.684592 -417.765738) (xy 88.652096 -409.733496) (xy 88.652096 -409.62961) (xy 88.651603 -409.612955)
			(xy 88.642983 -409.580778) (xy 88.626329 -409.55193) (xy 88.602775 -409.528375) (xy 88.573927 -409.511719)
			(xy 88.541751 -409.503098) (xy 88.525096 -409.50261) (xy 88.496394 -409.50261) (xy 88.481617 -409.50982)
			(xy 88.451507 -409.523035) (xy 88.436196 -409.529026) (xy 88.39901 -409.542792) (xy 88.322316 -409.562941)
			(xy 88.243858 -409.574442) (xy 88.164608 -409.577155) (xy 88.085547 -409.571044) (xy 88.007655 -409.556186)
			(xy 87.931896 -409.532765) (xy 87.859209 -409.501071) (xy 87.824564 -409.481782) (xy 87.793247 -409.463208)
			(xy 87.734199 -409.420601) (xy 87.679811 -409.372185) (xy 87.654892 -409.345638) (xy 87.630616 -409.318453)
			(xy 87.587137 -409.259953) (xy 87.549867 -409.197313) (xy 87.519198 -409.131192) (xy 87.495451 -409.062281)
			(xy 87.478875 -408.991302) (xy 87.469643 -408.919001) (xy 87.467852 -408.846135) (xy 87.473521 -408.773468)
			(xy 87.486591 -408.701761) (xy 87.506924 -408.631767) (xy 87.534308 -408.564218) (xy 87.551006 -408.531822)
			(xy 87.568765 -408.499311) (xy 87.610057 -408.437802) (xy 87.65752 -408.380919) (xy 87.710639 -408.329278)
			(xy 87.768839 -408.283439) (xy 87.831488 -408.243898) (xy 87.897909 -408.211085) (xy 87.96738 -408.185353)
			(xy 88.039151 -408.166983) (xy 88.112442 -408.156173) (xy 88.14943 -408.154124) (xy 88.165616 -408.152968)
			(xy 88.196641 -408.143493) (xy 88.224271 -408.126495) (xy 88.246715 -408.103073) (xy 88.262521 -408.074745)
			(xy 88.270666 -408.043344) (xy 88.271096 -408.027124) (xy 88.271096 -407.163016) (xy 88.270602 -407.146808)
			(xy 88.262422 -407.115441) (xy 88.24661 -407.087143) (xy 88.224185 -407.063736) (xy 88.196589 -407.046727)
			(xy 88.165601 -407.037212) (xy 88.14943 -407.036016) (xy 88.115412 -407.03418) (xy 88.047927 -407.024818)
			(xy 87.981644 -407.009056) (xy 87.949278 -406.998424) (xy 87.923901 -406.989465) (xy 87.874443 -406.968237)
			(xy 87.850472 -406.956006) (xy 87.822729 -406.941125) (xy 87.769714 -406.907166) (xy 87.719903 -406.868659)
			(xy 87.696548 -406.847548) (xy 87.669091 -406.821499) (xy 87.619262 -406.764528) (xy 87.575761 -406.702591)
			(xy 87.539078 -406.636387) (xy 87.509628 -406.566664) (xy 87.487743 -406.494209) (xy 87.473671 -406.419841)
			(xy 87.467571 -406.3444) (xy 87.469511 -406.268737) (xy 87.47947 -406.193707) (xy 87.497335 -406.120158)
			(xy 87.522904 -406.04892) (xy 87.555889 -405.980798) (xy 87.595917 -405.916562) (xy 87.642536 -405.856935)
			(xy 87.69522 -405.802593) (xy 87.753373 -405.754149) (xy 87.816338 -405.712149) (xy 87.883406 -405.677069)
			(xy 87.953817 -405.649304) (xy 88.026777 -405.629169) (xy 88.101462 -405.61689) (xy 88.177028 -405.612605)
			(xy 88.252622 -405.616365) (xy 88.327391 -405.628125) (xy 88.36406 -405.637492) (xy 88.37549 -405.640794)
			(xy 88.387682 -405.64435) (xy 88.392762 -405.645874) (xy 88.414854 -405.651762) (xy 88.460332 -405.656412)
			(xy 88.50591 -405.652859) (xy 88.550118 -405.641216) (xy 88.591533 -405.621858) (xy 88.628821 -405.59541)
			(xy 88.660781 -405.562723) (xy 88.686384 -405.524849) (xy 88.704805 -405.483009) (xy 88.715451 -405.43855)
			(xy 88.71712 -405.41575) (xy 88.71712 -405.3205) (xy 88.719152 -405.318468) (xy 88.730006 -405.306972)
			(xy 88.746205 -405.279832) (xy 88.755214 -405.249536) (xy 88.756477 -405.217955) (xy 88.753696 -405.20239)
			(xy 88.753696 -405.202136) (xy 88.746303 -405.164708) (xy 88.738616 -405.0888) (xy 88.739093 -405.012506)
			(xy 88.747729 -404.9367) (xy 88.764425 -404.862253) (xy 88.788989 -404.79002) (xy 88.82114 -404.720828)
			(xy 88.860507 -404.655473) (xy 88.906641 -404.594705) (xy 88.95901 -404.53922) (xy 89.017014 -404.489657)
			(xy 89.079988 -404.446582) (xy 89.147208 -404.410492) (xy 89.217903 -404.381799) (xy 89.291262 -404.360834)
			(xy 89.366443 -404.347837) (xy 89.442583 -404.342957) (xy 89.518808 -404.34625) (xy 89.594243 -404.357679)
			(xy 89.668023 -404.377111) (xy 89.7393 -404.404325) (xy 89.807258 -404.439008) (xy 89.871115 -404.480761)
			(xy 89.930139 -404.529106) (xy 89.983652 -404.583488) (xy 90.007694 -404.61311) (xy 90.024501 -404.634728)
			(xy 90.055143 -404.680116) (xy 90.068908 -404.703788) (xy 90.087159 -404.736964) (xy 90.117333 -404.806416)
			(xy 90.139962 -404.878678) (xy 90.154792 -404.952935) (xy 90.161654 -405.028346) (xy 90.161237 -405.05507)
			(xy 91.277697 -405.05507) (xy 91.281732 -404.979366) (xy 91.293791 -404.904521) (xy 91.313737 -404.83138)
			(xy 91.341344 -404.760775) (xy 91.3763 -404.693504) (xy 91.418208 -404.630329) (xy 91.466594 -404.571967)
			(xy 91.52091 -404.519079) (xy 91.580539 -404.472264) (xy 91.644807 -404.432052) (xy 91.712984 -404.3989)
			(xy 91.7843 -404.373182) (xy 91.857945 -404.35519) (xy 91.933085 -404.345128) (xy 92.008869 -404.343109)
			(xy 92.084439 -404.349158) (xy 92.158937 -404.363205) (xy 92.23152 -404.385091) (xy 92.301366 -404.414568)
			(xy 92.367683 -404.451303) (xy 92.429719 -404.494878) (xy 92.486772 -404.5448) (xy 92.538196 -404.600504)
			(xy 92.583407 -404.661359) (xy 92.621894 -404.726674) (xy 92.65322 -404.79571) (xy 92.67703 -404.867685)
			(xy 92.693055 -404.941783) (xy 92.701114 -405.017164) (xy 92.701618 -405.05507) (xy 92.701114 -405.092976)
			(xy 92.693055 -405.168357) (xy 92.67703 -405.242455) (xy 92.65322 -405.31443) (xy 92.621894 -405.383466)
			(xy 92.583407 -405.448781) (xy 92.538196 -405.509636) (xy 92.486772 -405.56534) (xy 92.429719 -405.615262)
			(xy 92.367683 -405.658837) (xy 92.301366 -405.695572) (xy 92.23152 -405.725049) (xy 92.158937 -405.746935)
			(xy 92.084439 -405.760982) (xy 92.008869 -405.767031) (xy 91.933085 -405.765012) (xy 91.857945 -405.75495)
			(xy 91.7843 -405.736958) (xy 91.712984 -405.71124) (xy 91.644807 -405.678088) (xy 91.580539 -405.637876)
			(xy 91.52091 -405.591061) (xy 91.466594 -405.538173) (xy 91.418208 -405.479811) (xy 91.3763 -405.416636)
			(xy 91.341344 -405.349365) (xy 91.313737 -405.27876) (xy 91.293791 -405.205619) (xy 91.281732 -405.130774)
			(xy 91.277697 -405.05507) (xy 90.161237 -405.05507) (xy 90.160472 -405.10406) (xy 90.151259 -405.17922)
			(xy 90.134118 -405.252978) (xy 90.109244 -405.324498) (xy 90.076918 -405.392974) (xy 90.037504 -405.457632)
			(xy 89.991449 -405.517739) (xy 89.939273 -405.572617) (xy 89.881566 -405.621646) (xy 89.81898 -405.664272)
			(xy 89.752222 -405.700012) (xy 89.682047 -405.728463) (xy 89.609248 -405.749303) (xy 89.534649 -405.762297)
			(xy 89.4969 -405.765254) (xy 89.480994 -405.766771) (xy 89.450624 -405.776667) (xy 89.423666 -405.793799)
			(xy 89.401812 -405.817095) (xy 89.386433 -405.84509) (xy 89.378495 -405.876029) (xy 89.378028 -405.892)
			(xy 89.378028 -406.32507) (xy 90.007697 -406.32507) (xy 90.011732 -406.249366) (xy 90.023791 -406.174521)
			(xy 90.043737 -406.10138) (xy 90.071344 -406.030775) (xy 90.1063 -405.963504) (xy 90.148208 -405.900329)
			(xy 90.196594 -405.841967) (xy 90.25091 -405.789079) (xy 90.310539 -405.742264) (xy 90.374807 -405.702052)
			(xy 90.442984 -405.6689) (xy 90.5143 -405.643182) (xy 90.587945 -405.62519) (xy 90.663085 -405.615128)
			(xy 90.738869 -405.613109) (xy 90.814439 -405.619158) (xy 90.888937 -405.633205) (xy 90.96152 -405.655091)
			(xy 91.031366 -405.684568) (xy 91.097683 -405.721303) (xy 91.159719 -405.764878) (xy 91.216772 -405.8148)
			(xy 91.268196 -405.870504) (xy 91.313407 -405.931359) (xy 91.351894 -405.996674) (xy 91.38322 -406.06571)
			(xy 91.40703 -406.137685) (xy 91.423055 -406.211783) (xy 91.431114 -406.287164) (xy 91.431618 -406.32507)
			(xy 91.431114 -406.362976) (xy 91.423055 -406.438357) (xy 91.40703 -406.512455) (xy 91.38322 -406.58443)
			(xy 91.351894 -406.653466) (xy 91.313407 -406.718781) (xy 91.268196 -406.779636) (xy 91.216772 -406.83534)
			(xy 91.159719 -406.885262) (xy 91.097683 -406.928837) (xy 91.031366 -406.965572) (xy 90.96152 -406.995049)
			(xy 90.888937 -407.016935) (xy 90.814439 -407.030982) (xy 90.738869 -407.037031) (xy 90.663085 -407.035012)
			(xy 90.587945 -407.02495) (xy 90.5143 -407.006958) (xy 90.442984 -406.98124) (xy 90.374807 -406.948088)
			(xy 90.310539 -406.907876) (xy 90.25091 -406.861061) (xy 90.196594 -406.808173) (xy 90.148208 -406.749811)
			(xy 90.1063 -406.686636) (xy 90.071344 -406.619365) (xy 90.043737 -406.54876) (xy 90.023791 -406.475619)
			(xy 90.011732 -406.400774) (xy 90.007697 -406.32507) (xy 89.378028 -406.32507) (xy 89.378028 -406.75814)
			(xy 89.378529 -406.774087) (xy 89.386449 -406.804981) (xy 89.401785 -406.832946) (xy 89.423577 -406.856232)
			(xy 89.450465 -406.873386) (xy 89.480767 -406.883335) (xy 89.496646 -406.884886) (xy 89.528938 -406.887334)
			(xy 89.592919 -406.897386) (xy 89.624408 -406.904952) (xy 89.661237 -406.914774) (xy 89.732721 -406.941244)
			(xy 89.800966 -406.975201) (xy 89.865192 -407.016257) (xy 89.924663 -407.063941) (xy 89.978697 -407.117707)
			(xy 90.026675 -407.17694) (xy 90.06805 -407.240962) (xy 90.102345 -407.309038) (xy 90.129169 -407.380389)
			(xy 90.148214 -407.454198) (xy 90.159263 -407.52962) (xy 90.161776 -407.59507) (xy 91.277697 -407.59507)
			(xy 91.281732 -407.519366) (xy 91.293791 -407.444521) (xy 91.313737 -407.37138) (xy 91.341344 -407.300775)
			(xy 91.3763 -407.233504) (xy 91.418208 -407.170329) (xy 91.466594 -407.111967) (xy 91.52091 -407.059079)
			(xy 91.580539 -407.012264) (xy 91.644807 -406.972052) (xy 91.712984 -406.9389) (xy 91.7843 -406.913182)
			(xy 91.857945 -406.89519) (xy 91.933085 -406.885128) (xy 92.008869 -406.883109) (xy 92.084439 -406.889158)
			(xy 92.158937 -406.903205) (xy 92.23152 -406.925091) (xy 92.301366 -406.954568) (xy 92.367683 -406.991303)
			(xy 92.429719 -407.034878) (xy 92.486772 -407.0848) (xy 92.538196 -407.140504) (xy 92.583407 -407.201359)
			(xy 92.621894 -407.266674) (xy 92.65322 -407.33571) (xy 92.67703 -407.407685) (xy 92.693055 -407.481783)
			(xy 92.701114 -407.557164) (xy 92.701618 -407.59507) (xy 92.701114 -407.632976) (xy 92.693055 -407.708357)
			(xy 92.67703 -407.782455) (xy 92.65322 -407.85443) (xy 92.621894 -407.923466) (xy 92.583407 -407.988781)
			(xy 92.538196 -408.049636) (xy 92.486772 -408.10534) (xy 92.429719 -408.155262) (xy 92.367683 -408.198837)
			(xy 92.301366 -408.235572) (xy 92.23152 -408.265049) (xy 92.158937 -408.286935) (xy 92.084439 -408.300982)
			(xy 92.008869 -408.307031) (xy 91.933085 -408.305012) (xy 91.857945 -408.29495) (xy 91.7843 -408.276958)
			(xy 91.712984 -408.25124) (xy 91.644807 -408.218088) (xy 91.580539 -408.177876) (xy 91.52091 -408.131061)
			(xy 91.466594 -408.078173) (xy 91.418208 -408.019811) (xy 91.3763 -407.956636) (xy 91.341344 -407.889365)
			(xy 91.313737 -407.81876) (xy 91.293791 -407.745619) (xy 91.281732 -407.670774) (xy 91.277697 -407.59507)
			(xy 90.161776 -407.59507) (xy 90.162188 -407.605791) (xy 90.156957 -407.681838) (xy 90.143628 -407.75689)
			(xy 90.122355 -407.830088) (xy 90.093382 -407.900594) (xy 90.05704 -407.9676) (xy 90.013745 -408.030338)
			(xy 89.963994 -408.088091) (xy 89.908356 -408.140196) (xy 89.847468 -408.186056) (xy 89.782028 -408.225147)
			(xy 89.747598 -408.2415) (xy 89.734612 -408.247919) (xy 89.711725 -408.265667) (xy 89.693435 -408.288122)
			(xy 89.680683 -408.314125) (xy 89.674129 -408.342335) (xy 89.673684 -408.356816) (xy 89.673684 -408.86507)
			(xy 90.007697 -408.86507) (xy 90.011732 -408.789366) (xy 90.023791 -408.714521) (xy 90.043737 -408.64138)
			(xy 90.071344 -408.570775) (xy 90.1063 -408.503504) (xy 90.148208 -408.440329) (xy 90.196594 -408.381967)
			(xy 90.25091 -408.329079) (xy 90.310539 -408.282264) (xy 90.374807 -408.242052) (xy 90.442984 -408.2089)
			(xy 90.5143 -408.183182) (xy 90.587945 -408.16519) (xy 90.663085 -408.155128) (xy 90.738869 -408.153109)
			(xy 90.814439 -408.159158) (xy 90.888937 -408.173205) (xy 90.96152 -408.195091) (xy 91.031366 -408.224568)
			(xy 91.097683 -408.261303) (xy 91.159719 -408.304878) (xy 91.165664 -408.31008) (xy 93.154506 -408.31008)
			(xy 93.158522 -408.19381) (xy 93.170549 -408.078095) (xy 93.190531 -407.963485) (xy 93.218373 -407.850526)
			(xy 93.253942 -407.739758) (xy 93.297068 -407.631707) (xy 93.347545 -407.526889) (xy 93.405134 -407.425804)
			(xy 93.46956 -407.328932) (xy 93.540515 -407.236736) (xy 93.617662 -407.149655) (xy 93.700633 -407.068104)
			(xy 93.789033 -406.992472) (xy 93.88244 -406.923118) (xy 93.980409 -406.860375) (xy 94.082473 -406.804539)
			(xy 94.188147 -406.755878) (xy 94.296926 -406.714624) (xy 94.408291 -406.680973) (xy 94.521714 -406.655085)
			(xy 94.636651 -406.637084) (xy 94.752557 -406.627055) (xy 94.868879 -406.625047) (xy 94.985062 -406.631069)
			(xy 95.100553 -406.645092) (xy 95.214801 -406.66705) (xy 95.327262 -406.696837) (xy 95.4374 -406.734312)
			(xy 95.54469 -406.779297) (xy 95.648621 -406.831576) (xy 95.748697 -406.890901) (xy 95.844443 -406.956989)
			(xy 95.9354 -407.029525) (xy 96.021136 -407.108164) (xy 96.101243 -407.19253) (xy 96.175339 -407.282222)
			(xy 96.243069 -407.376812) (xy 96.304113 -407.47585) (xy 96.358178 -407.578863) (xy 96.405008 -407.68536)
			(xy 96.444379 -407.794835) (xy 96.476103 -407.906765) (xy 96.500029 -408.020617) (xy 96.516043 -408.135849)
			(xy 96.52407 -408.251911) (xy 96.524572 -408.31008) (xy 96.52407 -408.368249) (xy 96.516043 -408.484311)
			(xy 96.500029 -408.599543) (xy 96.476103 -408.713395) (xy 96.444379 -408.825325) (xy 96.405008 -408.9348)
			(xy 96.358178 -409.041297) (xy 96.304113 -409.14431) (xy 96.243069 -409.243348) (xy 96.175339 -409.337938)
			(xy 96.101243 -409.42763) (xy 96.021136 -409.511996) (xy 95.9354 -409.590635) (xy 95.844443 -409.663171)
			(xy 95.748697 -409.729259) (xy 95.648621 -409.788584) (xy 95.54469 -409.840863) (xy 95.4374 -409.885848)
			(xy 95.327262 -409.923323) (xy 95.214801 -409.95311) (xy 95.100553 -409.975068) (xy 94.985062 -409.989091)
			(xy 94.868879 -409.995113) (xy 94.752557 -409.993105) (xy 94.636651 -409.983076) (xy 94.521714 -409.965075)
			(xy 94.408291 -409.939187) (xy 94.296926 -409.905536) (xy 94.188147 -409.864282) (xy 94.082473 -409.815621)
			(xy 93.980409 -409.759785) (xy 93.88244 -409.697042) (xy 93.789033 -409.627688) (xy 93.700633 -409.552056)
			(xy 93.617662 -409.470505) (xy 93.540515 -409.383424) (xy 93.46956 -409.291228) (xy 93.405134 -409.194356)
			(xy 93.347545 -409.093271) (xy 93.297068 -408.988453) (xy 93.253942 -408.880402) (xy 93.218373 -408.769634)
			(xy 93.190531 -408.656675) (xy 93.170549 -408.542065) (xy 93.158522 -408.42635) (xy 93.154506 -408.31008)
			(xy 91.165664 -408.31008) (xy 91.216772 -408.3548) (xy 91.268196 -408.410504) (xy 91.313407 -408.471359)
			(xy 91.351894 -408.536674) (xy 91.38322 -408.60571) (xy 91.40703 -408.677685) (xy 91.423055 -408.751783)
			(xy 91.431114 -408.827164) (xy 91.431618 -408.86507) (xy 91.431114 -408.902976) (xy 91.423055 -408.978357)
			(xy 91.40703 -409.052455) (xy 91.38322 -409.12443) (xy 91.351894 -409.193466) (xy 91.313407 -409.258781)
			(xy 91.268196 -409.319636) (xy 91.216772 -409.37534) (xy 91.159719 -409.425262) (xy 91.097683 -409.468837)
			(xy 91.031366 -409.505572) (xy 90.96152 -409.535049) (xy 90.888937 -409.556935) (xy 90.814439 -409.570982)
			(xy 90.738869 -409.577031) (xy 90.663085 -409.575012) (xy 90.587945 -409.56495) (xy 90.5143 -409.546958)
			(xy 90.442984 -409.52124) (xy 90.374807 -409.488088) (xy 90.310539 -409.447876) (xy 90.25091 -409.401061)
			(xy 90.196594 -409.348173) (xy 90.148208 -409.289811) (xy 90.1063 -409.226636) (xy 90.071344 -409.159365)
			(xy 90.043737 -409.08876) (xy 90.023791 -409.015619) (xy 90.011732 -408.940774) (xy 90.007697 -408.86507)
			(xy 89.673684 -408.86507) (xy 89.673684 -409.264612) (xy 89.674226 -409.281229) (xy 89.68282 -409.313332)
			(xy 89.699421 -409.342122) (xy 89.710768 -409.354274) (xy 97.367852 -417.011104) (xy 97.384433 -417.025769)
			(xy 97.421657 -417.049716) (xy 97.462465 -417.066857) (xy 97.505624 -417.076672) (xy 97.549831 -417.078866)
			(xy 97.59375 -417.073372) (xy 97.636054 -417.060355) (xy 97.675465 -417.04021) (xy 97.710793 -417.013545)
			(xy 97.74097 -416.981165) (xy 97.765084 -416.94405) (xy 97.782406 -416.903319) (xy 97.792415 -416.860204)
			(xy 97.794064 -416.83813) (xy 97.794064 -351.120964) (xy 97.794525 -351.083227) (xy 97.801985 -351.008124)
			(xy 97.816828 -350.934124) (xy 97.838909 -350.861954) (xy 97.868012 -350.792317) (xy 97.903853 -350.725897)
			(xy 97.94608 -350.663342) (xy 97.994281 -350.605266) (xy 98.047983 -350.552235) (xy 98.07702 -350.528128)
			(xy 98.087798 -350.518924) (xy 98.105363 -350.49669) (xy 98.11758 -350.471123) (xy 98.123846 -350.44349)
			(xy 98.124264 -350.429322) (xy 98.124264 -350.186244) (xy 98.12377 -350.169559) (xy 98.11512 -350.13733)
			(xy 98.098401 -350.10845) (xy 98.086926 -350.096328) (xy 98.023426 -350.033082) (xy 97.986596 -349.996252)
			(xy 97.986596 -349.048578) (xy 97.98605 -349.031932) (xy 97.977429 -348.999775) (xy 97.960779 -348.970945)
			(xy 97.937235 -348.947406) (xy 97.908401 -348.930761) (xy 97.876242 -348.922146) (xy 97.859596 -348.921578)
			(xy 97.57664 -348.921578) (xy 97.559981 -348.922068) (xy 97.527795 -348.930682) (xy 97.498936 -348.947333)
			(xy 97.475371 -348.970887) (xy 97.458706 -348.999738) (xy 97.450076 -349.031919) (xy 97.44964 -349.048578)
			(xy 97.44964 -349.063564) (xy 97.423732 -349.089218) (xy 97.048828 -349.464122) (xy 97.037963 -349.475737)
			(xy 97.0218 -349.503116) (xy 97.012895 -349.533637) (xy 97.011798 -349.565412) (xy 97.018578 -349.596475)
			(xy 97.025206 -349.610934) (xy 97.038577 -349.638765) (xy 97.058556 -349.697189) (xy 97.070504 -349.757767)
			(xy 97.074204 -349.819401) (xy 97.06959 -349.880974) (xy 97.056745 -349.941368) (xy 97.046796 -349.970598)
			(xy 97.033425 -350.005626) (xy 96.996921 -350.071111) (xy 96.974152 -350.1009) (xy 96.94672 -350.135698)
			(xy 96.94672 -352.384106) (xy 89.596976 -359.73385) (xy 89.596976 -359.812336) (xy 89.597405 -359.828089)
			(xy 89.605052 -359.858651) (xy 89.619969 -359.886399) (xy 89.641242 -359.909636) (xy 89.667568 -359.926939)
			(xy 89.68232 -359.932478) (xy 89.682574 -359.932478) (xy 89.720732 -359.946301) (xy 89.793908 -359.981411)
			(xy 89.862615 -360.024615) (xy 89.925963 -360.075353) (xy 89.98313 -360.132966) (xy 90.033375 -360.196706)
			(xy 90.055192 -360.230928) (xy 90.074544 -360.263131) (xy 90.107123 -360.330836) (xy 90.132386 -360.401597)
			(xy 90.150053 -360.474625) (xy 90.159925 -360.549109) (xy 90.161393 -360.60507) (xy 91.277697 -360.60507)
			(xy 91.281732 -360.529366) (xy 91.293791 -360.454521) (xy 91.313737 -360.38138) (xy 91.341344 -360.310775)
			(xy 91.3763 -360.243504) (xy 91.418208 -360.180329) (xy 91.466594 -360.121967) (xy 91.52091 -360.069079)
			(xy 91.580539 -360.022264) (xy 91.644807 -359.982052) (xy 91.712984 -359.9489) (xy 91.7843 -359.923182)
			(xy 91.857945 -359.90519) (xy 91.933085 -359.895128) (xy 92.008869 -359.893109) (xy 92.084439 -359.899158)
			(xy 92.158937 -359.913205) (xy 92.23152 -359.935091) (xy 92.301366 -359.964568) (xy 92.367683 -360.001303)
			(xy 92.429719 -360.044878) (xy 92.486772 -360.0948) (xy 92.538196 -360.150504) (xy 92.583407 -360.211359)
			(xy 92.621894 -360.276674) (xy 92.65322 -360.34571) (xy 92.67703 -360.417685) (xy 92.693055 -360.491783)
			(xy 92.701114 -360.567164) (xy 92.701618 -360.60507) (xy 92.701114 -360.642976) (xy 92.693055 -360.718357)
			(xy 92.67703 -360.792455) (xy 92.65322 -360.86443) (xy 92.621894 -360.933466) (xy 92.583407 -360.998781)
			(xy 92.538196 -361.059636) (xy 92.486772 -361.11534) (xy 92.429719 -361.165262) (xy 92.367683 -361.208837)
			(xy 92.301366 -361.245572) (xy 92.23152 -361.275049) (xy 92.158937 -361.296935) (xy 92.084439 -361.310982)
			(xy 92.008869 -361.317031) (xy 91.933085 -361.315012) (xy 91.857945 -361.30495) (xy 91.7843 -361.286958)
			(xy 91.712984 -361.26124) (xy 91.644807 -361.228088) (xy 91.580539 -361.187876) (xy 91.52091 -361.141061)
			(xy 91.466594 -361.088173) (xy 91.418208 -361.029811) (xy 91.3763 -360.966636) (xy 91.341344 -360.899365)
			(xy 91.313737 -360.82876) (xy 91.293791 -360.755619) (xy 91.281732 -360.680774) (xy 91.277697 -360.60507)
			(xy 90.161393 -360.60507) (xy 90.161895 -360.624219) (xy 90.155938 -360.699117) (xy 90.142123 -360.772971)
			(xy 90.120602 -360.844959) (xy 90.091616 -360.914277) (xy 90.055486 -360.980156) (xy 90.012616 -361.04186)
			(xy 89.963483 -361.098704) (xy 89.908633 -361.150054) (xy 89.848678 -361.195338) (xy 89.784285 -361.234053)
			(xy 89.716171 -361.265767) (xy 89.680796 -361.278424) (xy 89.659031 -361.286698) (xy 89.618721 -361.309994)
			(xy 89.583329 -361.340242) (xy 89.554038 -361.37643) (xy 89.531829 -361.417348) (xy 89.517444 -361.461628)
			(xy 89.511366 -361.507786) (xy 89.513796 -361.55428) (xy 89.524655 -361.599553) (xy 89.543578 -361.642091)
			(xy 89.569933 -361.68047) (xy 89.586054 -361.69727) (xy 89.62771 -361.738926) (xy 89.644539 -361.755029)
			(xy 89.682909 -361.781422) (xy 89.725447 -361.800379) (xy 89.770728 -361.811264) (xy 89.817235 -361.813713)
			(xy 89.863409 -361.807642) (xy 89.907703 -361.793256) (xy 89.948632 -361.771037) (xy 89.984825 -361.74173)
			(xy 90.015069 -361.706315) (xy 90.038351 -361.665981) (xy 90.046556 -361.644184) (xy 90.055337 -361.61941)
			(xy 90.076056 -361.571099) (xy 90.087958 -361.547664) (xy 90.106571 -361.512895) (xy 90.150372 -361.447307)
			(xy 90.201153 -361.386962) (xy 90.258292 -361.332599) (xy 90.321089 -361.284884) (xy 90.388776 -361.244402)
			(xy 90.460521 -361.211648) (xy 90.535447 -361.187024) (xy 90.612636 -361.170832) (xy 90.691141 -361.16327)
			(xy 90.730578 -361.163362) (xy 90.766559 -361.164355) (xy 90.838059 -361.172696) (xy 90.908351 -361.188214)
			(xy 90.976717 -361.210749) (xy 91.042459 -361.240071) (xy 91.104904 -361.275881) (xy 91.134438 -361.296458)
			(xy 91.165021 -361.318965) (xy 91.221698 -361.369503) (xy 91.272674 -361.425788) (xy 91.317367 -361.48718)
			(xy 91.355271 -361.552981) (xy 91.385954 -361.622444) (xy 91.409067 -361.694778) (xy 91.424348 -361.769162)
			(xy 91.431624 -361.84475) (xy 91.430811 -361.920683) (xy 91.421918 -361.996098) (xy 91.405047 -362.070138)
			(xy 91.38039 -362.14196) (xy 91.348227 -362.21075) (xy 91.308923 -362.275724) (xy 91.262925 -362.336145)
			(xy 91.210755 -362.391325) (xy 91.153008 -362.440638) (xy 91.090339 -362.483523) (xy 91.023461 -362.519492)
			(xy 90.953134 -362.548137) (xy 90.880156 -362.569131) (xy 90.805358 -362.582237) (xy 90.72959 -362.587306)
			(xy 90.653713 -362.584279) (xy 90.57859 -362.573192) (xy 90.505073 -362.55417) (xy 90.434 -362.527429)
			(xy 90.366178 -362.493274) (xy 90.302377 -362.452092) (xy 90.243323 -362.404352) (xy 90.189687 -362.350597)
			(xy 90.142078 -362.291437) (xy 90.101039 -362.227544) (xy 90.067035 -362.159646) (xy 90.040453 -362.088513)
			(xy 90.030554 -362.051854) (xy 90.030554 -362.0516) (xy 90.025864 -362.035498) (xy 90.009304 -362.006347)
			(xy 89.985723 -361.982516) (xy 89.956749 -361.965649) (xy 89.924381 -361.956912) (xy 89.907618 -361.95635)
			(xy 89.907364 -361.95635) (xy 89.890715 -361.956849) (xy 89.858553 -361.965477) (xy 89.829721 -361.982136)
			(xy 89.806183 -362.005689) (xy 89.789544 -362.034533) (xy 89.780938 -362.0667) (xy 89.780364 -362.08335)
			(xy 89.780364 -362.442252) (xy 89.780846 -362.458043) (xy 89.788613 -362.488655) (xy 89.803658 -362.516423)
			(xy 89.82506 -362.539647) (xy 89.838022 -362.548678) (xy 89.869627 -362.569834) (xy 89.928586 -362.617882)
			(xy 89.982085 -362.671944) (xy 90.029512 -362.731404) (xy 90.070327 -362.795583) (xy 90.104063 -362.863749)
			(xy 90.130337 -362.935124) (xy 90.148848 -363.008895) (xy 90.159385 -363.08422) (xy 90.161341 -363.14507)
			(xy 91.277697 -363.14507) (xy 91.281732 -363.069366) (xy 91.293791 -362.994521) (xy 91.313737 -362.92138)
			(xy 91.341344 -362.850775) (xy 91.3763 -362.783504) (xy 91.418208 -362.720329) (xy 91.466594 -362.661967)
			(xy 91.52091 -362.609079) (xy 91.580539 -362.562264) (xy 91.644807 -362.522052) (xy 91.712984 -362.4889)
			(xy 91.7843 -362.463182) (xy 91.857945 -362.44519) (xy 91.933085 -362.435128) (xy 92.008869 -362.433109)
			(xy 92.084439 -362.439158) (xy 92.158937 -362.453205) (xy 92.23152 -362.475091) (xy 92.301366 -362.504568)
			(xy 92.367683 -362.541303) (xy 92.429719 -362.584878) (xy 92.486772 -362.6348) (xy 92.538196 -362.690504)
			(xy 92.583407 -362.751359) (xy 92.621894 -362.816674) (xy 92.65322 -362.88571) (xy 92.67703 -362.957685)
			(xy 92.693055 -363.031783) (xy 92.701114 -363.107164) (xy 92.701618 -363.14507) (xy 92.701114 -363.182976)
			(xy 92.693055 -363.258357) (xy 92.67703 -363.332455) (xy 92.65322 -363.40443) (xy 92.621894 -363.473466)
			(xy 92.583407 -363.538781) (xy 92.538196 -363.599636) (xy 92.486772 -363.65534) (xy 92.429719 -363.705262)
			(xy 92.367683 -363.748837) (xy 92.301366 -363.785572) (xy 92.23152 -363.815049) (xy 92.158937 -363.836935)
			(xy 92.084439 -363.850982) (xy 92.008869 -363.857031) (xy 91.933085 -363.855012) (xy 91.857945 -363.84495)
			(xy 91.7843 -363.826958) (xy 91.712984 -363.80124) (xy 91.644807 -363.768088) (xy 91.580539 -363.727876)
			(xy 91.52091 -363.681061) (xy 91.466594 -363.628173) (xy 91.418208 -363.569811) (xy 91.3763 -363.506636)
			(xy 91.341344 -363.439365) (xy 91.313737 -363.36876) (xy 91.293791 -363.295619) (xy 91.281732 -363.220774)
			(xy 91.277697 -363.14507) (xy 90.161341 -363.14507) (xy 90.161829 -363.160238) (xy 90.15615 -363.236084)
			(xy 90.142414 -363.310891) (xy 90.120777 -363.383806) (xy 90.091487 -363.453998) (xy 90.054878 -363.520666)
			(xy 90.011367 -363.583048) (xy 89.96145 -363.640434) (xy 89.905697 -363.692168) (xy 89.844745 -363.737661)
			(xy 89.779288 -363.776393) (xy 89.710073 -363.807922) (xy 89.63789 -363.83189) (xy 89.563563 -363.848022)
			(xy 89.487939 -363.856134) (xy 89.411881 -363.856134) (xy 89.336257 -363.848022) (xy 89.26193 -363.83189)
			(xy 89.189747 -363.807922) (xy 89.120532 -363.776393) (xy 89.055075 -363.737661) (xy 88.994123 -363.692168)
			(xy 88.93837 -363.640434) (xy 88.888453 -363.583048) (xy 88.844942 -363.520666) (xy 88.808333 -363.453998)
			(xy 88.779043 -363.383806) (xy 88.757406 -363.310891) (xy 88.74367 -363.236084) (xy 88.737991 -363.160238)
			(xy 88.740435 -363.08422) (xy 88.750972 -363.008895) (xy 88.769483 -362.935124) (xy 88.795757 -362.863749)
			(xy 88.829493 -362.795583) (xy 88.870308 -362.731404) (xy 88.917735 -362.671944) (xy 88.971234 -362.617882)
			(xy 89.030193 -362.569834) (xy 89.061798 -362.548678) (xy 89.07477 -362.539657) (xy 89.096184 -362.516438)
			(xy 89.111231 -362.488665) (xy 89.118987 -362.458045) (xy 89.119456 -362.442252) (xy 89.119456 -362.166154)
			(xy 89.06891 -362.1151) (xy 89.049098 -362.095288) (xy 89.036927 -362.083935) (xy 89.008088 -362.067346)
			(xy 88.975944 -362.058761) (xy 88.942674 -362.058761) (xy 88.91053 -362.067346) (xy 88.881691 -362.083935)
			(xy 88.86952 -362.095288) (xy 88.850724 -362.114084) (xy 88.841072 -362.138214) (xy 88.827111 -362.172042)
			(xy 88.793222 -362.236908) (xy 88.752857 -362.297955) (xy 88.70644 -362.354537) (xy 88.654462 -362.406057)
			(xy 88.597472 -362.451972) (xy 88.536071 -362.491796) (xy 88.470908 -362.52511) (xy 88.436958 -362.538772)
			(xy 88.403707 -362.551173) (xy 88.335304 -362.570089) (xy 88.265359 -362.582107) (xy 88.194565 -362.587108)
			(xy 88.159082 -362.586524) (xy 88.119544 -362.584828) (xy 88.041182 -362.573755) (xy 87.96453 -362.554059)
			(xy 87.890537 -362.525984) (xy 87.820113 -362.489875) (xy 87.754128 -362.446179) (xy 87.693397 -362.395434)
			(xy 87.638668 -362.338267) (xy 87.614252 -362.307124) (xy 87.591918 -362.277094) (xy 87.552982 -362.213176)
			(xy 87.520968 -362.145526) (xy 87.496229 -362.074889) (xy 87.479039 -362.002047) (xy 87.469587 -361.927803)
			(xy 87.467979 -361.852977) (xy 87.47423 -361.778396) (xy 87.488273 -361.704882) (xy 87.509953 -361.633247)
			(xy 87.53903 -361.564283) (xy 87.575183 -361.498751) (xy 87.618012 -361.437374) (xy 87.667046 -361.38083)
			(xy 87.721742 -361.329744) (xy 87.781497 -361.284679) (xy 87.845651 -361.246133) (xy 87.913495 -361.214532)
			(xy 87.984281 -361.190224) (xy 88.057227 -361.173478) (xy 88.094312 -361.168442) (xy 88.142318 -361.1626)
			(xy 88.206072 -361.090718) (xy 88.206072 -359.640886) (xy 95.860616 -351.986596) (xy 95.871963 -351.974447)
			(xy 95.888546 -351.94565) (xy 95.897134 -351.913549) (xy 95.8977 -351.896934) (xy 95.8977 -351.852484)
			(xy 95.897291 -351.837805) (xy 95.890576 -351.809227) (xy 95.877486 -351.78295) (xy 95.858717 -351.760377)
			(xy 95.83527 -351.742711) (xy 95.822008 -351.736406) (xy 95.793578 -351.72321) (xy 95.740309 -351.690179)
			(xy 95.692045 -351.650189) (xy 95.649688 -351.603988) (xy 95.614031 -351.55244) (xy 95.585741 -351.496509)
			(xy 95.565347 -351.437241) (xy 95.55323 -351.375744) (xy 95.549617 -351.31317) (xy 95.554575 -351.250687)
			(xy 95.568012 -351.189466) (xy 95.589677 -351.13065) (xy 95.619164 -351.075341) (xy 95.655921 -351.024572)
			(xy 95.677228 -351.001584) (xy 95.677228 -349.187008) (xy 95.488252 -348.998032) (xy 95.488252 -348.995746)
			(xy 95.414084 -348.921578) (xy 94.21368 -348.921578) (xy 94.21368 -348.173802) (xy 94.206568 -348.153482)
			(xy 94.198009 -348.127124) (xy 94.188809 -348.072478) (xy 94.18828 -348.04477) (xy 94.18828 -347.206824)
			(xy 93.63202 -346.65031) (xy 93.63202 -341.314786) (xy 94.409006 -340.5378) (xy 94.414086 -340.493604)
			(xy 94.418064 -340.463098) (xy 94.433156 -340.403459) (xy 94.456102 -340.346379) (xy 94.48649 -340.292889)
			(xy 94.523772 -340.243952) (xy 94.567274 -340.200453) (xy 94.616213 -340.163175) (xy 94.669705 -340.13279)
			(xy 94.726786 -340.109847) (xy 94.786427 -340.094759) (xy 94.81693 -340.09076) (xy 94.861126 -340.08568)
			(xy 95.105982 -339.840824) (xy 95.152718 -339.793834) (xy 95.348044 -339.598508) (xy 95.348044 -338.207604)
			(xy 96.204024 -337.351624) (xy 96.204024 -336.032856) (xy 96.687132 -335.549748) (xy 96.687132 -327.817734)
			(xy 91.859354 -322.989956) (xy 90.46591 -322.989956) (xy 89.0143 -321.538346) (xy 89.0143 -320.736722)
			(xy 89.013787 -320.713533) (xy 89.005373 -320.667923) (xy 88.988819 -320.624599) (xy 88.964676 -320.585)
			(xy 88.933747 -320.55044) (xy 88.897058 -320.522069) (xy 88.855829 -320.500829) (xy 88.811429 -320.487425)
			(xy 88.765334 -320.482304) (xy 88.719075 -320.485634) (xy 88.674189 -320.497306) (xy 88.632167 -320.516932)
			(xy 88.61298 -320.529966) (xy 88.599539 -320.540122) (xy 88.571841 -320.559306) (xy 88.557608 -320.56832)
			(xy 88.525497 -320.587848) (xy 88.457946 -320.620801) (xy 88.387303 -320.646464) (xy 88.314352 -320.664552)
			(xy 88.277192 -320.670174) (xy 88.239083 -320.674926) (xy 88.162316 -320.677194) (xy 88.08575 -320.671182)
			(xy 88.010278 -320.656961) (xy 87.936775 -320.634696) (xy 87.866097 -320.604645) (xy 87.799066 -320.567159)
			(xy 87.736461 -320.522673) (xy 87.67901 -320.471704) (xy 87.627382 -320.414846) (xy 87.582176 -320.352759)
			(xy 87.543918 -320.286165) (xy 87.513054 -320.215839) (xy 87.489941 -320.142598) (xy 87.47485 -320.067294)
			(xy 87.467955 -319.990803) (xy 87.469336 -319.914015) (xy 87.478978 -319.837821) (xy 87.496768 -319.763109)
			(xy 87.522499 -319.690747) (xy 87.555873 -319.621577) (xy 87.596501 -319.556402) (xy 87.61984 -319.525904)
			(xy 87.631524 -319.511426) (xy 87.655012 -319.483738) (xy 87.706748 -319.432791) (xy 87.763406 -319.387381)
			(xy 87.824398 -319.347982) (xy 87.889087 -319.315003) (xy 87.9568 -319.288789) (xy 87.991696 -319.278762)
			(xy 88.007539 -319.273867) (xy 88.036172 -319.257169) (xy 88.059539 -319.23366) (xy 88.076064 -319.204926)
			(xy 88.084634 -319.172907) (xy 88.085168 -319.156334) (xy 88.085168 -318.233806) (xy 88.084634 -318.217231)
			(xy 88.076084 -318.185204) (xy 88.059562 -318.156465) (xy 88.036186 -318.132961) (xy 88.007538 -318.116283)
			(xy 87.991696 -318.111378) (xy 87.956554 -318.101256) (xy 87.888378 -318.074781) (xy 87.823277 -318.041453)
			(xy 87.761939 -318.001623) (xy 87.705009 -317.955712) (xy 87.653088 -317.904204) (xy 87.606725 -317.847642)
			(xy 87.566408 -317.786622) (xy 87.532562 -317.721789) (xy 87.505545 -317.653827) (xy 87.485641 -317.583451)
			(xy 87.47306 -317.511406) (xy 87.467936 -317.43845) (xy 87.470322 -317.365353) (xy 87.474806 -317.329058)
			(xy 87.480107 -317.293411) (xy 87.496972 -317.223339) (xy 87.52083 -317.15533) (xy 87.551436 -317.090079)
			(xy 87.588478 -317.028254) (xy 87.60968 -316.999112) (xy 87.633273 -316.968381) (xy 87.686106 -316.911707)
			(xy 87.744783 -316.861107) (xy 87.808608 -316.817181) (xy 87.876827 -316.780447) (xy 87.948633 -316.75134)
			(xy 88.023175 -316.730206) (xy 88.061292 -316.723268) (xy 88.10206 -316.71701) (xy 88.184436 -316.712811)
			(xy 88.22563 -316.714886) (xy 88.264458 -316.717907) (xy 88.341172 -316.731359) (xy 88.415958 -316.753109)
			(xy 88.487922 -316.782895) (xy 88.556202 -316.820363) (xy 88.619983 -316.865063) (xy 88.6785 -316.916461)
			(xy 88.731054 -316.973942) (xy 88.777017 -317.036818) (xy 88.815838 -317.104338) (xy 88.847053 -317.175693)
			(xy 88.859106 -317.212726) (xy 88.868504 -317.242444) (xy 88.890602 -317.264542) (xy 88.902734 -317.276003)
			(xy 88.931613 -317.292712) (xy 88.963836 -317.301363) (xy 88.9972 -317.301363) (xy 89.029423 -317.292712)
			(xy 89.058302 -317.276003) (xy 89.070434 -317.264542) (xy 89.119456 -317.21552) (xy 89.119456 -316.857888)
			(xy 89.118978 -316.842096) (xy 89.111216 -316.811482) (xy 89.09617 -316.783713) (xy 89.074762 -316.760492)
			(xy 89.061798 -316.751462) (xy 89.030193 -316.730306) (xy 88.971234 -316.682258) (xy 88.917735 -316.628196)
			(xy 88.870308 -316.568736) (xy 88.829493 -316.504557) (xy 88.795757 -316.436391) (xy 88.769483 -316.365016)
			(xy 88.750972 -316.291245) (xy 88.740435 -316.21592) (xy 88.737991 -316.139902) (xy 88.74367 -316.064056)
			(xy 88.757406 -315.989249) (xy 88.779043 -315.916334) (xy 88.808333 -315.846142) (xy 88.844942 -315.779474)
			(xy 88.888453 -315.717092) (xy 88.93837 -315.659706) (xy 88.994123 -315.607972) (xy 89.055075 -315.562479)
			(xy 89.120532 -315.523747) (xy 89.189747 -315.492218) (xy 89.26193 -315.46825) (xy 89.336257 -315.452118)
			(xy 89.411881 -315.444006) (xy 89.487939 -315.444006) (xy 89.563563 -315.452118) (xy 89.63789 -315.46825)
			(xy 89.710073 -315.492218) (xy 89.779288 -315.523747) (xy 89.844745 -315.562479) (xy 89.905697 -315.607972)
			(xy 89.96145 -315.659706) (xy 90.011367 -315.717092) (xy 90.054878 -315.779474) (xy 90.091487 -315.846142)
			(xy 90.120777 -315.916334) (xy 90.142414 -315.989249) (xy 90.15615 -316.064056) (xy 90.161829 -316.139902)
			(xy 90.161341 -316.15507) (xy 91.277697 -316.15507) (xy 91.281732 -316.079366) (xy 91.293791 -316.004521)
			(xy 91.313737 -315.93138) (xy 91.341344 -315.860775) (xy 91.3763 -315.793504) (xy 91.418208 -315.730329)
			(xy 91.466594 -315.671967) (xy 91.52091 -315.619079) (xy 91.580539 -315.572264) (xy 91.644807 -315.532052)
			(xy 91.712984 -315.4989) (xy 91.7843 -315.473182) (xy 91.857945 -315.45519) (xy 91.933085 -315.445128)
			(xy 92.008869 -315.443109) (xy 92.084439 -315.449158) (xy 92.158937 -315.463205) (xy 92.23152 -315.485091)
			(xy 92.301366 -315.514568) (xy 92.367683 -315.551303) (xy 92.429719 -315.594878) (xy 92.486772 -315.6448)
			(xy 92.538196 -315.700504) (xy 92.583407 -315.761359) (xy 92.621894 -315.826674) (xy 92.65322 -315.89571)
			(xy 92.67703 -315.967685) (xy 92.693055 -316.041783) (xy 92.701114 -316.117164) (xy 92.701618 -316.15507)
			(xy 92.701114 -316.192976) (xy 92.693055 -316.268357) (xy 92.67703 -316.342455) (xy 92.65322 -316.41443)
			(xy 92.621894 -316.483466) (xy 92.583407 -316.548781) (xy 92.538196 -316.609636) (xy 92.486772 -316.66534)
			(xy 92.429719 -316.715262) (xy 92.367683 -316.758837) (xy 92.301366 -316.795572) (xy 92.23152 -316.825049)
			(xy 92.158937 -316.846935) (xy 92.084439 -316.860982) (xy 92.008869 -316.867031) (xy 91.933085 -316.865012)
			(xy 91.857945 -316.85495) (xy 91.7843 -316.836958) (xy 91.712984 -316.81124) (xy 91.644807 -316.778088)
			(xy 91.580539 -316.737876) (xy 91.52091 -316.691061) (xy 91.466594 -316.638173) (xy 91.418208 -316.579811)
			(xy 91.3763 -316.516636) (xy 91.341344 -316.449365) (xy 91.313737 -316.37876) (xy 91.293791 -316.305619)
			(xy 91.281732 -316.230774) (xy 91.277697 -316.15507) (xy 90.161341 -316.15507) (xy 90.159385 -316.21592)
			(xy 90.148848 -316.291245) (xy 90.130337 -316.365016) (xy 90.104063 -316.436391) (xy 90.070327 -316.504557)
			(xy 90.029512 -316.568736) (xy 89.982085 -316.628196) (xy 89.928586 -316.682258) (xy 89.869627 -316.730306)
			(xy 89.838022 -316.751462) (xy 89.825051 -316.760483) (xy 89.803641 -316.783703) (xy 89.7886 -316.811476)
			(xy 89.780853 -316.842096) (xy 89.780364 -316.857888) (xy 89.780364 -317.21679) (xy 89.780906 -317.233441)
			(xy 89.789521 -317.265609) (xy 89.806168 -317.294452) (xy 89.829712 -317.318004) (xy 89.858548 -317.334661)
			(xy 89.890713 -317.343288) (xy 89.907364 -317.34379) (xy 89.907618 -317.34379) (xy 89.924382 -317.343277)
			(xy 89.956749 -317.334531) (xy 89.985717 -317.31765) (xy 90.009282 -317.293799) (xy 90.025814 -317.264631)
			(xy 90.030554 -317.24854) (xy 90.030554 -317.248286) (xy 90.040133 -317.21281) (xy 90.065634 -317.143888)
			(xy 90.098094 -317.077958) (xy 90.137169 -317.015719) (xy 90.182444 -316.957834) (xy 90.207592 -316.93104)
			(xy 90.231946 -316.906387) (xy 90.284677 -316.861417) (xy 90.341526 -316.821782) (xy 90.401957 -316.787855)
			(xy 90.465397 -316.759959) (xy 90.531246 -316.738356) (xy 90.56497 -316.73038) (xy 90.601921 -316.722648)
			(xy 90.676931 -316.714106) (xy 90.752424 -316.713552) (xy 90.827552 -316.720991) (xy 90.901471 -316.73634)
			(xy 90.97335 -316.759426) (xy 91.042381 -316.78999) (xy 91.10779 -316.827689) (xy 91.168842 -316.872099)
			(xy 91.22485 -316.922722) (xy 91.275186 -316.978988) (xy 91.319283 -317.040265) (xy 91.356648 -317.105866)
			(xy 91.386859 -317.175053) (xy 91.409578 -317.247048) (xy 91.424549 -317.321044) (xy 91.431605 -317.396209)
			(xy 91.431618 -317.43396) (xy 91.430675 -317.471345) (xy 91.421909 -317.545616) (xy 91.405403 -317.618559)
			(xy 91.381339 -317.689369) (xy 91.349984 -317.757265) (xy 91.311683 -317.8215) (xy 91.266858 -317.881365)
			(xy 91.216002 -317.936199) (xy 91.159678 -317.9854) (xy 91.098505 -318.028423) (xy 91.033159 -318.064795)
			(xy 90.964358 -318.094114) (xy 90.892863 -318.116059) (xy 90.819462 -318.130386) (xy 90.744962 -318.136937)
			(xy 90.670186 -318.135641) (xy 90.595959 -318.126512) (xy 90.523097 -318.10965) (xy 90.452406 -318.085242)
			(xy 90.384663 -318.053555) (xy 90.320616 -318.014941) (xy 90.260971 -317.969824) (xy 90.206385 -317.918701)
			(xy 90.15746 -317.862138) (xy 90.114736 -317.800756) (xy 90.078684 -317.735232) (xy 90.063828 -317.700914)
			(xy 90.054605 -317.680243) (xy 90.029957 -317.642284) (xy 89.998974 -317.609291) (xy 89.962636 -317.58231)
			(xy 89.922093 -317.562192) (xy 89.878628 -317.549574) (xy 89.833615 -317.544857) (xy 89.788478 -317.548187)
			(xy 89.744645 -317.559462) (xy 89.703502 -317.578323) (xy 89.666352 -317.604174) (xy 89.650062 -317.619888)
			(xy 89.644728 -317.625222) (xy 89.629094 -317.64157) (xy 89.603296 -317.67872) (xy 89.584478 -317.719849)
			(xy 89.573234 -317.763658) (xy 89.569919 -317.808766) (xy 89.574637 -317.853749) (xy 89.58724 -317.897187)
			(xy 89.607331 -317.937709) (xy 89.634274 -317.974038) (xy 89.66722 -318.005026) (xy 89.705129 -318.029696)
			(xy 89.725754 -318.038988) (xy 89.759467 -318.05367) (xy 89.823949 -318.089021) (xy 89.884444 -318.13083)
			(xy 89.940307 -318.178653) (xy 89.990942 -318.23198) (xy 90.03581 -318.290242) (xy 90.074433 -318.352819)
			(xy 90.106399 -318.419044) (xy 90.131368 -318.488212) (xy 90.149074 -318.559586) (xy 90.159328 -318.632404)
			(xy 90.161624 -318.69507) (xy 91.277697 -318.69507) (xy 91.281732 -318.619366) (xy 91.293791 -318.544521)
			(xy 91.313737 -318.47138) (xy 91.341344 -318.400775) (xy 91.3763 -318.333504) (xy 91.418208 -318.270329)
			(xy 91.466594 -318.211967) (xy 91.52091 -318.159079) (xy 91.580539 -318.112264) (xy 91.644807 -318.072052)
			(xy 91.712984 -318.0389) (xy 91.7843 -318.013182) (xy 91.857945 -317.99519) (xy 91.933085 -317.985128)
			(xy 92.008869 -317.983109) (xy 92.084439 -317.989158) (xy 92.158937 -318.003205) (xy 92.23152 -318.025091)
			(xy 92.301366 -318.054568) (xy 92.367683 -318.091303) (xy 92.429719 -318.134878) (xy 92.486772 -318.1848)
			(xy 92.538196 -318.240504) (xy 92.583407 -318.301359) (xy 92.621894 -318.366674) (xy 92.65322 -318.43571)
			(xy 92.67703 -318.507685) (xy 92.693055 -318.581783) (xy 92.701114 -318.657164) (xy 92.701618 -318.69507)
			(xy 92.701114 -318.732976) (xy 92.693055 -318.808357) (xy 92.67703 -318.882455) (xy 92.65322 -318.95443)
			(xy 92.621894 -319.023466) (xy 92.583407 -319.088781) (xy 92.538196 -319.149636) (xy 92.486772 -319.20534)
			(xy 92.429719 -319.255262) (xy 92.367683 -319.298837) (xy 92.301366 -319.335572) (xy 92.23152 -319.365049)
			(xy 92.158937 -319.386935) (xy 92.084439 -319.400982) (xy 92.008869 -319.407031) (xy 91.933085 -319.405012)
			(xy 91.857945 -319.39495) (xy 91.7843 -319.376958) (xy 91.712984 -319.35124) (xy 91.644807 -319.318088)
			(xy 91.580539 -319.277876) (xy 91.52091 -319.231061) (xy 91.466594 -319.178173) (xy 91.418208 -319.119811)
			(xy 91.3763 -319.056636) (xy 91.341344 -318.989365) (xy 91.313737 -318.91876) (xy 91.293791 -318.845619)
			(xy 91.281732 -318.770774) (xy 91.277697 -318.69507) (xy 90.161624 -318.69507) (xy 90.162021 -318.705891)
			(xy 90.157124 -318.779265) (xy 90.144689 -318.851742) (xy 90.124849 -318.922552) (xy 90.111834 -318.956944)
			(xy 90.102944 -318.979296) (xy 90.102944 -319.070228) (xy 90.103419 -319.092517) (xy 90.111214 -319.136409)
			(xy 90.126544 -319.178269) (xy 90.148938 -319.216814) (xy 90.17771 -319.250865) (xy 90.211979 -319.279376)
			(xy 90.250694 -319.301475) (xy 90.29267 -319.316485) (xy 90.33662 -319.323945) (xy 90.381198 -319.323627)
			(xy 90.425037 -319.315541) (xy 90.446098 -319.308226) (xy 90.481197 -319.294137) (xy 90.553703 -319.272605)
			(xy 90.628084 -319.258885) (xy 90.7035 -319.25313) (xy 90.779102 -319.255406) (xy 90.854035 -319.265688)
			(xy 90.927456 -319.283858) (xy 90.998535 -319.309713) (xy 91.066472 -319.34296) (xy 91.130499 -319.383225)
			(xy 91.164561 -319.41008) (xy 93.154506 -319.41008) (xy 93.158522 -319.29381) (xy 93.170549 -319.178095)
			(xy 93.190531 -319.063485) (xy 93.218373 -318.950526) (xy 93.253942 -318.839758) (xy 93.297068 -318.731707)
			(xy 93.347545 -318.626889) (xy 93.405134 -318.525804) (xy 93.46956 -318.428932) (xy 93.540515 -318.336736)
			(xy 93.617662 -318.249655) (xy 93.700633 -318.168104) (xy 93.789033 -318.092472) (xy 93.88244 -318.023118)
			(xy 93.980409 -317.960375) (xy 94.082473 -317.904539) (xy 94.188147 -317.855878) (xy 94.296926 -317.814624)
			(xy 94.408291 -317.780973) (xy 94.521714 -317.755085) (xy 94.636651 -317.737084) (xy 94.752557 -317.727055)
			(xy 94.868879 -317.725047) (xy 94.985062 -317.731069) (xy 95.100553 -317.745092) (xy 95.214801 -317.76705)
			(xy 95.327262 -317.796837) (xy 95.4374 -317.834312) (xy 95.54469 -317.879297) (xy 95.648621 -317.931576)
			(xy 95.748697 -317.990901) (xy 95.844443 -318.056989) (xy 95.9354 -318.129525) (xy 96.021136 -318.208164)
			(xy 96.101243 -318.29253) (xy 96.175339 -318.382222) (xy 96.243069 -318.476812) (xy 96.304113 -318.57585)
			(xy 96.358178 -318.678863) (xy 96.405008 -318.78536) (xy 96.444379 -318.894835) (xy 96.476103 -319.006765)
			(xy 96.500029 -319.120617) (xy 96.516043 -319.235849) (xy 96.52407 -319.351911) (xy 96.524572 -319.41008)
			(xy 96.52407 -319.468249) (xy 96.516043 -319.584311) (xy 96.500029 -319.699543) (xy 96.476103 -319.813395)
			(xy 96.444379 -319.925325) (xy 96.405008 -320.0348) (xy 96.358178 -320.141297) (xy 96.304113 -320.24431)
			(xy 96.243069 -320.343348) (xy 96.175339 -320.437938) (xy 96.101243 -320.52763) (xy 96.021136 -320.611996)
			(xy 95.9354 -320.690635) (xy 95.844443 -320.763171) (xy 95.748697 -320.829259) (xy 95.648621 -320.888584)
			(xy 95.54469 -320.940863) (xy 95.4374 -320.985848) (xy 95.327262 -321.023323) (xy 95.214801 -321.05311)
			(xy 95.100553 -321.075068) (xy 94.985062 -321.089091) (xy 94.868879 -321.095113) (xy 94.752557 -321.093105)
			(xy 94.636651 -321.083076) (xy 94.521714 -321.065075) (xy 94.408291 -321.039187) (xy 94.296926 -321.005536)
			(xy 94.188147 -320.964282) (xy 94.082473 -320.915621) (xy 93.980409 -320.859785) (xy 93.88244 -320.797042)
			(xy 93.789033 -320.727688) (xy 93.700633 -320.652056) (xy 93.617662 -320.570505) (xy 93.540515 -320.483424)
			(xy 93.46956 -320.391228) (xy 93.405134 -320.294356) (xy 93.347545 -320.193271) (xy 93.297068 -320.088453)
			(xy 93.253942 -319.980402) (xy 93.218373 -319.869634) (xy 93.190531 -319.756675) (xy 93.170549 -319.642065)
			(xy 93.158522 -319.52635) (xy 93.154506 -319.41008) (xy 91.164561 -319.41008) (xy 91.189895 -319.430054)
			(xy 91.243989 -319.482917) (xy 91.292172 -319.54122) (xy 91.3339 -319.604303) (xy 91.368702 -319.671457)
			(xy 91.396185 -319.741922) (xy 91.41604 -319.814905) (xy 91.428043 -319.889583) (xy 91.432059 -319.965112)
			(xy 91.428041 -320.04064) (xy 91.416036 -320.115317) (xy 91.396178 -320.1883) (xy 91.368692 -320.258764)
			(xy 91.333888 -320.325917) (xy 91.292158 -320.388999) (xy 91.243974 -320.4473) (xy 91.189878 -320.500162)
			(xy 91.13048 -320.546988) (xy 91.066452 -320.587251) (xy 90.998514 -320.620496) (xy 90.927434 -320.646349)
			(xy 90.854013 -320.664517) (xy 90.779079 -320.674796) (xy 90.703477 -320.677069) (xy 90.628061 -320.671312)
			(xy 90.553681 -320.657589) (xy 90.481175 -320.636055) (xy 90.446098 -320.621914) (xy 90.425053 -320.614517)
			(xy 90.381197 -320.606384) (xy 90.336595 -320.606032) (xy 90.292616 -320.613474) (xy 90.250612 -320.628481)
			(xy 90.211874 -320.65059) (xy 90.177591 -320.679124) (xy 90.148816 -320.713205) (xy 90.126434 -320.751787)
			(xy 90.111133 -320.793684) (xy 90.103382 -320.83761) (xy 90.102944 -320.859912) (xy 90.102944 -321.166236)
			(xy 90.8939 -321.957192) (xy 92.28709 -321.957192) (xy 96.992694 -326.662542) (xy 97.009095 -326.677392)
			(xy 97.046021 -326.701758) (xy 97.086611 -326.719356) (xy 97.129636 -326.729654) (xy 97.173794 -326.73234)
			(xy 97.21775 -326.727333) (xy 97.260174 -326.714785) (xy 97.299781 -326.695076) (xy 97.335374 -326.668801)
			(xy 97.365874 -326.636755) (xy 97.37852 -326.6186) (xy 97.37852 -314.258706) (xy 91.484196 -308.364382)
			(xy 91.484196 -295.63695) (xy 97.211388 -289.910012) (xy 97.222738 -289.897864) (xy 97.239329 -289.869069)
			(xy 97.247922 -289.836966) (xy 97.248472 -289.82035) (xy 97.248472 -283.36367) (xy 91.819222 -277.93442)
			(xy 90.221562 -277.93442) (xy 88.814148 -276.52726) (xy 88.814148 -276.242526) (xy 88.801238 -276.224027)
			(xy 88.769997 -276.191492) (xy 88.733505 -276.164981) (xy 88.692907 -276.145325) (xy 88.649478 -276.133143)
			(xy 88.60458 -276.128815) (xy 88.559624 -276.132479) (xy 88.516019 -276.144019) (xy 88.495378 -276.153118)
			(xy 88.463878 -276.168213) (xy 88.398528 -276.192889) (xy 88.331076 -276.211051) (xy 88.26217 -276.222523)
			(xy 88.192472 -276.227195) (xy 88.122652 -276.225023) (xy 88.087962 -276.220936) (xy 88.05086 -276.215623)
			(xy 87.97796 -276.198195) (xy 87.907295 -276.173203) (xy 87.839648 -276.140923) (xy 87.775767 -276.101713)
			(xy 87.71636 -276.056008) (xy 87.662085 -276.004313) (xy 87.613543 -275.9472) (xy 87.571271 -275.885303)
			(xy 87.535738 -275.819306) (xy 87.507336 -275.749941) (xy 87.486381 -275.677976) (xy 87.473105 -275.604206)
			(xy 87.467654 -275.529451) (xy 87.470089 -275.454536) (xy 87.480383 -275.380291) (xy 87.498421 -275.30754)
			(xy 87.524005 -275.237087) (xy 87.556851 -275.169713) (xy 87.596595 -275.106163) (xy 87.642797 -275.047141)
			(xy 87.694945 -274.993302) (xy 87.752463 -274.94524) (xy 87.814712 -274.903489) (xy 87.847678 -274.885658)
			(xy 87.883416 -274.867397) (xy 87.958146 -274.838121) (xy 87.996776 -274.827238) (xy 88.012707 -274.822424)
			(xy 88.041536 -274.805824) (xy 88.065094 -274.782336) (xy 88.081779 -274.753557) (xy 88.090457 -274.721442)
			(xy 88.09101 -274.70481) (xy 88.091264 -274.627086) (xy 88.0618 -274.556728) (xy 88.0618 -273.83105)
			(xy 88.06307 -273.82978) (xy 88.06307 -273.725132) (xy 88.003126 -273.665188) (xy 87.972646 -273.656044)
			(xy 87.935868 -273.644322) (xy 87.864885 -273.613986) (xy 87.797601 -273.576146) (xy 87.734807 -273.531249)
			(xy 87.677239 -273.479819) (xy 87.625575 -273.422463) (xy 87.580421 -273.359852) (xy 87.542307 -273.292724)
			(xy 87.511681 -273.221865) (xy 87.488902 -273.148108) (xy 87.474239 -273.072319) (xy 87.467862 -272.995389)
			(xy 87.469848 -272.91822) (xy 87.480172 -272.841719) (xy 87.498714 -272.766785) (xy 87.525256 -272.694297)
			(xy 87.559485 -272.625107) (xy 87.601001 -272.560027) (xy 87.649316 -272.499822) (xy 87.676228 -272.47215)
			(xy 87.703828 -272.445243) (xy 87.763865 -272.396897) (xy 87.828776 -272.355323) (xy 87.8978 -272.321007)
			(xy 87.970128 -272.294351) (xy 88.044913 -272.275667) (xy 88.121278 -272.265175) (xy 88.198331 -272.262997)
			(xy 88.275168 -272.269159) (xy 88.350889 -272.283588) (xy 88.424607 -272.306116) (xy 88.495459 -272.336478)
			(xy 88.562614 -272.374319) (xy 88.625287 -272.419196) (xy 88.682743 -272.470583) (xy 88.73431 -272.527879)
			(xy 88.779382 -272.590411) (xy 88.817433 -272.657448) (xy 88.833198 -272.692622) (xy 88.848184 -272.727674)
			(xy 88.911684 -272.76933) (xy 88.949784 -272.76933) (xy 88.966435 -272.768789) (xy 88.998604 -272.760174)
			(xy 89.027447 -272.743528) (xy 89.051 -272.719984) (xy 89.067657 -272.691147) (xy 89.076283 -272.658981)
			(xy 89.076784 -272.64233) (xy 89.076784 -272.378424) (xy 89.076347 -272.363594) (xy 89.069498 -272.334734)
			(xy 89.056187 -272.308227) (xy 89.037128 -272.285499) (xy 89.025476 -272.276316) (xy 88.995353 -272.253306)
			(xy 88.939655 -272.201885) (xy 88.889738 -272.144834) (xy 88.846168 -272.082801) (xy 88.809438 -272.016488)
			(xy 88.779965 -271.946647) (xy 88.758083 -271.874069) (xy 88.744039 -271.799576) (xy 88.737993 -271.724012)
			(xy 88.740012 -271.648234) (xy 88.750075 -271.573099) (xy 88.768067 -271.49946) (xy 88.793784 -271.42815)
			(xy 88.826936 -271.359978) (xy 88.867145 -271.295716) (xy 88.913958 -271.236092) (xy 88.966843 -271.181781)
			(xy 89.025201 -271.133399) (xy 89.088371 -271.091495) (xy 89.155637 -271.056542) (xy 89.226237 -271.028937)
			(xy 89.299372 -271.008993) (xy 89.374212 -270.996935) (xy 89.44991 -270.992901) (xy 89.525608 -270.996935)
			(xy 89.600448 -271.008993) (xy 89.673583 -271.028937) (xy 89.744183 -271.056542) (xy 89.811449 -271.091495)
			(xy 89.874619 -271.133399) (xy 89.932977 -271.181781) (xy 89.985862 -271.236092) (xy 90.032675 -271.295716)
			(xy 90.072884 -271.359978) (xy 90.106036 -271.42815) (xy 90.131753 -271.49946) (xy 90.149745 -271.573099)
			(xy 90.159808 -271.648234) (xy 90.161322 -271.70507) (xy 91.277697 -271.70507) (xy 91.281732 -271.629366)
			(xy 91.293791 -271.554521) (xy 91.313737 -271.48138) (xy 91.341344 -271.410775) (xy 91.3763 -271.343504)
			(xy 91.418208 -271.280329) (xy 91.466594 -271.221967) (xy 91.52091 -271.169079) (xy 91.580539 -271.122264)
			(xy 91.644807 -271.082052) (xy 91.712984 -271.0489) (xy 91.7843 -271.023182) (xy 91.857945 -271.00519)
			(xy 91.933085 -270.995128) (xy 92.008869 -270.993109) (xy 92.084439 -270.999158) (xy 92.158937 -271.013205)
			(xy 92.23152 -271.035091) (xy 92.301366 -271.064568) (xy 92.367683 -271.101303) (xy 92.429719 -271.144878)
			(xy 92.486772 -271.1948) (xy 92.538196 -271.250504) (xy 92.583407 -271.311359) (xy 92.621894 -271.376674)
			(xy 92.65322 -271.44571) (xy 92.67703 -271.517685) (xy 92.693055 -271.591783) (xy 92.701114 -271.667164)
			(xy 92.701618 -271.70507) (xy 92.701114 -271.742976) (xy 92.693055 -271.818357) (xy 92.67703 -271.892455)
			(xy 92.65322 -271.96443) (xy 92.621894 -272.033466) (xy 92.583407 -272.098781) (xy 92.538196 -272.159636)
			(xy 92.486772 -272.21534) (xy 92.429719 -272.265262) (xy 92.367683 -272.308837) (xy 92.301366 -272.345572)
			(xy 92.23152 -272.375049) (xy 92.158937 -272.396935) (xy 92.084439 -272.410982) (xy 92.008869 -272.417031)
			(xy 91.933085 -272.415012) (xy 91.857945 -272.40495) (xy 91.7843 -272.386958) (xy 91.712984 -272.36124)
			(xy 91.644807 -272.328088) (xy 91.580539 -272.287876) (xy 91.52091 -272.241061) (xy 91.466594 -272.188173)
			(xy 91.418208 -272.129811) (xy 91.3763 -272.066636) (xy 91.341344 -271.999365) (xy 91.313737 -271.92876)
			(xy 91.293791 -271.855619) (xy 91.281732 -271.780774) (xy 91.277697 -271.70507) (xy 90.161322 -271.70507)
			(xy 90.161827 -271.724012) (xy 90.155781 -271.799576) (xy 90.141737 -271.874069) (xy 90.119855 -271.946647)
			(xy 90.090382 -272.016488) (xy 90.053652 -272.082801) (xy 90.010082 -272.144834) (xy 89.960165 -272.201885)
			(xy 89.904467 -272.253306) (xy 89.874344 -272.276316) (xy 89.862659 -272.28547) (xy 89.843552 -272.308178)
			(xy 89.830231 -272.334698) (xy 89.823423 -272.363584) (xy 89.823036 -272.378424) (xy 89.823036 -272.64233)
			(xy 89.823534 -272.65898) (xy 89.832161 -272.691145) (xy 89.848819 -272.71998) (xy 89.872372 -272.743521)
			(xy 89.901217 -272.760164) (xy 89.933385 -272.768774) (xy 89.950036 -272.76933) (xy 89.988136 -272.76933)
			(xy 90.051382 -272.727928) (xy 90.066622 -272.692622) (xy 90.081354 -272.660872) (xy 90.098687 -272.626801)
			(xy 90.139605 -272.562229) (xy 90.187209 -272.502413) (xy 90.240949 -272.448045) (xy 90.300206 -272.399749)
			(xy 90.364299 -272.358082) (xy 90.432487 -272.323524) (xy 90.503987 -272.296474) (xy 90.577974 -272.277243)
			(xy 90.653597 -272.266052) (xy 90.729983 -272.26303) (xy 90.806252 -272.268213) (xy 90.881527 -272.28154)
			(xy 90.954941 -272.302859) (xy 91.025646 -272.331922) (xy 91.092829 -272.368396) (xy 91.155716 -272.411861)
			(xy 91.213583 -272.461815) (xy 91.265762 -272.517683) (xy 91.311653 -272.578822) (xy 91.350727 -272.644527)
			(xy 91.382534 -272.714042) (xy 91.406707 -272.786565) (xy 91.422968 -272.861261) (xy 91.43113 -272.93727)
			(xy 91.431099 -273.013716) (xy 91.427554 -273.051778) (xy 91.423112 -273.088423) (xy 91.407601 -273.160596)
			(xy 91.384697 -273.230774) (xy 91.354645 -273.298201) (xy 91.336622 -273.330416) (xy 91.317344 -273.362891)
			(xy 91.272931 -273.423977) (xy 91.222299 -273.480016) (xy 91.166017 -273.530378) (xy 91.104719 -273.574498)
			(xy 91.039093 -273.611878) (xy 90.969878 -273.642099) (xy 90.897852 -273.664821) (xy 90.823825 -273.679787)
			(xy 90.748629 -273.686831) (xy 90.67311 -273.685872) (xy 90.598117 -273.676921) (xy 90.524494 -273.66008)
			(xy 90.453068 -273.635537) (xy 90.384643 -273.603568) (xy 90.319988 -273.564533) (xy 90.25983 -273.518871)
			(xy 90.204845 -273.467096) (xy 90.155652 -273.409789) (xy 90.112804 -273.347595) (xy 90.094308 -273.314668)
			(xy 90.08258 -273.29415) (xy 90.052751 -273.257499) (xy 90.016661 -273.226993) (xy 89.975554 -273.203684)
			(xy 89.930846 -273.188376) (xy 89.88408 -273.181595) (xy 89.836866 -273.183577) (xy 89.790832 -273.194252)
			(xy 89.747564 -273.213253) (xy 89.708555 -273.239924) (xy 89.691464 -273.256248) (xy 89.621868 -273.325844)
			(xy 89.617689 -273.349423) (xy 89.617209 -273.397301) (xy 89.625706 -273.444421) (xy 89.642878 -273.489116)
			(xy 89.668118 -273.529804) (xy 89.700532 -273.565043) (xy 89.738974 -273.593588) (xy 89.760298 -273.604482)
			(xy 89.793392 -273.621043) (xy 89.856285 -273.660048) (xy 89.914792 -273.705369) (xy 89.968281 -273.756515)
			(xy 90.016174 -273.812934) (xy 90.057956 -273.874018) (xy 90.093175 -273.939107) (xy 90.12145 -274.007499)
			(xy 90.142478 -274.078456) (xy 90.15603 -274.151211) (xy 90.16196 -274.22498) (xy 90.161483 -274.24507)
			(xy 91.277697 -274.24507) (xy 91.281732 -274.169366) (xy 91.293791 -274.094521) (xy 91.313737 -274.02138)
			(xy 91.341344 -273.950775) (xy 91.3763 -273.883504) (xy 91.418208 -273.820329) (xy 91.466594 -273.761967)
			(xy 91.52091 -273.709079) (xy 91.580539 -273.662264) (xy 91.644807 -273.622052) (xy 91.712984 -273.5889)
			(xy 91.7843 -273.563182) (xy 91.857945 -273.54519) (xy 91.933085 -273.535128) (xy 92.008869 -273.533109)
			(xy 92.084439 -273.539158) (xy 92.158937 -273.553205) (xy 92.23152 -273.575091) (xy 92.301366 -273.604568)
			(xy 92.367683 -273.641303) (xy 92.429719 -273.684878) (xy 92.486772 -273.7348) (xy 92.538196 -273.790504)
			(xy 92.583407 -273.851359) (xy 92.621894 -273.916674) (xy 92.65322 -273.98571) (xy 92.67703 -274.057685)
			(xy 92.693055 -274.131783) (xy 92.701114 -274.207164) (xy 92.701618 -274.24507) (xy 92.701114 -274.282976)
			(xy 92.693055 -274.358357) (xy 92.67703 -274.432455) (xy 92.65322 -274.50443) (xy 92.621894 -274.573466)
			(xy 92.583407 -274.638781) (xy 92.538196 -274.699636) (xy 92.486772 -274.75534) (xy 92.429719 -274.805262)
			(xy 92.367683 -274.848837) (xy 92.301366 -274.885572) (xy 92.23152 -274.915049) (xy 92.158937 -274.936935)
			(xy 92.084439 -274.950982) (xy 92.008869 -274.957031) (xy 91.933085 -274.955012) (xy 91.857945 -274.94495)
			(xy 91.7843 -274.926958) (xy 91.712984 -274.90124) (xy 91.644807 -274.868088) (xy 91.580539 -274.827876)
			(xy 91.52091 -274.781061) (xy 91.466594 -274.728173) (xy 91.418208 -274.669811) (xy 91.3763 -274.606636)
			(xy 91.341344 -274.539365) (xy 91.313737 -274.46876) (xy 91.293791 -274.395619) (xy 91.281732 -274.320774)
			(xy 91.277697 -274.24507) (xy 90.161483 -274.24507) (xy 90.160205 -274.298965) (xy 90.150783 -274.37237)
			(xy 90.133796 -274.4444) (xy 90.109427 -274.51428) (xy 90.07794 -274.581254) (xy 90.039674 -274.6446)
			(xy 89.995043 -274.703634) (xy 89.970102 -274.730972) (xy 89.935812 -274.767802) (xy 89.935812 -274.993608)
			(xy 89.936308 -275.010261) (xy 89.94493 -275.042433) (xy 89.961586 -275.071277) (xy 89.985139 -275.094826)
			(xy 90.013986 -275.111477) (xy 90.046158 -275.120095) (xy 90.062812 -275.120608) (xy 90.092022 -275.120608)
			(xy 90.144346 -275.095462) (xy 90.16238 -275.072602) (xy 90.186023 -275.043584) (xy 90.238454 -274.99016)
			(xy 90.296202 -274.942534) (xy 90.358629 -274.901231) (xy 90.425046 -274.866707) (xy 90.494719 -274.839344)
			(xy 90.56688 -274.819444) (xy 90.64073 -274.807227) (xy 90.715454 -274.802827) (xy 90.790228 -274.806294)
			(xy 90.864225 -274.817588) (xy 90.936628 -274.836586) (xy 91.006637 -274.863077) (xy 91.07348 -274.896769)
			(xy 91.136418 -274.93729) (xy 91.164765 -274.96008) (xy 93.154506 -274.96008) (xy 93.158522 -274.84381)
			(xy 93.170549 -274.728095) (xy 93.190531 -274.613485) (xy 93.218373 -274.500526) (xy 93.253942 -274.389758)
			(xy 93.297068 -274.281707) (xy 93.347545 -274.176889) (xy 93.405134 -274.075804) (xy 93.46956 -273.978932)
			(xy 93.540515 -273.886736) (xy 93.617662 -273.799655) (xy 93.700633 -273.718104) (xy 93.789033 -273.642472)
			(xy 93.88244 -273.573118) (xy 93.980409 -273.510375) (xy 94.082473 -273.454539) (xy 94.188147 -273.405878)
			(xy 94.296926 -273.364624) (xy 94.408291 -273.330973) (xy 94.521714 -273.305085) (xy 94.636651 -273.287084)
			(xy 94.752557 -273.277055) (xy 94.868879 -273.275047) (xy 94.985062 -273.281069) (xy 95.100553 -273.295092)
			(xy 95.214801 -273.31705) (xy 95.327262 -273.346837) (xy 95.4374 -273.384312) (xy 95.54469 -273.429297)
			(xy 95.648621 -273.481576) (xy 95.748697 -273.540901) (xy 95.844443 -273.606989) (xy 95.9354 -273.679525)
			(xy 96.021136 -273.758164) (xy 96.101243 -273.84253) (xy 96.175339 -273.932222) (xy 96.243069 -274.026812)
			(xy 96.304113 -274.12585) (xy 96.358178 -274.228863) (xy 96.405008 -274.33536) (xy 96.444379 -274.444835)
			(xy 96.476103 -274.556765) (xy 96.500029 -274.670617) (xy 96.516043 -274.785849) (xy 96.52407 -274.901911)
			(xy 96.524572 -274.96008) (xy 96.52407 -275.018249) (xy 96.516043 -275.134311) (xy 96.500029 -275.249543)
			(xy 96.476103 -275.363395) (xy 96.444379 -275.475325) (xy 96.405008 -275.5848) (xy 96.358178 -275.691297)
			(xy 96.304113 -275.79431) (xy 96.243069 -275.893348) (xy 96.175339 -275.987938) (xy 96.101243 -276.07763)
			(xy 96.021136 -276.161996) (xy 95.9354 -276.240635) (xy 95.844443 -276.313171) (xy 95.748697 -276.379259)
			(xy 95.648621 -276.438584) (xy 95.54469 -276.490863) (xy 95.4374 -276.535848) (xy 95.327262 -276.573323)
			(xy 95.214801 -276.60311) (xy 95.100553 -276.625068) (xy 94.985062 -276.639091) (xy 94.868879 -276.645113)
			(xy 94.752557 -276.643105) (xy 94.636651 -276.633076) (xy 94.521714 -276.615075) (xy 94.408291 -276.589187)
			(xy 94.296926 -276.555536) (xy 94.188147 -276.514282) (xy 94.082473 -276.465621) (xy 93.980409 -276.409785)
			(xy 93.88244 -276.347042) (xy 93.789033 -276.277688) (xy 93.700633 -276.202056) (xy 93.617662 -276.120505)
			(xy 93.540515 -276.033424) (xy 93.46956 -275.941228) (xy 93.405134 -275.844356) (xy 93.347545 -275.743271)
			(xy 93.297068 -275.638453) (xy 93.253942 -275.530402) (xy 93.218373 -275.419634) (xy 93.190531 -275.306675)
			(xy 93.170549 -275.192065) (xy 93.158522 -275.07635) (xy 93.154506 -274.96008) (xy 91.164765 -274.96008)
			(xy 91.194756 -274.984192) (xy 91.24785 -275.036957) (xy 91.295113 -275.095002) (xy 91.336024 -275.157688)
			(xy 91.37013 -275.22432) (xy 91.397055 -275.294164) (xy 91.416502 -275.366447) (xy 91.428256 -275.440373)
			(xy 91.432187 -275.515124) (xy 91.428251 -275.589874) (xy 91.416492 -275.663799) (xy 91.397041 -275.736081)
			(xy 91.370111 -275.805923) (xy 91.336 -275.872553) (xy 91.295085 -275.935235) (xy 91.247818 -275.993278)
			(xy 91.194721 -276.04604) (xy 91.13638 -276.092938) (xy 91.073439 -276.133454) (xy 91.006594 -276.167142)
			(xy 90.936583 -276.193628) (xy 90.864179 -276.212621) (xy 90.790181 -276.223911) (xy 90.715407 -276.227372)
			(xy 90.640683 -276.222968) (xy 90.566834 -276.210746) (xy 90.494675 -276.190841) (xy 90.425003 -276.163473)
			(xy 90.358588 -276.128945) (xy 90.296164 -276.087638) (xy 90.238419 -276.040008) (xy 90.185992 -275.986581)
			(xy 90.16238 -275.957538) (xy 90.144346 -275.934678) (xy 90.092022 -275.909532) (xy 90.062812 -275.909532)
			(xy 90.046158 -275.910025) (xy 90.013984 -275.918645) (xy 89.985138 -275.9353) (xy 89.961588 -275.958854)
			(xy 89.944937 -275.987702) (xy 89.936323 -276.019878) (xy 89.935812 -276.036532) (xy 89.935812 -276.115272)
			(xy 90.670888 -276.850348) (xy 92.268294 -276.850348) (xy 96.439736 -281.021536) (xy 96.456626 -281.036774)
			(xy 96.49474 -281.061596) (xy 96.536664 -281.079236) (xy 96.58106 -281.089131) (xy 96.626507 -281.090965)
			(xy 96.671555 -281.084678) (xy 96.714764 -281.070472) (xy 96.754754 -281.048801) (xy 96.790247 -281.020357)
			(xy 96.820109 -280.986049) (xy 96.843387 -280.946972) (xy 96.859336 -280.904375) (xy 96.867447 -280.85962)
			(xy 96.86798 -280.836878) (xy 96.86798 -220.97492) (xy 100.149152 -217.693748) (xy 100.158122 -217.683032)
			(xy 100.171593 -217.658552) (xy 100.179388 -217.631721) (xy 100.180648 -217.617802) (xy 100.180648 -217.420952)
			(xy 100.180394 -217.394028) (xy 100.179891 -217.371282) (xy 100.171794 -217.326517) (xy 100.155854 -217.28391)
			(xy 100.13258 -217.244823) (xy 100.102718 -217.210506) (xy 100.067221 -217.182055) (xy 100.027225 -217.160382)
			(xy 99.984008 -217.146178) (xy 99.938952 -217.139898) (xy 99.893498 -217.141743) (xy 99.8491 -217.151653)
			(xy 99.807176 -217.169312) (xy 99.769067 -217.194156) (xy 99.75215 -217.20937) (xy 90.756232 -226.205034)
			(xy 90.747123 -226.215839) (xy 90.733425 -226.240551) (xy 90.72548 -226.267666) (xy 90.724228 -226.281742)
			(xy 90.724228 -226.448112) (xy 90.180668 -226.991672) (xy 90.169806 -227.003166) (xy 90.153592 -227.030305)
			(xy 90.144567 -227.060604) (xy 90.14329 -227.092193) (xy 90.146124 -227.10775) (xy 90.146124 -227.108004)
			(xy 90.153541 -227.14557) (xy 90.161233 -227.221758) (xy 90.161001 -227.25507) (xy 91.277697 -227.25507)
			(xy 91.281732 -227.179366) (xy 91.293791 -227.104521) (xy 91.313737 -227.03138) (xy 91.341344 -226.960775)
			(xy 91.3763 -226.893504) (xy 91.418208 -226.830329) (xy 91.466594 -226.771967) (xy 91.52091 -226.719079)
			(xy 91.580539 -226.672264) (xy 91.644807 -226.632052) (xy 91.712984 -226.5989) (xy 91.7843 -226.573182)
			(xy 91.857945 -226.55519) (xy 91.933085 -226.545128) (xy 92.008869 -226.543109) (xy 92.084439 -226.549158)
			(xy 92.158937 -226.563205) (xy 92.23152 -226.585091) (xy 92.301366 -226.614568) (xy 92.367683 -226.651303)
			(xy 92.429719 -226.694878) (xy 92.486772 -226.7448) (xy 92.538196 -226.800504) (xy 92.583407 -226.861359)
			(xy 92.621894 -226.926674) (xy 92.65322 -226.99571) (xy 92.67703 -227.067685) (xy 92.693055 -227.141783)
			(xy 92.701114 -227.217164) (xy 92.701618 -227.25507) (xy 92.701114 -227.292976) (xy 92.693055 -227.368357)
			(xy 92.67703 -227.442455) (xy 92.65322 -227.51443) (xy 92.621894 -227.583466) (xy 92.583407 -227.648781)
			(xy 92.538196 -227.709636) (xy 92.486772 -227.76534) (xy 92.429719 -227.815262) (xy 92.367683 -227.858837)
			(xy 92.301366 -227.895572) (xy 92.23152 -227.925049) (xy 92.158937 -227.946935) (xy 92.084439 -227.960982)
			(xy 92.008869 -227.967031) (xy 91.933085 -227.965012) (xy 91.857945 -227.95495) (xy 91.7843 -227.936958)
			(xy 91.712984 -227.91124) (xy 91.644807 -227.878088) (xy 91.580539 -227.837876) (xy 91.52091 -227.791061)
			(xy 91.466594 -227.738173) (xy 91.418208 -227.679811) (xy 91.3763 -227.616636) (xy 91.341344 -227.549365)
			(xy 91.313737 -227.47876) (xy 91.293791 -227.405619) (xy 91.281732 -227.330774) (xy 91.277697 -227.25507)
			(xy 90.161001 -227.25507) (xy 90.1607 -227.298331) (xy 90.15195 -227.374404) (xy 90.135083 -227.449099)
			(xy 90.110294 -227.52155) (xy 90.07787 -227.590922) (xy 90.038185 -227.656412) (xy 89.991699 -227.717262)
			(xy 89.938949 -227.77277) (xy 89.880543 -227.822293) (xy 89.817159 -227.86526) (xy 89.749528 -227.901174)
			(xy 89.678432 -227.929619) (xy 89.64168 -227.940362) (xy 89.617804 -227.946712) (xy 89.603026 -227.950788)
			(xy 89.575847 -227.964946) (xy 89.552832 -227.985182) (xy 89.535312 -228.010325) (xy 89.524299 -228.038924)
			(xy 89.52043 -228.069325) (xy 89.523929 -228.09977) (xy 89.534593 -228.128501) (xy 89.551806 -228.153856)
			(xy 89.56294 -228.16439) (xy 89.563956 -228.165406) (xy 89.563956 -228.52507) (xy 90.007697 -228.52507)
			(xy 90.011732 -228.449366) (xy 90.023791 -228.374521) (xy 90.043737 -228.30138) (xy 90.071344 -228.230775)
			(xy 90.1063 -228.163504) (xy 90.148208 -228.100329) (xy 90.196594 -228.041967) (xy 90.25091 -227.989079)
			(xy 90.310539 -227.942264) (xy 90.374807 -227.902052) (xy 90.442984 -227.8689) (xy 90.5143 -227.843182)
			(xy 90.587945 -227.82519) (xy 90.663085 -227.815128) (xy 90.738869 -227.813109) (xy 90.814439 -227.819158)
			(xy 90.888937 -227.833205) (xy 90.96152 -227.855091) (xy 91.031366 -227.884568) (xy 91.097683 -227.921303)
			(xy 91.159719 -227.964878) (xy 91.216772 -228.0148) (xy 91.268196 -228.070504) (xy 91.313407 -228.131359)
			(xy 91.351894 -228.196674) (xy 91.38322 -228.26571) (xy 91.40703 -228.337685) (xy 91.423055 -228.411783)
			(xy 91.431114 -228.487164) (xy 91.431618 -228.52507) (xy 91.431114 -228.562976) (xy 91.423055 -228.638357)
			(xy 91.40703 -228.712455) (xy 91.38322 -228.78443) (xy 91.351894 -228.853466) (xy 91.313407 -228.918781)
			(xy 91.268196 -228.979636) (xy 91.216772 -229.03534) (xy 91.159719 -229.085262) (xy 91.097683 -229.128837)
			(xy 91.031366 -229.165572) (xy 90.96152 -229.195049) (xy 90.888937 -229.216935) (xy 90.814439 -229.230982)
			(xy 90.738869 -229.237031) (xy 90.663085 -229.235012) (xy 90.587945 -229.22495) (xy 90.5143 -229.206958)
			(xy 90.442984 -229.18124) (xy 90.374807 -229.148088) (xy 90.310539 -229.107876) (xy 90.25091 -229.061061)
			(xy 90.196594 -229.008173) (xy 90.148208 -228.949811) (xy 90.1063 -228.886636) (xy 90.071344 -228.819365)
			(xy 90.043737 -228.74876) (xy 90.023791 -228.675619) (xy 90.011732 -228.600774) (xy 90.007697 -228.52507)
			(xy 89.563956 -228.52507) (xy 89.563956 -229.033832) (xy 89.613994 -229.101142) (xy 89.65438 -229.113334)
			(xy 89.682574 -229.122478) (xy 89.717532 -229.13508) (xy 89.78485 -229.166561) (xy 89.848521 -229.204884)
			(xy 89.907852 -229.249634) (xy 89.962197 -229.300322) (xy 90.010964 -229.356397) (xy 90.053623 -229.417249)
			(xy 90.089709 -229.482214) (xy 90.118829 -229.550586) (xy 90.140666 -229.62162) (xy 90.154982 -229.694542)
			(xy 90.161622 -229.76856) (xy 90.161226 -229.79507) (xy 91.277697 -229.79507) (xy 91.281732 -229.719366)
			(xy 91.293791 -229.644521) (xy 91.313737 -229.57138) (xy 91.341344 -229.500775) (xy 91.3763 -229.433504)
			(xy 91.418208 -229.370329) (xy 91.466594 -229.311967) (xy 91.52091 -229.259079) (xy 91.580539 -229.212264)
			(xy 91.644807 -229.172052) (xy 91.712984 -229.1389) (xy 91.7843 -229.113182) (xy 91.857945 -229.09519)
			(xy 91.933085 -229.085128) (xy 92.008869 -229.083109) (xy 92.084439 -229.089158) (xy 92.158937 -229.103205)
			(xy 92.23152 -229.125091) (xy 92.301366 -229.154568) (xy 92.367683 -229.191303) (xy 92.429719 -229.234878)
			(xy 92.486772 -229.2848) (xy 92.538196 -229.340504) (xy 92.583407 -229.401359) (xy 92.621894 -229.466674)
			(xy 92.65322 -229.53571) (xy 92.67703 -229.607685) (xy 92.693055 -229.681783) (xy 92.701114 -229.757164)
			(xy 92.701618 -229.79507) (xy 92.701114 -229.832976) (xy 92.693055 -229.908357) (xy 92.67703 -229.982455)
			(xy 92.65322 -230.05443) (xy 92.621894 -230.123466) (xy 92.583407 -230.188781) (xy 92.538196 -230.249636)
			(xy 92.486772 -230.30534) (xy 92.429719 -230.355262) (xy 92.367683 -230.398837) (xy 92.301366 -230.435572)
			(xy 92.23152 -230.465049) (xy 92.158937 -230.486935) (xy 92.084439 -230.500982) (xy 92.008869 -230.507031)
			(xy 91.933085 -230.505012) (xy 91.857945 -230.49495) (xy 91.7843 -230.476958) (xy 91.712984 -230.45124)
			(xy 91.644807 -230.418088) (xy 91.580539 -230.377876) (xy 91.52091 -230.331061) (xy 91.466594 -230.278173)
			(xy 91.418208 -230.219811) (xy 91.3763 -230.156636) (xy 91.341344 -230.089365) (xy 91.313737 -230.01876)
			(xy 91.293791 -229.945619) (xy 91.281732 -229.870774) (xy 91.277697 -229.79507) (xy 90.161226 -229.79507)
			(xy 90.160513 -229.842866) (xy 90.151668 -229.916653) (xy 90.135182 -229.989116) (xy 90.111235 -230.059466)
			(xy 90.080087 -230.126939) (xy 90.042079 -230.190798) (xy 89.997623 -230.25035) (xy 89.947204 -230.304945)
			(xy 89.891371 -230.353989) (xy 89.830731 -230.396948) (xy 89.765945 -230.433354) (xy 89.697718 -230.462812)
			(xy 89.626793 -230.485) (xy 89.553942 -230.499677) (xy 89.479958 -230.506682) (xy 89.442798 -230.506778)
			(xy 89.405553 -230.505915) (xy 89.331538 -230.497383) (xy 89.25882 -230.481167) (xy 89.188193 -230.457444)
			(xy 89.120431 -230.426474) (xy 89.056274 -230.388595) (xy 88.996424 -230.344222) (xy 88.941538 -230.29384)
			(xy 88.892213 -230.238001) (xy 88.848992 -230.177315) (xy 88.812345 -230.112446) (xy 88.782675 -230.044104)
			(xy 88.760306 -229.973037) (xy 88.745482 -229.900022) (xy 88.738366 -229.825858) (xy 88.739035 -229.751357)
			(xy 88.747483 -229.677333) (xy 88.763617 -229.604596) (xy 88.78726 -229.533943) (xy 88.818154 -229.466145)
			(xy 88.85596 -229.401945) (xy 88.877648 -229.371652) (xy 88.90254 -229.338124) (xy 88.90254 -229.200456)
			(xy 88.90209 -229.185514) (xy 88.895066 -229.156466) (xy 88.881483 -229.129846) (xy 88.862085 -229.107111)
			(xy 88.837935 -229.089507) (xy 88.824308 -229.083362) (xy 88.724994 -229.04196) (xy 88.631522 -229.075488)
			(xy 88.61552 -229.08768) (xy 88.586296 -229.10971) (xy 88.524131 -229.148334) (xy 88.45833 -229.180376)
			(xy 88.389588 -229.205496) (xy 88.318632 -229.22343) (xy 88.24621 -229.233989) (xy 88.173087 -229.23706)
			(xy 88.100034 -229.232611) (xy 88.027824 -229.220689) (xy 87.957218 -229.201421) (xy 87.888962 -229.175009)
			(xy 87.823777 -229.141733) (xy 87.792814 -229.122224) (xy 87.75573 -229.09657) (xy 87.724948 -229.0731)
			(xy 87.668147 -229.020506) (xy 87.617389 -228.962058) (xy 87.573275 -228.898447) (xy 87.536326 -228.830423)
			(xy 87.506978 -228.758791) (xy 87.485578 -228.684397) (xy 87.472378 -228.608119) (xy 87.469472 -228.56952)
			(xy 87.467652 -228.533091) (xy 87.470559 -228.460205) (xy 87.480907 -228.388) (xy 87.498586 -228.317231)
			(xy 87.523411 -228.248642) (xy 87.555121 -228.182952) (xy 87.593384 -228.12085) (xy 87.637799 -228.062987)
			(xy 87.687899 -228.009971) (xy 87.74316 -227.962358) (xy 87.803001 -227.920647) (xy 87.866794 -227.885275)
			(xy 87.933871 -227.856614) (xy 88.003527 -227.834965) (xy 88.039194 -227.827332) (xy 88.083898 -227.818442)
			(xy 88.141048 -227.748338) (xy 88.141048 -226.381818) (xy 88.326468 -226.196144) (xy 89.004648 -225.517964)
			(xy 90.005408 -225.517964) (xy 99.261676 -216.261696) (xy 99.27033 -216.251248) (xy 99.283446 -216.227505)
			(xy 99.291258 -216.201529) (xy 99.292664 -216.188036) (xy 99.292664 -193.334132) (xy 97.443544 -191.485012)
			(xy 97.443544 -184.99201) (xy 93.815408 -181.363874) (xy 93.815408 -177.985166) (xy 92.542614 -176.712372)
			(xy 92.402406 -176.712372) (xy 92.367862 -176.740058) (xy 92.34371 -176.758637) (xy 92.291418 -176.789919)
			(xy 92.235437 -176.813984) (xy 92.176757 -176.830407) (xy 92.116417 -176.838896) (xy 92.055484 -176.839303)
			(xy 91.995036 -176.831619) (xy 91.936142 -176.815981) (xy 91.879845 -176.792666) (xy 91.827139 -176.762085)
			(xy 91.778959 -176.724779) (xy 91.736156 -176.68141) (xy 91.699487 -176.632744) (xy 91.669602 -176.579641)
			(xy 91.647028 -176.523042) (xy 91.632165 -176.463948) (xy 91.628214 -176.433734) (xy 91.623134 -176.389538)
			(xy 91.496896 -176.2633) (xy 91.412314 -176.178972) (xy 91.371928 -176.138586) (xy 91.371928 -174.644812)
			(xy 90.885264 -174.158148) (xy 90.885264 -173.720252) (xy 90.884715 -173.70361) (xy 90.876088 -173.671462)
			(xy 90.859436 -173.642641) (xy 90.835892 -173.619113) (xy 90.807061 -173.602479) (xy 90.774907 -173.593874)
			(xy 90.758264 -173.593252) (xy 90.373708 -173.593252) (xy 90.357057 -173.593794) (xy 90.324888 -173.60241)
			(xy 90.296044 -173.619056) (xy 90.27249 -173.6426) (xy 90.255831 -173.671436) (xy 90.247201 -173.703601)
			(xy 90.246708 -173.720252) (xy 90.246708 -177.10404) (xy 90.20048 -177.150268) (xy 90.103452 -177.247042)
			(xy 89.958672 -177.391822) (xy 89.953592 -177.436018) (xy 89.949613 -177.466524) (xy 89.93452 -177.526166)
			(xy 89.911574 -177.583248) (xy 89.881186 -177.636741) (xy 89.843906 -177.68568) (xy 89.800405 -177.729184)
			(xy 89.751468 -177.766468) (xy 89.697978 -177.796859) (xy 89.640897 -177.81981) (xy 89.581257 -177.834907)
			(xy 89.550748 -177.838862) (xy 89.506552 -177.843942) (xy 89.41816 -177.932588) (xy 89.41816 -181.971696)
			(xy 89.418603 -181.987133) (xy 89.426039 -182.017099) (xy 89.440452 -182.044404) (xy 89.461 -182.067448)
			(xy 89.48648 -182.084885) (xy 89.515401 -182.095694) (xy 89.530682 -182.097934) (xy 89.545668 -182.099712)
			(xy 89.550748 -182.100474) (xy 89.588723 -182.106419) (xy 89.663204 -182.125425) (xy 89.735203 -182.152346)
			(xy 89.803882 -182.186868) (xy 89.868441 -182.228591) (xy 89.928128 -182.277027) (xy 89.982248 -182.331613)
			(xy 90.030172 -182.391713) (xy 90.071339 -182.456627) (xy 90.105273 -182.525599) (xy 90.131576 -182.597826)
			(xy 90.149943 -182.672467) (xy 90.16016 -182.748653) (xy 90.16159 -182.80507) (xy 91.277951 -182.80507)
			(xy 91.281986 -182.729366) (xy 91.294045 -182.654521) (xy 91.313991 -182.58138) (xy 91.341598 -182.510775)
			(xy 91.376554 -182.443504) (xy 91.418462 -182.380329) (xy 91.466848 -182.321967) (xy 91.521164 -182.269079)
			(xy 91.580793 -182.222264) (xy 91.645061 -182.182052) (xy 91.713238 -182.1489) (xy 91.784554 -182.123182)
			(xy 91.858199 -182.10519) (xy 91.933339 -182.095128) (xy 92.009123 -182.093109) (xy 92.084693 -182.099158)
			(xy 92.159191 -182.113205) (xy 92.231774 -182.135091) (xy 92.30162 -182.164568) (xy 92.367937 -182.201303)
			(xy 92.429973 -182.244878) (xy 92.487026 -182.2948) (xy 92.53845 -182.350504) (xy 92.583661 -182.411359)
			(xy 92.622148 -182.476674) (xy 92.653474 -182.54571) (xy 92.677284 -182.617685) (xy 92.693309 -182.691783)
			(xy 92.701368 -182.767164) (xy 92.701872 -182.80507) (xy 92.701368 -182.842976) (xy 92.693309 -182.918357)
			(xy 92.677284 -182.992455) (xy 92.653474 -183.06443) (xy 92.622148 -183.133466) (xy 92.583661 -183.198781)
			(xy 92.53845 -183.259636) (xy 92.487026 -183.31534) (xy 92.429973 -183.365262) (xy 92.367937 -183.408837)
			(xy 92.30162 -183.445572) (xy 92.231774 -183.475049) (xy 92.159191 -183.496935) (xy 92.084693 -183.510982)
			(xy 92.009123 -183.517031) (xy 91.933339 -183.515012) (xy 91.858199 -183.50495) (xy 91.784554 -183.486958)
			(xy 91.713238 -183.46124) (xy 91.645061 -183.428088) (xy 91.580793 -183.387876) (xy 91.521164 -183.341061)
			(xy 91.466848 -183.288173) (xy 91.418462 -183.229811) (xy 91.376554 -183.166636) (xy 91.341598 -183.099365)
			(xy 91.313991 -183.02876) (xy 91.294045 -182.955619) (xy 91.281986 -182.880774) (xy 91.277951 -182.80507)
			(xy 90.16159 -182.80507) (xy 90.162108 -182.825496) (xy 90.155765 -182.902101) (xy 90.141203 -182.977577)
			(xy 90.118593 -183.051044) (xy 90.088199 -183.121647) (xy 90.050373 -183.188564) (xy 90.005556 -183.251015)
			(xy 89.954272 -183.308273) (xy 89.897115 -183.359671) (xy 89.834753 -183.404611) (xy 89.767912 -183.44257)
			(xy 89.732866 -183.458358) (xy 89.712427 -183.467744) (xy 89.674958 -183.492616) (xy 89.642452 -183.523694)
			(xy 89.615923 -183.560008) (xy 89.5962 -183.600425) (xy 89.583899 -183.643682) (xy 89.579403 -183.688429)
			(xy 89.582853 -183.733269) (xy 89.594141 -183.776801) (xy 89.612916 -183.817667) (xy 89.638589 -183.854591)
			(xy 89.654126 -183.870854) (xy 89.65438 -183.871108) (xy 89.670625 -183.886678) (xy 89.70754 -183.9124)
			(xy 89.74841 -183.931214) (xy 89.791956 -183.942531) (xy 89.836815 -183.945997) (xy 89.881582 -183.941503)
			(xy 89.924857 -183.929191) (xy 89.965286 -183.909446) (xy 90.001601 -183.882885) (xy 90.032668 -183.85034)
			(xy 90.057514 -183.812829) (xy 90.066876 -183.792368) (xy 90.082296 -183.757954) (xy 90.119381 -183.692287)
			(xy 90.163201 -183.630909) (xy 90.213265 -183.574507) (xy 90.269011 -183.523715) (xy 90.329815 -183.479102)
			(xy 90.394995 -183.441167) (xy 90.463821 -183.410336) (xy 90.53552 -183.386955) (xy 90.609289 -183.371285)
			(xy 90.684302 -183.363502) (xy 90.759717 -183.363694) (xy 90.834689 -183.371858) (xy 90.908378 -183.387903)
			(xy 90.979957 -183.411649) (xy 91.048625 -183.44283) (xy 91.113611 -183.481096) (xy 91.174187 -183.526018)
			(xy 91.229674 -183.577093) (xy 91.27945 -183.633748) (xy 91.322957 -183.695349) (xy 91.359708 -183.761204)
			(xy 91.38929 -183.830575) (xy 91.411371 -183.902685) (xy 91.425705 -183.976726) (xy 91.432131 -184.051867)
			(xy 91.430576 -184.127266) (xy 91.426284 -184.164732) (xy 91.421033 -184.202208) (xy 91.403614 -184.275852)
			(xy 91.378481 -184.347233) (xy 91.345917 -184.415545) (xy 91.306289 -184.480017) (xy 91.260045 -184.53992)
			(xy 91.207708 -184.59458) (xy 91.149867 -184.643379) (xy 91.087175 -184.685766) (xy 91.02034 -184.721264)
			(xy 90.950117 -184.74947) (xy 90.877297 -184.770068) (xy 90.802703 -184.782824) (xy 90.727177 -184.787594)
			(xy 90.651571 -184.784325) (xy 90.576739 -184.773054) (xy 90.503525 -184.753908) (xy 90.432755 -184.727102)
			(xy 90.365228 -184.69294) (xy 90.301706 -184.651806) (xy 90.242907 -184.604166) (xy 90.189493 -184.550557)
			(xy 90.142068 -184.491584) (xy 90.101168 -184.427913) (xy 90.067252 -184.360261) (xy 90.040705 -184.289394)
			(xy 90.030808 -184.25287) (xy 90.02014 -184.210706) (xy 89.951306 -184.157366) (xy 89.907872 -184.157366)
			(xy 89.891224 -184.157912) (xy 89.859065 -184.166534) (xy 89.830231 -184.183184) (xy 89.806687 -184.206726)
			(xy 89.790037 -184.235559) (xy 89.781413 -184.267718) (xy 89.780872 -184.284366) (xy 89.780872 -184.642252)
			(xy 89.838276 -184.747662) (xy 89.862406 -184.76468) (xy 89.892655 -184.786753) (xy 89.948818 -184.836288)
			(xy 89.999471 -184.891444) (xy 90.044055 -184.951612) (xy 90.082076 -185.016128) (xy 90.113115 -185.084279)
			(xy 90.136828 -185.155312) (xy 90.152954 -185.228442) (xy 90.161313 -185.30286) (xy 90.161596 -185.34507)
			(xy 91.277951 -185.34507) (xy 91.281986 -185.269366) (xy 91.294045 -185.194521) (xy 91.313991 -185.12138)
			(xy 91.341598 -185.050775) (xy 91.376554 -184.983504) (xy 91.418462 -184.920329) (xy 91.466848 -184.861967)
			(xy 91.521164 -184.809079) (xy 91.580793 -184.762264) (xy 91.645061 -184.722052) (xy 91.713238 -184.6889)
			(xy 91.784554 -184.663182) (xy 91.858199 -184.64519) (xy 91.933339 -184.635128) (xy 92.009123 -184.633109)
			(xy 92.084693 -184.639158) (xy 92.159191 -184.653205) (xy 92.231774 -184.675091) (xy 92.30162 -184.704568)
			(xy 92.367937 -184.741303) (xy 92.429973 -184.784878) (xy 92.487026 -184.8348) (xy 92.53845 -184.890504)
			(xy 92.583661 -184.951359) (xy 92.622148 -185.016674) (xy 92.653474 -185.08571) (xy 92.677284 -185.157685)
			(xy 92.693309 -185.231783) (xy 92.701368 -185.307164) (xy 92.701872 -185.34507) (xy 92.701368 -185.382976)
			(xy 92.693309 -185.458357) (xy 92.677284 -185.532455) (xy 92.653474 -185.60443) (xy 92.622148 -185.673466)
			(xy 92.583661 -185.738781) (xy 92.53845 -185.799636) (xy 92.487026 -185.85534) (xy 92.429973 -185.905262)
			(xy 92.367937 -185.948837) (xy 92.30162 -185.985572) (xy 92.231774 -186.015049) (xy 92.159191 -186.036935)
			(xy 92.084693 -186.050982) (xy 92.009123 -186.057031) (xy 91.933339 -186.055012) (xy 91.858199 -186.04495)
			(xy 91.784554 -186.026958) (xy 91.713238 -186.00124) (xy 91.645061 -185.968088) (xy 91.580793 -185.927876)
			(xy 91.521164 -185.881061) (xy 91.466848 -185.828173) (xy 91.418462 -185.769811) (xy 91.376554 -185.706636)
			(xy 91.341598 -185.639365) (xy 91.313991 -185.56876) (xy 91.294045 -185.495619) (xy 91.281986 -185.420774)
			(xy 91.277951 -185.34507) (xy 90.161596 -185.34507) (xy 90.161815 -185.377744) (xy 90.154454 -185.452268)
			(xy 90.13931 -185.525607) (xy 90.116551 -185.596951) (xy 90.086428 -185.665512) (xy 90.049275 -185.730532)
			(xy 90.005502 -185.791293) (xy 89.955593 -185.847123) (xy 89.900099 -185.897405) (xy 89.839633 -185.941585)
			(xy 89.774863 -185.979172) (xy 89.706505 -186.009754) (xy 89.635316 -186.03299) (xy 89.56208 -186.048625)
			(xy 89.487607 -186.056486) (xy 89.412721 -186.056486) (xy 89.338248 -186.048625) (xy 89.265012 -186.03299)
			(xy 89.193823 -186.009754) (xy 89.125465 -185.979172) (xy 89.060695 -185.941585) (xy 89.000229 -185.897405)
			(xy 88.944735 -185.847123) (xy 88.894826 -185.791293) (xy 88.851053 -185.730532) (xy 88.8139 -185.665512)
			(xy 88.783777 -185.596951) (xy 88.761018 -185.525607) (xy 88.745874 -185.452268) (xy 88.738513 -185.377744)
			(xy 88.739015 -185.30286) (xy 88.747374 -185.228442) (xy 88.7635 -185.155312) (xy 88.787213 -185.084279)
			(xy 88.818252 -185.016128) (xy 88.856273 -184.951612) (xy 88.900857 -184.891444) (xy 88.95151 -184.836288)
			(xy 89.007673 -184.786753) (xy 89.037922 -184.76468) (xy 89.062052 -184.747662) (xy 89.119456 -184.642252)
			(xy 89.119456 -184.271412) (xy 89.073736 -184.225692) (xy 89.036398 -184.188354) (xy 88.931496 -184.1881)
			(xy 88.871298 -184.248298) (xy 88.862154 -184.279032) (xy 88.851136 -184.314255) (xy 88.822792 -184.382401)
			(xy 88.787547 -184.447248) (xy 88.74578 -184.508098) (xy 88.697939 -184.564299) (xy 88.644538 -184.615247)
			(xy 88.586152 -184.660394) (xy 88.523406 -184.699256) (xy 88.456975 -184.731416) (xy 88.387572 -184.756527)
			(xy 88.315943 -184.77432) (xy 88.242857 -184.784604) (xy 88.1691 -184.787269) (xy 88.095462 -184.782286)
			(xy 88.022736 -184.769708) (xy 87.951702 -184.749671) (xy 87.883124 -184.72239) (xy 87.817737 -184.688157)
			(xy 87.786718 -184.66816) (xy 87.74914 -184.642384) (xy 87.680225 -184.582761) (xy 87.649304 -184.549288)
			(xy 87.624436 -184.520696) (xy 87.580239 -184.459137) (xy 87.542833 -184.393232) (xy 87.51264 -184.323726)
			(xy 87.490003 -184.251405) (xy 87.475177 -184.177088) (xy 87.468331 -184.101617) (xy 87.469543 -184.025846)
			(xy 87.478797 -183.950632) (xy 87.495991 -183.876827) (xy 87.520928 -183.805267) (xy 87.553327 -183.736761)
			(xy 87.592821 -183.672085) (xy 87.638963 -183.611971) (xy 87.69123 -183.5571) (xy 87.749032 -183.508092)
			(xy 87.811713 -183.465503) (xy 87.844884 -183.447182) (xy 87.864397 -183.435248) (xy 87.899151 -183.405515)
			(xy 87.928018 -183.370038) (xy 87.950064 -183.329965) (xy 87.964577 -183.286592) (xy 87.971087 -183.241321)
			(xy 87.969384 -183.195615) (xy 87.959523 -183.150954) (xy 87.941823 -183.108781) (xy 87.916855 -183.07046)
			(xy 87.901526 -183.053482) (xy 87.895684 -183.04764) (xy 87.865204 -183.016906) (xy 87.865204 -182.939182)
			(xy 87.864659 -182.922535) (xy 87.856038 -182.890376) (xy 87.839388 -182.861544) (xy 87.815845 -182.838003)
			(xy 87.787011 -182.821357) (xy 87.754851 -182.81274) (xy 87.738204 -182.812182) (xy 87.690706 -182.812182)
			(xy 87.619078 -182.874412) (xy 87.612474 -182.921148) (xy 87.611966 -182.923942) (xy 87.605492 -182.95951)
			(xy 87.586258 -183.029204) (xy 87.560058 -183.09659) (xy 87.527163 -183.160972) (xy 87.487911 -183.221689)
			(xy 87.442707 -183.278114) (xy 87.417656 -183.30418) (xy 87.389921 -183.331627) (xy 87.329446 -183.380943)
			(xy 87.26394 -183.423348) (xy 87.194188 -183.458333) (xy 87.121028 -183.485478) (xy 87.045337 -183.504457)
			(xy 86.968025 -183.515043) (xy 86.890019 -183.517108) (xy 86.812255 -183.510628) (xy 86.735666 -183.49568)
			(xy 86.661172 -183.472444) (xy 86.589667 -183.441199) (xy 86.522009 -183.402319) (xy 86.459009 -183.356271)
			(xy 86.42985 -183.330342) (xy 86.405543 -183.307592) (xy 86.360815 -183.258274) (xy 86.320884 -183.204998)
			(xy 86.286098 -183.148228) (xy 86.2711 -183.118506) (xy 86.255029 -183.084687) (xy 86.229265 -183.014379)
			(xy 86.211024 -182.941754) (xy 86.200509 -182.867616) (xy 86.197835 -182.792784) (xy 86.203032 -182.718084)
			(xy 86.216042 -182.644343) (xy 86.236723 -182.572375) (xy 86.264844 -182.502976) (xy 86.300096 -182.436912)
			(xy 86.342089 -182.374915) (xy 86.390358 -182.317669) (xy 86.444371 -182.265807) (xy 86.50353 -182.219902)
			(xy 86.567181 -182.180461) (xy 86.634621 -182.147921) (xy 86.705105 -182.12264) (xy 86.777853 -182.104899)
			(xy 86.852062 -182.094894) (xy 86.926911 -182.092734) (xy 87.001573 -182.098444) (xy 87.075223 -182.111962)
			(xy 87.147047 -182.133136) (xy 87.216252 -182.161734) (xy 87.282071 -182.197439) (xy 87.343778 -182.239857)
			(xy 87.400691 -182.288519) (xy 87.4268 -182.315358) (xy 87.442824 -182.331573) (xy 87.479539 -182.358589)
			(xy 87.520482 -182.378627) (xy 87.564341 -182.391044) (xy 87.609712 -182.395442) (xy 87.655139 -182.391681)
			(xy 87.699169 -182.379882) (xy 87.740389 -182.360421) (xy 87.777479 -182.333924) (xy 87.809251 -182.301238)
			(xy 87.834687 -182.263411) (xy 87.852971 -182.221656) (xy 87.863518 -182.17731) (xy 87.865204 -182.154576)
			(xy 87.865204 -176.612296) (xy 87.844873 -176.590363) (xy 87.809489 -176.542149) (xy 87.780687 -176.489736)
			(xy 87.758959 -176.434017) (xy 87.744674 -176.375943) (xy 87.738078 -176.316502) (xy 87.73928 -176.256709)
			(xy 87.748263 -176.197582) (xy 87.764871 -176.140129) (xy 87.788823 -176.08533) (xy 87.819709 -176.034117)
			(xy 87.857004 -175.987365) (xy 87.900072 -175.94587) (xy 87.948178 -175.910339) (xy 88.000504 -175.881378)
			(xy 88.056156 -175.859481) (xy 88.114187 -175.84502) (xy 88.143842 -175.841152) (xy 88.188038 -175.836072)
			(xy 88.2523 -175.771556) (xy 88.488012 -175.535844) (xy 88.488012 -170.1673) (xy 89.12479 -169.530522)
			(xy 89.12479 -166.066724) (xy 89.294716 -165.896798) (xy 89.294716 -165.081204) (xy 89.294173 -165.064555)
			(xy 89.285556 -165.03239) (xy 89.268909 -165.003551) (xy 89.245365 -164.980003) (xy 89.216529 -164.963351)
			(xy 89.184365 -164.954729) (xy 89.167716 -164.954204) (xy 89.0905 -164.954204) (xy 84.588096 -160.4518)
			(xy 84.588096 -154.201114) (xy 84.587557 -154.184496) (xy 84.578967 -154.15239) (xy 84.562368 -154.123596)
			(xy 84.551012 -154.111452) (xy 82.460338 -152.021032) (xy 82.438636 -152.018426) (xy 82.394951 -152.019805)
			(xy 82.352145 -152.028634) (xy 82.311479 -152.044653) (xy 82.274152 -152.06739) (xy 82.241263 -152.096175)
			(xy 82.21378 -152.130161) (xy 82.192514 -152.168345) (xy 82.178091 -152.209603) (xy 82.17408 -152.23109)
			(xy 82.168624 -152.26102) (xy 82.150833 -152.319197) (xy 82.125491 -152.374506) (xy 82.093046 -152.425969)
			(xy 82.05407 -152.472681) (xy 82.009248 -152.513818) (xy 81.959372 -152.548654) (xy 81.905321 -152.576577)
			(xy 81.848047 -152.597093) (xy 81.788561 -152.60984) (xy 81.727909 -152.614595) (xy 81.667163 -152.611273)
			(xy 81.607392 -152.599934) (xy 81.549649 -152.580776) (xy 81.494954 -152.554137) (xy 81.44427 -152.520488)
			(xy 81.39849 -152.480421) (xy 81.358421 -152.434642) (xy 81.32477 -152.383959) (xy 81.29813 -152.329264)
			(xy 81.27897 -152.271523) (xy 81.267628 -152.211752) (xy 81.264305 -152.151005) (xy 81.269058 -152.090354)
			(xy 81.281803 -152.030867) (xy 81.302317 -151.973592) (xy 81.330238 -151.91954) (xy 81.365073 -151.869663)
			(xy 81.406208 -151.824841) (xy 81.452919 -151.785862) (xy 81.504381 -151.753416) (xy 81.559689 -151.728072)
			(xy 81.617866 -151.710279) (xy 81.647792 -151.704802) (xy 81.669286 -151.700797) (xy 81.710567 -151.686405)
			(xy 81.748774 -151.665157) (xy 81.782779 -151.637681) (xy 81.811576 -151.604788) (xy 81.834316 -151.567449)
			(xy 81.850326 -151.526768) (xy 81.859134 -151.483946) (xy 81.860479 -151.440249) (xy 81.85785 -151.418544)
			(xy 81.726024 -151.286464) (xy 81.726024 -148.278596) (xy 81.712671 -148.26154) (xy 81.681167 -148.231814)
			(xy 81.645079 -148.207861) (xy 81.605451 -148.190375) (xy 81.563432 -148.179862) (xy 81.520239 -148.176627)
			(xy 81.477123 -148.180764) (xy 81.435333 -148.192154) (xy 81.396079 -148.210465) (xy 81.378044 -148.222462)
			(xy 81.354222 -148.239759) (xy 81.302983 -148.268749) (xy 81.248449 -148.290929) (xy 81.191521 -148.305931)
			(xy 81.133139 -148.313507) (xy 81.074267 -148.313533) (xy 81.015879 -148.306009) (xy 80.958937 -148.291057)
			(xy 80.904384 -148.268926) (xy 80.853119 -148.239982) (xy 80.80599 -148.204701) (xy 80.763776 -148.163667)
			(xy 80.745076 -148.140928) (xy 80.72636 -148.116621) (xy 80.69491 -148.063946) (xy 80.670779 -148.007543)
			(xy 80.654398 -147.948422) (xy 80.646061 -147.887643) (xy 80.645917 -147.826295) (xy 80.65397 -147.765477)
			(xy 80.670075 -147.70628) (xy 80.693942 -147.649765) (xy 80.725145 -147.596944) (xy 80.763124 -147.548765)
			(xy 80.807198 -147.506091) (xy 80.856578 -147.469686) (xy 80.910378 -147.440204) (xy 80.967633 -147.418172)
			(xy 81.027319 -147.403986) (xy 81.088365 -147.3979) (xy 81.149677 -147.400023) (xy 81.210156 -147.410317)
			(xy 81.268717 -147.428597) (xy 81.324312 -147.454536) (xy 81.375944 -147.487669) (xy 81.422688 -147.527401)
			(xy 81.443576 -147.54987) (xy 81.459576 -147.565338) (xy 81.495942 -147.590985) (xy 81.536216 -147.609911)
			(xy 81.579169 -147.62154) (xy 81.623491 -147.625515) (xy 81.667828 -147.621717) (xy 81.710827 -147.61026)
			(xy 81.751177 -147.591495) (xy 81.787644 -147.565994) (xy 81.803748 -147.550632) (xy 86.780624 -142.573502)
			(xy 86.780624 -141.65199) (xy 86.73211 -141.585442) (xy 86.692486 -141.572742) (xy 86.65682 -141.560775)
			(xy 86.588016 -141.530345) (xy 86.522806 -141.492826) (xy 86.461917 -141.448639) (xy 86.406028 -141.398275)
			(xy 86.355764 -141.342297) (xy 86.311685 -141.28133) (xy 86.274283 -141.216053) (xy 86.243975 -141.147195)
			(xy 86.2211 -141.075524) (xy 86.205912 -141.001839) (xy 86.198582 -140.926964) (xy 86.19919 -140.851734)
			(xy 86.20773 -140.776987) (xy 86.224108 -140.703558) (xy 86.248139 -140.632267) (xy 86.279556 -140.563908)
			(xy 86.318009 -140.499244) (xy 86.340188 -140.468858) (xy 86.363377 -140.438674) (xy 86.415209 -140.382925)
			(xy 86.472694 -140.333025) (xy 86.535175 -140.289545) (xy 86.60194 -140.252982) (xy 86.672225 -140.223752)
			(xy 86.745229 -140.20219) (xy 86.820117 -140.188541) (xy 86.896033 -140.182963) (xy 86.972111 -140.185518)
			(xy 87.047483 -140.196177) (xy 87.121286 -140.214819) (xy 87.192678 -140.24123) (xy 87.260844 -140.275109)
			(xy 87.325006 -140.31607) (xy 87.38443 -140.363643) (xy 87.438437 -140.417287) (xy 87.486412 -140.476387)
			(xy 87.527805 -140.54027) (xy 87.545418 -140.574014) (xy 87.55604 -140.593973) (xy 87.583229 -140.630092)
			(xy 87.616384 -140.660826) (xy 87.654457 -140.685203) (xy 87.696245 -140.702453) (xy 87.740428 -140.712031)
			(xy 87.785608 -140.713634) (xy 87.808054 -140.71092) (xy 87.87765 -140.641324) (xy 87.893755 -140.624483)
			(xy 87.920147 -140.586086) (xy 87.939093 -140.54352) (xy 87.949957 -140.498212) (xy 87.952375 -140.451682)
			(xy 87.946266 -140.405492) (xy 87.931835 -140.361191) (xy 87.909565 -140.320265) (xy 87.880205 -140.284088)
			(xy 87.844738 -140.253872) (xy 87.824818 -140.241782) (xy 87.792582 -140.222654) (xy 87.731922 -140.178614)
			(xy 87.676227 -140.128442) (xy 87.626113 -140.072694) (xy 87.582137 -140.011987) (xy 87.544785 -139.946995)
			(xy 87.514471 -139.878436) (xy 87.491531 -139.807071) (xy 87.476219 -139.733691) (xy 87.472012 -139.696444)
			(xy 87.468573 -139.657286) (xy 87.469328 -139.578679) (xy 87.478758 -139.500636) (xy 87.487252 -139.462256)
			(xy 87.49658 -139.424843) (xy 87.522231 -139.352125) (xy 87.555591 -139.282605) (xy 87.59627 -139.217099)
			(xy 87.643791 -139.156373) (xy 87.697598 -139.10114) (xy 87.757059 -139.052046) (xy 87.821478 -139.009667)
			(xy 87.890101 -138.974499) (xy 87.962123 -138.946954) (xy 88.0367 -138.927356) (xy 88.112959 -138.915933)
			(xy 88.151462 -138.91387) (xy 88.189674 -138.912835) (xy 88.265947 -138.91796) (xy 88.341232 -138.931224)
			(xy 88.414663 -138.952475) (xy 88.485397 -138.981469) (xy 88.519254 -138.999214) (xy 88.554175 -139.018749)
			(xy 88.619813 -139.064517) (xy 88.6799 -139.117364) (xy 88.733676 -139.176621) (xy 88.757506 -139.208764)
			(xy 88.768936 -139.22502) (xy 88.7857 -139.249912) (xy 88.896698 -139.31138) (xy 88.969342 -139.295124)
			(xy 88.985995 -139.290829) (xy 89.016331 -139.274657) (xy 89.041248 -139.250971) (xy 89.058934 -139.221492)
			(xy 89.068107 -139.188361) (xy 89.068656 -139.171172) (xy 89.068656 -139.022074) (xy 89.019126 -138.922252)
			(xy 88.998044 -138.90498) (xy 88.969017 -138.880481) (xy 88.915811 -138.826266) (xy 88.86868 -138.766695)
			(xy 88.828159 -138.702444) (xy 88.79471 -138.634244) (xy 88.768712 -138.562871) (xy 88.75046 -138.489135)
			(xy 88.740164 -138.413875) (xy 88.737938 -138.337946) (xy 88.74381 -138.262212) (xy 88.757712 -138.187534)
			(xy 88.779485 -138.11476) (xy 88.808884 -138.044719) (xy 88.845572 -137.978205) (xy 88.889134 -137.915976)
			(xy 88.939074 -137.858738) (xy 88.994823 -137.807143) (xy 89.05575 -137.761778) (xy 89.12116 -137.723156)
			(xy 89.190311 -137.691719) (xy 89.262415 -137.667823) (xy 89.336654 -137.651739) (xy 89.412183 -137.643652)
			(xy 89.488145 -137.643652) (xy 89.563674 -137.651739) (xy 89.637913 -137.667823) (xy 89.710017 -137.691719)
			(xy 89.779168 -137.723156) (xy 89.844578 -137.761778) (xy 89.905505 -137.807143) (xy 89.961254 -137.858738)
			(xy 90.011194 -137.915976) (xy 90.054756 -137.978205) (xy 90.091444 -138.044719) (xy 90.120843 -138.11476)
			(xy 90.142616 -138.187534) (xy 90.156518 -138.262212) (xy 90.16239 -138.337946) (xy 90.161888 -138.35507)
			(xy 91.277951 -138.35507) (xy 91.281986 -138.279366) (xy 91.294045 -138.204521) (xy 91.313991 -138.13138)
			(xy 91.341598 -138.060775) (xy 91.376554 -137.993504) (xy 91.418462 -137.930329) (xy 91.466848 -137.871967)
			(xy 91.521164 -137.819079) (xy 91.580793 -137.772264) (xy 91.645061 -137.732052) (xy 91.713238 -137.6989)
			(xy 91.784554 -137.673182) (xy 91.858199 -137.65519) (xy 91.933339 -137.645128) (xy 92.009123 -137.643109)
			(xy 92.084693 -137.649158) (xy 92.159191 -137.663205) (xy 92.231774 -137.685091) (xy 92.30162 -137.714568)
			(xy 92.367937 -137.751303) (xy 92.429973 -137.794878) (xy 92.487026 -137.8448) (xy 92.53845 -137.900504)
			(xy 92.583661 -137.961359) (xy 92.622148 -138.026674) (xy 92.653474 -138.09571) (xy 92.677284 -138.167685)
			(xy 92.693309 -138.241783) (xy 92.701368 -138.317164) (xy 92.701872 -138.35507) (xy 92.701368 -138.392976)
			(xy 92.693309 -138.468357) (xy 92.677284 -138.542455) (xy 92.653474 -138.61443) (xy 92.622148 -138.683466)
			(xy 92.583661 -138.748781) (xy 92.53845 -138.809636) (xy 92.487026 -138.86534) (xy 92.429973 -138.915262)
			(xy 92.367937 -138.958837) (xy 92.30162 -138.995572) (xy 92.231774 -139.025049) (xy 92.159191 -139.046935)
			(xy 92.084693 -139.060982) (xy 92.009123 -139.067031) (xy 91.933339 -139.065012) (xy 91.858199 -139.05495)
			(xy 91.784554 -139.036958) (xy 91.713238 -139.01124) (xy 91.645061 -138.978088) (xy 91.580793 -138.937876)
			(xy 91.521164 -138.891061) (xy 91.466848 -138.838173) (xy 91.418462 -138.779811) (xy 91.376554 -138.716636)
			(xy 91.341598 -138.649365) (xy 91.313991 -138.57876) (xy 91.294045 -138.505619) (xy 91.281986 -138.430774)
			(xy 91.277951 -138.35507) (xy 90.161888 -138.35507) (xy 90.160164 -138.413875) (xy 90.149868 -138.489135)
			(xy 90.131616 -138.562871) (xy 90.105618 -138.634244) (xy 90.072169 -138.702444) (xy 90.031648 -138.766695)
			(xy 89.984517 -138.826266) (xy 89.931311 -138.880481) (xy 89.902284 -138.90498) (xy 89.881202 -138.922252)
			(xy 89.831672 -139.022074) (xy 89.831672 -139.171172) (xy 89.832234 -139.188362) (xy 89.841404 -139.221496)
			(xy 89.859085 -139.25098) (xy 89.883994 -139.274676) (xy 89.914325 -139.290862) (xy 89.930986 -139.295124)
			(xy 90.003884 -139.31138) (xy 90.114374 -139.250166) (xy 90.131392 -139.22502) (xy 90.152836 -139.194313)
			(xy 90.201202 -139.137121) (xy 90.255308 -139.085326) (xy 90.314553 -139.039498) (xy 90.378284 -139.000146)
			(xy 90.445795 -138.967705) (xy 90.516339 -138.942533) (xy 90.589137 -138.924908) (xy 90.663384 -138.915026)
			(xy 90.738257 -138.912995) (xy 90.81293 -138.918839) (xy 90.886576 -138.932493) (xy 90.958381 -138.953805)
			(xy 91.027551 -138.982541) (xy 91.093321 -139.018381) (xy 91.154963 -139.06093) (xy 91.211796 -139.109718)
			(xy 91.263191 -139.164204) (xy 91.308579 -139.223786) (xy 91.34746 -139.287806) (xy 91.379402 -139.355554)
			(xy 91.404053 -139.426283) (xy 91.42114 -139.499209) (xy 91.430474 -139.573526) (xy 91.431951 -139.648413)
			(xy 91.429332 -139.685776) (xy 91.425608 -139.723554) (xy 91.411122 -139.798075) (xy 91.388787 -139.87063)
			(xy 91.358856 -139.940397) (xy 91.32167 -140.006581) (xy 91.27765 -140.068432) (xy 91.227298 -140.125246)
			(xy 91.171184 -140.176378) (xy 91.109947 -140.221247) (xy 91.044283 -140.259343) (xy 90.974936 -140.290234)
			(xy 90.902696 -140.313569) (xy 90.828382 -140.329082) (xy 90.752839 -140.336597) (xy 90.676925 -140.33603)
			(xy 90.601504 -140.327386) (xy 90.52743 -140.310763) (xy 90.455547 -140.286351) (xy 90.38667 -140.254426)
			(xy 90.321582 -140.215352) (xy 90.261023 -140.169572) (xy 90.20568 -140.117607) (xy 90.156183 -140.060046)
			(xy 90.113093 -139.997545) (xy 90.094562 -139.964414) (xy 90.082832 -139.943901) (xy 90.053005 -139.907257)
			(xy 90.016924 -139.876751) (xy 89.97583 -139.853434) (xy 89.931137 -139.838106) (xy 89.884381 -139.831296)
			(xy 89.837173 -139.833238) (xy 89.791134 -139.843864) (xy 89.747851 -139.86281) (xy 89.70881 -139.889423)
			(xy 89.691718 -139.90574) (xy 89.611454 -139.986004) (xy 89.608672 -140.008938) (xy 89.61048 -140.055095)
			(xy 89.620605 -140.100163) (xy 89.638715 -140.142658) (xy 89.66421 -140.181177) (xy 89.696251 -140.21445)
			(xy 89.733782 -140.24138) (xy 89.754456 -140.251688) (xy 89.756488 -140.252704) (xy 89.790023 -140.269231)
			(xy 89.853759 -140.308321) (xy 89.913047 -140.353875) (xy 89.967235 -140.405391) (xy 90.015726 -140.462302)
			(xy 90.057986 -140.523981) (xy 90.09355 -140.589749) (xy 90.122025 -140.658882) (xy 90.1431 -140.730619)
			(xy 90.156541 -140.804168) (xy 90.1622 -140.878722) (xy 90.161722 -140.89507) (xy 91.277951 -140.89507)
			(xy 91.281986 -140.819366) (xy 91.294045 -140.744521) (xy 91.313991 -140.67138) (xy 91.341598 -140.600775)
			(xy 91.376554 -140.533504) (xy 91.418462 -140.470329) (xy 91.466848 -140.411967) (xy 91.521164 -140.359079)
			(xy 91.580793 -140.312264) (xy 91.645061 -140.272052) (xy 91.713238 -140.2389) (xy 91.784554 -140.213182)
			(xy 91.858199 -140.19519) (xy 91.933339 -140.185128) (xy 92.009123 -140.183109) (xy 92.084693 -140.189158)
			(xy 92.159191 -140.203205) (xy 92.231774 -140.225091) (xy 92.30162 -140.254568) (xy 92.367937 -140.291303)
			(xy 92.429973 -140.334878) (xy 92.487026 -140.3848) (xy 92.53845 -140.440504) (xy 92.583661 -140.501359)
			(xy 92.622148 -140.566674) (xy 92.653474 -140.63571) (xy 92.677284 -140.707685) (xy 92.693309 -140.781783)
			(xy 92.701368 -140.857164) (xy 92.701872 -140.89507) (xy 92.701368 -140.932976) (xy 92.693309 -141.008357)
			(xy 92.677284 -141.082455) (xy 92.653474 -141.15443) (xy 92.622148 -141.223466) (xy 92.583661 -141.288781)
			(xy 92.53845 -141.349636) (xy 92.487026 -141.40534) (xy 92.429973 -141.455262) (xy 92.367937 -141.498837)
			(xy 92.30162 -141.535572) (xy 92.231774 -141.565049) (xy 92.159191 -141.586935) (xy 92.084693 -141.600982)
			(xy 92.009123 -141.607031) (xy 91.933339 -141.605012) (xy 91.858199 -141.59495) (xy 91.784554 -141.576958)
			(xy 91.713238 -141.55124) (xy 91.645061 -141.518088) (xy 91.580793 -141.477876) (xy 91.521164 -141.431061)
			(xy 91.466848 -141.378173) (xy 91.418462 -141.319811) (xy 91.376554 -141.256636) (xy 91.341598 -141.189365)
			(xy 91.313991 -141.11876) (xy 91.294045 -141.045619) (xy 91.281986 -140.970774) (xy 91.277951 -140.89507)
			(xy 90.161722 -140.89507) (xy 90.160015 -140.953458) (xy 90.155522 -140.990574) (xy 90.150181 -141.026623)
			(xy 90.133081 -141.097469) (xy 90.108828 -141.166195) (xy 90.077677 -141.232081) (xy 90.039954 -141.294439)
			(xy 89.996055 -141.352613) (xy 89.946438 -141.405996) (xy 89.891625 -141.454026) (xy 89.862152 -141.47546)
			(xy 89.838276 -141.492478) (xy 89.780872 -141.597888) (xy 89.780872 -141.955774) (xy 89.781412 -141.972426)
			(xy 89.790025 -142.004597) (xy 89.806671 -142.033442) (xy 89.830215 -142.056996) (xy 89.859053 -142.073654)
			(xy 89.89122 -142.082281) (xy 89.907872 -142.082774) (xy 89.951306 -142.082774) (xy 90.019886 -142.029688)
			(xy 90.030808 -141.98727) (xy 90.040614 -141.951166) (xy 90.066796 -141.881079) (xy 90.100184 -141.814124)
			(xy 90.140409 -141.751039) (xy 90.187028 -141.692521) (xy 90.239526 -141.639214) (xy 90.297325 -141.591706)
			(xy 90.359787 -141.550521) (xy 90.426224 -141.516114) (xy 90.495903 -141.488864) (xy 90.568056 -141.469071)
			(xy 90.641886 -141.456954) (xy 90.716579 -141.452646) (xy 90.791313 -141.456194) (xy 90.865263 -141.467561)
			(xy 90.937612 -141.486619) (xy 91.007565 -141.51316) (xy 91.074348 -141.54689) (xy 91.137226 -141.587438)
			(xy 91.165351 -141.61008) (xy 93.15476 -141.61008) (xy 93.158776 -141.49381) (xy 93.170803 -141.378095)
			(xy 93.190785 -141.263485) (xy 93.218627 -141.150526) (xy 93.254196 -141.039758) (xy 93.297322 -140.931707)
			(xy 93.347799 -140.826889) (xy 93.405388 -140.725804) (xy 93.469814 -140.628932) (xy 93.540769 -140.536736)
			(xy 93.617916 -140.449655) (xy 93.700887 -140.368104) (xy 93.789287 -140.292472) (xy 93.882694 -140.223118)
			(xy 93.980663 -140.160375) (xy 94.082727 -140.104539) (xy 94.188401 -140.055878) (xy 94.29718 -140.014624)
			(xy 94.408545 -139.980973) (xy 94.521968 -139.955085) (xy 94.636905 -139.937084) (xy 94.752811 -139.927055)
			(xy 94.869133 -139.925047) (xy 94.985316 -139.931069) (xy 95.100807 -139.945092) (xy 95.215055 -139.96705)
			(xy 95.327516 -139.996837) (xy 95.437654 -140.034312) (xy 95.544944 -140.079297) (xy 95.648875 -140.131576)
			(xy 95.748951 -140.190901) (xy 95.844697 -140.256989) (xy 95.935654 -140.329525) (xy 96.02139 -140.408164)
			(xy 96.101497 -140.49253) (xy 96.175593 -140.582222) (xy 96.243323 -140.676812) (xy 96.304367 -140.77585)
			(xy 96.358432 -140.878863) (xy 96.405262 -140.98536) (xy 96.444633 -141.094835) (xy 96.476357 -141.206765)
			(xy 96.500283 -141.320617) (xy 96.516297 -141.435849) (xy 96.524324 -141.551911) (xy 96.524826 -141.61008)
			(xy 96.524324 -141.668249) (xy 96.516297 -141.784311) (xy 96.500283 -141.899543) (xy 96.476357 -142.013395)
			(xy 96.444633 -142.125325) (xy 96.405262 -142.2348) (xy 96.358432 -142.341297) (xy 96.304367 -142.44431)
			(xy 96.243323 -142.543348) (xy 96.175593 -142.637938) (xy 96.101497 -142.72763) (xy 96.02139 -142.811996)
			(xy 95.935654 -142.890635) (xy 95.844697 -142.963171) (xy 95.748951 -143.029259) (xy 95.648875 -143.088584)
			(xy 95.544944 -143.140863) (xy 95.437654 -143.185848) (xy 95.327516 -143.223323) (xy 95.215055 -143.25311)
			(xy 95.100807 -143.275068) (xy 94.985316 -143.289091) (xy 94.869133 -143.295113) (xy 94.752811 -143.293105)
			(xy 94.636905 -143.283076) (xy 94.521968 -143.265075) (xy 94.408545 -143.239187) (xy 94.29718 -143.205536)
			(xy 94.188401 -143.164282) (xy 94.082727 -143.115621) (xy 93.980663 -143.059785) (xy 93.882694 -142.997042)
			(xy 93.789287 -142.927688) (xy 93.700887 -142.852056) (xy 93.617916 -142.770505) (xy 93.540769 -142.683424)
			(xy 93.469814 -142.591228) (xy 93.405388 -142.494356) (xy 93.347799 -142.393271) (xy 93.297322 -142.288453)
			(xy 93.254196 -142.180402) (xy 93.218627 -142.069634) (xy 93.190785 -141.956675) (xy 93.170803 -141.842065)
			(xy 93.158776 -141.72635) (xy 93.15476 -141.61008) (xy 91.165351 -141.61008) (xy 91.195504 -141.634355)
			(xy 91.248542 -141.687126) (xy 91.295753 -141.745168) (xy 91.336617 -141.80784) (xy 91.370683 -141.874453)
			(xy 91.397576 -141.94427) (xy 91.416999 -142.016523) (xy 91.428738 -142.090414) (xy 91.432663 -142.165129)
			(xy 91.428732 -142.239844) (xy 91.416987 -142.313734) (xy 91.397558 -142.385985) (xy 91.370659 -142.4558)
			(xy 91.336588 -142.52241) (xy 91.295719 -142.585079) (xy 91.248503 -142.643117) (xy 91.195461 -142.695883)
			(xy 91.137178 -142.742796) (xy 91.074297 -142.783339) (xy 91.007511 -142.817063) (xy 90.937557 -142.843598)
			(xy 90.865206 -142.862651) (xy 90.791255 -142.874011) (xy 90.716521 -142.877554) (xy 90.641828 -142.87324)
			(xy 90.567999 -142.861116) (xy 90.495848 -142.841318) (xy 90.426171 -142.814062) (xy 90.359737 -142.779649)
			(xy 90.297278 -142.73846) (xy 90.239483 -142.690947) (xy 90.186989 -142.637636) (xy 90.140375 -142.579114)
			(xy 90.100155 -142.516026) (xy 90.066773 -142.449068) (xy 90.040597 -142.378978) (xy 90.030808 -142.34287)
			(xy 90.030808 -142.342616) (xy 90.026121 -142.32651) (xy 90.009565 -142.297347) (xy 89.985986 -142.273503)
			(xy 89.95701 -142.256622) (xy 89.924639 -142.247871) (xy 89.907872 -142.247366) (xy 89.85504 -142.247366)
			(xy 89.780872 -142.321534) (xy 89.780872 -142.41145) (xy 89.723722 -142.468346) (xy 88.896952 -143.295116)
			(xy 87.632794 -143.295116) (xy 84.09153 -146.83638) (xy 85.0435 -146.83638) (xy 85.0435 -146.776444)
			(xy 85.051323 -146.717022) (xy 85.066836 -146.659129) (xy 85.089772 -146.603756) (xy 85.119739 -146.55185)
			(xy 85.156226 -146.5043) (xy 85.198606 -146.46192) (xy 85.246156 -146.425433) (xy 85.298062 -146.395466)
			(xy 85.353435 -146.37253) (xy 85.411328 -146.357017) (xy 85.47075 -146.349194) (xy 85.530686 -146.349194)
			(xy 85.590108 -146.357017) (xy 85.648001 -146.37253) (xy 85.703374 -146.395466) (xy 85.75528 -146.425433)
			(xy 85.80283 -146.46192) (xy 85.84521 -146.5043) (xy 85.881697 -146.55185) (xy 85.911664 -146.603756)
			(xy 85.9346 -146.659129) (xy 85.950113 -146.717022) (xy 85.957936 -146.776444) (xy 85.958426 -146.806412)
			(xy 85.957936 -146.83638) (xy 85.950113 -146.895802) (xy 85.9346 -146.953695) (xy 85.911664 -147.009068)
			(xy 85.881697 -147.060974) (xy 85.84521 -147.108524) (xy 85.80283 -147.150904) (xy 85.75528 -147.187391)
			(xy 85.703374 -147.217358) (xy 85.648001 -147.240294) (xy 85.590108 -147.255807) (xy 85.530686 -147.26363)
			(xy 85.47075 -147.26363) (xy 85.411328 -147.255807) (xy 85.353435 -147.240294) (xy 85.298062 -147.217358)
			(xy 85.246156 -147.187391) (xy 85.198606 -147.150904) (xy 85.156226 -147.108524) (xy 85.119739 -147.060974)
			(xy 85.089772 -147.009068) (xy 85.066836 -146.953695) (xy 85.051323 -146.895802) (xy 85.0435 -146.83638)
			(xy 84.09153 -146.83638) (xy 83.545938 -147.381972) (xy 86.639382 -147.381972) (xy 86.639382 -147.322036)
			(xy 86.647205 -147.262614) (xy 86.662718 -147.204721) (xy 86.685654 -147.149348) (xy 86.715621 -147.097442)
			(xy 86.752108 -147.049892) (xy 86.794488 -147.007512) (xy 86.842038 -146.971025) (xy 86.893944 -146.941058)
			(xy 86.949317 -146.918122) (xy 87.00721 -146.902609) (xy 87.066632 -146.894786) (xy 87.126568 -146.894786)
			(xy 87.18599 -146.902609) (xy 87.243883 -146.918122) (xy 87.299256 -146.941058) (xy 87.351162 -146.971025)
			(xy 87.398712 -147.007512) (xy 87.441092 -147.049892) (xy 87.477579 -147.097442) (xy 87.507546 -147.149348)
			(xy 87.530482 -147.204721) (xy 87.545995 -147.262614) (xy 87.553818 -147.322036) (xy 87.554308 -147.352004)
			(xy 87.553818 -147.381972) (xy 87.545995 -147.441394) (xy 87.530482 -147.499287) (xy 87.507546 -147.55466)
			(xy 87.477579 -147.606566) (xy 87.441092 -147.654116) (xy 87.398712 -147.696496) (xy 87.351162 -147.732983)
			(xy 87.299256 -147.76295) (xy 87.243883 -147.785886) (xy 87.18599 -147.801399) (xy 87.126568 -147.809222)
			(xy 87.066632 -147.809222) (xy 87.00721 -147.801399) (xy 86.949317 -147.785886) (xy 86.893944 -147.76295)
			(xy 86.842038 -147.732983) (xy 86.794488 -147.696496) (xy 86.752108 -147.654116) (xy 86.715621 -147.606566)
			(xy 86.685654 -147.55466) (xy 86.662718 -147.499287) (xy 86.647205 -147.441394) (xy 86.639382 -147.381972)
			(xy 83.545938 -147.381972) (xy 82.838544 -148.089366) (xy 82.838544 -148.547578) (xy 83.270326 -148.547578)
			(xy 83.270326 -148.487642) (xy 83.278149 -148.42822) (xy 83.293662 -148.370327) (xy 83.316598 -148.314954)
			(xy 83.346565 -148.263048) (xy 83.383052 -148.215498) (xy 83.425432 -148.173118) (xy 83.472982 -148.136631)
			(xy 83.524888 -148.106664) (xy 83.580261 -148.083728) (xy 83.638154 -148.068215) (xy 83.697576 -148.060392)
			(xy 83.757512 -148.060392) (xy 83.816934 -148.068215) (xy 83.874827 -148.083728) (xy 83.9302 -148.106664)
			(xy 83.982106 -148.136631) (xy 84.029656 -148.173118) (xy 84.072036 -148.215498) (xy 84.108523 -148.263048)
			(xy 84.13849 -148.314954) (xy 84.161426 -148.370327) (xy 84.176939 -148.42822) (xy 84.184762 -148.487642)
			(xy 84.185252 -148.51761) (xy 84.184762 -148.547578) (xy 84.176939 -148.607) (xy 84.161426 -148.664893)
			(xy 84.13849 -148.720266) (xy 84.108523 -148.772172) (xy 84.072036 -148.819722) (xy 84.029656 -148.862102)
			(xy 83.982106 -148.898589) (xy 83.9302 -148.928556) (xy 83.920949 -148.932388) (xy 85.23908 -148.932388)
			(xy 85.23908 -148.872452) (xy 85.246903 -148.81303) (xy 85.262416 -148.755137) (xy 85.285352 -148.699764)
			(xy 85.315319 -148.647858) (xy 85.351806 -148.600308) (xy 85.394186 -148.557928) (xy 85.441736 -148.521441)
			(xy 85.493642 -148.491474) (xy 85.549015 -148.468538) (xy 85.606908 -148.453025) (xy 85.66633 -148.445202)
			(xy 85.726266 -148.445202) (xy 85.785688 -148.453025) (xy 85.843581 -148.468538) (xy 85.898954 -148.491474)
			(xy 85.95086 -148.521441) (xy 85.99841 -148.557928) (xy 86.04079 -148.600308) (xy 86.077277 -148.647858)
			(xy 86.107244 -148.699764) (xy 86.13018 -148.755137) (xy 86.145693 -148.81303) (xy 86.153516 -148.872452)
			(xy 86.154006 -148.90242) (xy 86.153516 -148.932388) (xy 86.145693 -148.99181) (xy 86.13018 -149.049703)
			(xy 86.107244 -149.105076) (xy 86.077277 -149.156982) (xy 86.04079 -149.204532) (xy 85.99841 -149.246912)
			(xy 85.95086 -149.283399) (xy 85.898954 -149.313366) (xy 85.843581 -149.336302) (xy 85.785688 -149.351815)
			(xy 85.726266 -149.359638) (xy 85.66633 -149.359638) (xy 85.606908 -149.351815) (xy 85.549015 -149.336302)
			(xy 85.493642 -149.313366) (xy 85.441736 -149.283399) (xy 85.394186 -149.246912) (xy 85.351806 -149.204532)
			(xy 85.315319 -149.156982) (xy 85.285352 -149.105076) (xy 85.262416 -149.049703) (xy 85.246903 -148.99181)
			(xy 85.23908 -148.932388) (xy 83.920949 -148.932388) (xy 83.874827 -148.951492) (xy 83.816934 -148.967005)
			(xy 83.757512 -148.974828) (xy 83.697576 -148.974828) (xy 83.638154 -148.967005) (xy 83.580261 -148.951492)
			(xy 83.524888 -148.928556) (xy 83.472982 -148.898589) (xy 83.425432 -148.862102) (xy 83.383052 -148.819722)
			(xy 83.346565 -148.772172) (xy 83.316598 -148.720266) (xy 83.293662 -148.664893) (xy 83.278149 -148.607)
			(xy 83.270326 -148.547578) (xy 82.838544 -148.547578) (xy 82.838544 -149.841708) (xy 83.837 -149.841708)
			(xy 83.837 -149.781772) (xy 83.844823 -149.72235) (xy 83.860336 -149.664457) (xy 83.883272 -149.609084)
			(xy 83.913239 -149.557178) (xy 83.949726 -149.509628) (xy 83.992106 -149.467248) (xy 84.039656 -149.430761)
			(xy 84.091562 -149.400794) (xy 84.146935 -149.377858) (xy 84.204828 -149.362345) (xy 84.26425 -149.354522)
			(xy 84.324186 -149.354522) (xy 84.383608 -149.362345) (xy 84.441501 -149.377858) (xy 84.496874 -149.400794)
			(xy 84.54878 -149.430761) (xy 84.59633 -149.467248) (xy 84.63871 -149.509628) (xy 84.675197 -149.557178)
			(xy 84.705164 -149.609084) (xy 84.7281 -149.664457) (xy 84.743613 -149.72235) (xy 84.751436 -149.781772)
			(xy 84.751926 -149.81174) (xy 84.751436 -149.841708) (xy 84.743613 -149.90113) (xy 84.7281 -149.959023)
			(xy 84.705164 -150.014396) (xy 84.675197 -150.066302) (xy 84.63871 -150.113852) (xy 84.59633 -150.156232)
			(xy 84.54878 -150.192719) (xy 84.496874 -150.222686) (xy 84.441501 -150.245622) (xy 84.383608 -150.261135)
			(xy 84.324186 -150.268958) (xy 84.26425 -150.268958) (xy 84.204828 -150.261135) (xy 84.146935 -150.245622)
			(xy 84.091562 -150.222686) (xy 84.039656 -150.192719) (xy 83.992106 -150.156232) (xy 83.949726 -150.113852)
			(xy 83.913239 -150.066302) (xy 83.883272 -150.014396) (xy 83.860336 -149.959023) (xy 83.844823 -149.90113)
			(xy 83.837 -149.841708) (xy 82.838544 -149.841708) (xy 82.838544 -150.825454) (xy 83.255862 -151.242772)
			(xy 84.315282 -151.242772) (xy 84.315282 -151.182836) (xy 84.323105 -151.123414) (xy 84.338618 -151.065521)
			(xy 84.361554 -151.010148) (xy 84.391521 -150.958242) (xy 84.428008 -150.910692) (xy 84.470388 -150.868312)
			(xy 84.517938 -150.831825) (xy 84.569844 -150.801858) (xy 84.625217 -150.778922) (xy 84.68311 -150.763409)
			(xy 84.742532 -150.755586) (xy 84.802468 -150.755586) (xy 84.86189 -150.763409) (xy 84.919783 -150.778922)
			(xy 84.975156 -150.801858) (xy 85.027062 -150.831825) (xy 85.074612 -150.868312) (xy 85.116992 -150.910692)
			(xy 85.153479 -150.958242) (xy 85.183446 -151.010148) (xy 85.206382 -151.065521) (xy 85.221895 -151.123414)
			(xy 85.229718 -151.182836) (xy 85.230208 -151.212804) (xy 85.229718 -151.242772) (xy 85.221895 -151.302194)
			(xy 85.206382 -151.360087) (xy 85.183446 -151.41546) (xy 85.153479 -151.467366) (xy 85.116992 -151.514916)
			(xy 85.074612 -151.557296) (xy 85.027062 -151.593783) (xy 84.975156 -151.62375) (xy 84.919783 -151.646686)
			(xy 84.86189 -151.662199) (xy 84.802468 -151.670022) (xy 84.742532 -151.670022) (xy 84.68311 -151.662199)
			(xy 84.625217 -151.646686) (xy 84.569844 -151.62375) (xy 84.517938 -151.593783) (xy 84.470388 -151.557296)
			(xy 84.428008 -151.514916) (xy 84.391521 -151.467366) (xy 84.361554 -151.41546) (xy 84.338618 -151.360087)
			(xy 84.323105 -151.302194) (xy 84.315282 -151.242772) (xy 83.255862 -151.242772) (xy 85.37321 -153.36012)
			(xy 86.39887 -153.36012) (xy 86.402874 -153.160022) (xy 86.414881 -152.960244) (xy 86.434872 -152.761107)
			(xy 86.462814 -152.562929) (xy 86.498662 -152.366027) (xy 86.54236 -152.170718) (xy 86.593837 -151.977313)
			(xy 86.653011 -151.786123) (xy 86.719787 -151.597453) (xy 86.794059 -151.411606) (xy 86.875706 -151.228879)
			(xy 86.964599 -151.049566) (xy 87.060595 -150.873952) (xy 87.16354 -150.70232) (xy 87.27327 -150.534944)
			(xy 87.389608 -150.372093) (xy 87.512369 -150.214026) (xy 87.641356 -150.060998) (xy 87.776363 -149.913253)
			(xy 87.917172 -149.771027) (xy 88.063559 -149.63455) (xy 88.215289 -149.504038) (xy 88.37212 -149.379702)
			(xy 88.533799 -149.26174) (xy 88.700069 -149.150341) (xy 88.870662 -149.045684) (xy 89.045306 -148.947936)
			(xy 89.223722 -148.857253) (xy 89.405622 -148.773782) (xy 89.590717 -148.697655) (xy 89.778709 -148.628995)
			(xy 89.969298 -148.567911) (xy 90.162178 -148.514501) (xy 90.35704 -148.468852) (xy 90.553573 -148.431035)
			(xy 90.751462 -148.401111) (xy 90.950389 -148.379129) (xy 91.150037 -148.365124) (xy 91.350085 -148.359118)
			(xy 91.550213 -148.36112) (xy 91.750101 -148.371128) (xy 91.949428 -148.389125) (xy 92.147876 -148.415083)
			(xy 92.345126 -148.44896) (xy 92.540863 -148.490702) (xy 92.734773 -148.540241) (xy 92.926546 -148.597499)
			(xy 93.115875 -148.662384) (xy 93.302455 -148.734792) (xy 93.48599 -148.814608) (xy 93.666184 -148.901702)
			(xy 93.842749 -148.995936) (xy 94.015402 -149.097159) (xy 94.183867 -149.205209) (xy 94.347875 -149.319912)
			(xy 94.507162 -149.441086) (xy 94.661473 -149.568535) (xy 94.810561 -149.702056) (xy 94.954188 -149.841436)
			(xy 95.092124 -149.98645) (xy 95.224147 -150.136867) (xy 95.350046 -150.292445) (xy 95.46962 -150.452937)
			(xy 95.582676 -150.618083) (xy 95.689035 -150.787621) (xy 95.788526 -150.961279) (xy 95.880989 -151.138778)
			(xy 95.966276 -151.319834) (xy 96.044251 -151.504158) (xy 96.114788 -151.691454) (xy 96.177776 -151.881422)
			(xy 96.233113 -152.073758) (xy 96.28071 -152.268154) (xy 96.320491 -152.464299) (xy 96.352393 -152.661878)
			(xy 96.376364 -152.860575) (xy 96.392366 -153.060073) (xy 96.400373 -153.260051) (xy 96.400874 -153.36012)
			(xy 96.400373 -153.460189) (xy 96.392366 -153.660167) (xy 96.376364 -153.859665) (xy 96.352393 -154.058362)
			(xy 96.320491 -154.255941) (xy 96.28071 -154.452086) (xy 96.233113 -154.646482) (xy 96.177776 -154.838818)
			(xy 96.114788 -155.028786) (xy 96.044251 -155.216082) (xy 95.966276 -155.400406) (xy 95.880989 -155.581462)
			(xy 95.788526 -155.758961) (xy 95.689035 -155.932619) (xy 95.582676 -156.102157) (xy 95.46962 -156.267303)
			(xy 95.350046 -156.427795) (xy 95.224147 -156.583373) (xy 95.092124 -156.73379) (xy 94.954188 -156.878804)
			(xy 94.810561 -157.018184) (xy 94.661473 -157.151705) (xy 94.507162 -157.279154) (xy 94.347875 -157.400328)
			(xy 94.183867 -157.515031) (xy 94.015402 -157.623081) (xy 93.842749 -157.724304) (xy 93.666184 -157.818538)
			(xy 93.48599 -157.905632) (xy 93.302455 -157.985448) (xy 93.115875 -158.057856) (xy 92.926546 -158.122741)
			(xy 92.734773 -158.179999) (xy 92.540863 -158.229538) (xy 92.345126 -158.27128) (xy 92.147876 -158.305157)
			(xy 91.949428 -158.331115) (xy 91.750101 -158.349112) (xy 91.550213 -158.35912) (xy 91.350085 -158.361122)
			(xy 91.150037 -158.355116) (xy 90.950389 -158.341111) (xy 90.751462 -158.319129) (xy 90.553573 -158.289205)
			(xy 90.35704 -158.251388) (xy 90.162178 -158.205739) (xy 89.969298 -158.152329) (xy 89.778709 -158.091245)
			(xy 89.590717 -158.022585) (xy 89.405622 -157.946458) (xy 89.223722 -157.862987) (xy 89.045306 -157.772304)
			(xy 88.870662 -157.674556) (xy 88.700069 -157.569899) (xy 88.533799 -157.4585) (xy 88.37212 -157.340538)
			(xy 88.215289 -157.216202) (xy 88.063559 -157.08569) (xy 87.917172 -156.949213) (xy 87.776363 -156.806987)
			(xy 87.641356 -156.659242) (xy 87.512369 -156.506214) (xy 87.389608 -156.348147) (xy 87.27327 -156.185296)
			(xy 87.16354 -156.01792) (xy 87.060595 -155.846288) (xy 86.964599 -155.670674) (xy 86.875706 -155.491361)
			(xy 86.794059 -155.308634) (xy 86.719787 -155.122787) (xy 86.653011 -154.934117) (xy 86.593837 -154.742927)
			(xy 86.54236 -154.549522) (xy 86.498662 -154.354213) (xy 86.462814 -154.157311) (xy 86.434872 -153.959133)
			(xy 86.414881 -153.759996) (xy 86.402874 -153.560218) (xy 86.39887 -153.36012) (xy 85.37321 -153.36012)
			(xy 85.700616 -153.687526) (xy 85.700616 -159.763714) (xy 85.701158 -159.78033) (xy 85.709754 -159.812432)
			(xy 85.726359 -159.841219) (xy 85.7377 -159.853376) (xy 89.415874 -163.531296) (xy 91.314016 -163.531296)
			(xy 92.28709 -164.50437) (xy 92.553282 -164.770816) (xy 92.597478 -164.775896) (xy 92.626505 -164.779676)
			(xy 92.683343 -164.793673) (xy 92.737933 -164.814804) (xy 92.789382 -164.842723) (xy 92.836852 -164.876975)
			(xy 92.879566 -164.917) (xy 92.916828 -164.962145) (xy 92.948029 -165.011673) (xy 92.97266 -165.064775)
			(xy 92.990319 -165.120585) (xy 93.000717 -165.17819) (xy 93.003685 -165.236652) (xy 92.999174 -165.295014)
			(xy 92.993718 -165.323774) (xy 92.993718 -165.324028) (xy 92.990954 -165.339532) (xy 92.992267 -165.370987)
			(xy 93.001272 -165.401154) (xy 93.017417 -165.428181) (xy 93.028262 -165.439598) (xy 93.496384 -165.90772)
			(xy 93.496384 -165.923468) (xy 93.570552 -165.997636) (xy 94.121224 -165.997636) (xy 94.121224 -166.745412)
			(xy 94.128336 -166.765732) (xy 94.136893 -166.792091) (xy 94.146091 -166.846736) (xy 94.146624 -166.874444)
			(xy 94.146624 -168.069514) (xy 93.928692 -168.287446) (xy 93.70822 -168.507664) (xy 92.331032 -168.507664)
			(xy 92.316025 -168.509232) (xy 92.28732 -168.518503) (xy 92.261586 -168.534241) (xy 92.240254 -168.555569)
			(xy 92.224512 -168.581301) (xy 92.215236 -168.610004) (xy 92.213684 -168.625012) (xy 92.213684 -170.301412)
			(xy 92.21424 -170.31806) (xy 92.222879 -170.350217) (xy 92.239539 -170.379046) (xy 92.263087 -170.402587)
			(xy 92.291922 -170.419237) (xy 92.324082 -170.427865) (xy 92.357379 -170.427884) (xy 92.389548 -170.419291)
			(xy 92.418401 -170.402672) (xy 92.4306 -170.391328) (xy 92.565728 -170.2562) (xy 94.7674 -170.2562)
			(xy 94.784048 -170.255657) (xy 94.816211 -170.247039) (xy 94.845046 -170.230391) (xy 94.868591 -170.206846)
			(xy 94.885239 -170.178011) (xy 94.893857 -170.145848) (xy 94.8944 -170.1292) (xy 94.8944 -169.458386)
			(xy 95.340932 -169.0116) (xy 95.351787 -169.000081) (xy 95.367974 -168.972895) (xy 95.376952 -168.942555)
			(xy 95.378016 -168.926764) (xy 95.379935 -168.888232) (xy 95.390057 -168.811745) (xy 95.407269 -168.736536)
			(xy 95.431419 -168.663259) (xy 95.462297 -168.592554) (xy 95.499634 -168.525036) (xy 95.543105 -168.461294)
			(xy 95.59233 -168.401884) (xy 95.619316 -168.374314) (xy 97.380552 -166.613078) (xy 97.380552 -86.626954)
			(xy 98.21926 -85.788246) (xy 98.21926 -84.620862) (xy 98.127058 -84.52866) (xy 97.827084 -84.52866)
			(xy 97.795163 -84.528203) (xy 97.731721 -84.521065) (xy 97.669467 -84.506912) (xy 97.609174 -84.485921)
			(xy 97.580196 -84.472526) (xy 97.554288 -84.46008) (xy 97.260918 -84.46008) (xy 97.244267 -84.460621)
			(xy 97.212099 -84.469235) (xy 97.183257 -84.485882) (xy 97.159705 -84.509426) (xy 97.14305 -84.538264)
			(xy 97.134426 -84.570429) (xy 97.133918 -84.58708) (xy 97.133918 -85.10778) (xy 96.370902 -85.10778)
			(xy 96.370902 -85.08238) (xy 94.766638 -85.08238) (xy 94.725236 -85.040978) (xy 94.55277 -85.040978)
			(xy 94.350078 -84.838286) (xy 94.337946 -84.826825) (xy 94.309067 -84.810116) (xy 94.276844 -84.801465)
			(xy 94.24348 -84.801465) (xy 94.211257 -84.810116) (xy 94.182378 -84.826825) (xy 94.170246 -84.838286)
			(xy 93.867478 -85.141054) (xy 93.809566 -85.19922) (xy 93.568012 -85.440774) (xy 93.568012 -86.068916)
			(xy 93.587824 -86.090278) (xy 93.622439 -86.137143) (xy 93.650828 -86.188021) (xy 93.672531 -86.242091)
			(xy 93.687198 -86.298477) (xy 93.694591 -86.356269) (xy 93.694591 -86.414531) (xy 93.687198 -86.472323)
			(xy 93.672531 -86.528709) (xy 93.650828 -86.582779) (xy 93.622439 -86.633657) (xy 93.587824 -86.680522)
			(xy 93.568012 -86.701884) (xy 93.568012 -87.36584) (xy 89.92616 -91.007692) (xy 89.92616 -93.322394)
			(xy 89.926631 -93.338696) (xy 89.934843 -93.370247) (xy 89.950782 -93.398688) (xy 89.96172 -93.410786)
			(xy 89.987492 -93.438166) (xy 90.033746 -93.497452) (xy 90.073494 -93.561284) (xy 90.106295 -93.628948)
			(xy 90.131782 -93.699692) (xy 90.149672 -93.772729) (xy 90.159766 -93.847244) (xy 90.161446 -93.90507)
			(xy 91.277697 -93.90507) (xy 91.281732 -93.829366) (xy 91.293791 -93.754521) (xy 91.313737 -93.68138)
			(xy 91.341344 -93.610775) (xy 91.3763 -93.543504) (xy 91.418208 -93.480329) (xy 91.466594 -93.421967)
			(xy 91.52091 -93.369079) (xy 91.580539 -93.322264) (xy 91.644807 -93.282052) (xy 91.712984 -93.2489)
			(xy 91.7843 -93.223182) (xy 91.857945 -93.20519) (xy 91.933085 -93.195128) (xy 92.008869 -93.193109)
			(xy 92.084439 -93.199158) (xy 92.158937 -93.213205) (xy 92.23152 -93.235091) (xy 92.301366 -93.264568)
			(xy 92.367683 -93.301303) (xy 92.429719 -93.344878) (xy 92.486772 -93.3948) (xy 92.538196 -93.450504)
			(xy 92.583407 -93.511359) (xy 92.621894 -93.576674) (xy 92.65322 -93.64571) (xy 92.67703 -93.717685)
			(xy 92.693055 -93.791783) (xy 92.701114 -93.867164) (xy 92.701618 -93.90507) (xy 92.701114 -93.942976)
			(xy 92.693055 -94.018357) (xy 92.67703 -94.092455) (xy 92.65322 -94.16443) (xy 92.621894 -94.233466)
			(xy 92.583407 -94.298781) (xy 92.538196 -94.359636) (xy 92.486772 -94.41534) (xy 92.429719 -94.465262)
			(xy 92.367683 -94.508837) (xy 92.301366 -94.545572) (xy 92.23152 -94.575049) (xy 92.158937 -94.596935)
			(xy 92.084439 -94.610982) (xy 92.008869 -94.617031) (xy 91.933085 -94.615012) (xy 91.857945 -94.60495)
			(xy 91.7843 -94.586958) (xy 91.712984 -94.56124) (xy 91.644807 -94.528088) (xy 91.580539 -94.487876)
			(xy 91.52091 -94.441061) (xy 91.466594 -94.388173) (xy 91.418208 -94.329811) (xy 91.3763 -94.266636)
			(xy 91.341344 -94.199365) (xy 91.313737 -94.12876) (xy 91.293791 -94.055619) (xy 91.281732 -93.980774)
			(xy 91.277697 -93.90507) (xy 90.161446 -93.90507) (xy 90.16195 -93.922407) (xy 90.159586 -93.959934)
			(xy 90.156094 -93.998494) (xy 90.141785 -94.07459) (xy 90.119302 -94.148684) (xy 90.08891 -94.219899)
			(xy 90.050968 -94.287395) (xy 90.005924 -94.350374) (xy 89.954311 -94.408093) (xy 89.896738 -94.459868)
			(xy 89.833886 -94.505089) (xy 89.80043 -94.524576) (xy 89.780905 -94.536499) (xy 89.746124 -94.566214)
			(xy 89.717227 -94.601678) (xy 89.695148 -94.641743) (xy 89.680602 -94.685114) (xy 89.674057 -94.73039)
			(xy 89.675727 -94.776105) (xy 89.685556 -94.820782) (xy 89.703228 -94.862977) (xy 89.72817 -94.901325)
			(xy 89.743534 -94.918276) (xy 89.749376 -94.924372) (xy 89.780364 -94.95536) (xy 89.780364 -94.96679)
			(xy 89.780906 -94.983441) (xy 89.789521 -95.015609) (xy 89.806168 -95.044452) (xy 89.829712 -95.068004)
			(xy 89.858548 -95.084661) (xy 89.890713 -95.093288) (xy 89.907364 -95.09379) (xy 89.907618 -95.09379)
			(xy 89.924382 -95.093277) (xy 89.956749 -95.084531) (xy 89.985717 -95.06765) (xy 90.009282 -95.043799)
			(xy 90.025814 -95.014631) (xy 90.030554 -94.99854) (xy 90.030554 -94.998286) (xy 90.040312 -94.962167)
			(xy 90.066403 -94.892041) (xy 90.099708 -94.82504) (xy 90.139858 -94.761903) (xy 90.186411 -94.703327)
			(xy 90.238852 -94.649959) (xy 90.296604 -94.602387) (xy 90.359028 -94.561136) (xy 90.425435 -94.526663)
			(xy 90.495093 -94.499347) (xy 90.567232 -94.479491) (xy 90.641056 -94.467312) (xy 90.71575 -94.462946)
			(xy 90.790491 -94.466441) (xy 90.864452 -94.477759) (xy 90.936817 -94.496773) (xy 91.006788 -94.523275)
			(xy 91.073593 -94.556973) (xy 91.136493 -94.597493) (xy 91.194795 -94.644388) (xy 91.247855 -94.697142)
			(xy 91.295087 -94.755172) (xy 91.335971 -94.817837) (xy 91.370054 -94.884445) (xy 91.39696 -94.954262)
			(xy 91.416393 -95.026516) (xy 91.428138 -95.10041) (xy 91.432066 -95.175129) (xy 91.428132 -95.249848)
			(xy 91.416381 -95.323741) (xy 91.396942 -95.395994) (xy 91.37003 -95.465808) (xy 91.335941 -95.532414)
			(xy 91.295053 -95.595075) (xy 91.247816 -95.653101) (xy 91.194752 -95.70585) (xy 91.136446 -95.752741)
			(xy 91.073542 -95.793256) (xy 91.006735 -95.826948) (xy 90.936762 -95.853444) (xy 90.864395 -95.872453)
			(xy 90.790433 -95.883764) (xy 90.715692 -95.887253) (xy 90.640998 -95.882881) (xy 90.567175 -95.870697)
			(xy 90.495037 -95.850834) (xy 90.425382 -95.823513) (xy 90.358978 -95.789034) (xy 90.296557 -95.747779)
			(xy 90.23881 -95.700202) (xy 90.186372 -95.646829) (xy 90.139824 -95.588249) (xy 90.099679 -95.525109)
			(xy 90.06638 -95.458105) (xy 90.040295 -95.387978) (xy 90.030554 -95.351854) (xy 90.030554 -95.3516)
			(xy 90.025864 -95.335498) (xy 90.009304 -95.306347) (xy 89.985723 -95.282516) (xy 89.956749 -95.265649)
			(xy 89.924381 -95.256912) (xy 89.907618 -95.25635) (xy 89.907364 -95.25635) (xy 89.890715 -95.256849)
			(xy 89.858553 -95.265477) (xy 89.829721 -95.282136) (xy 89.806183 -95.305689) (xy 89.789544 -95.334533)
			(xy 89.780938 -95.3667) (xy 89.780364 -95.38335) (xy 89.780364 -95.742252) (xy 89.780846 -95.758043)
			(xy 89.788613 -95.788655) (xy 89.803658 -95.816423) (xy 89.82506 -95.839647) (xy 89.838022 -95.848678)
			(xy 89.869627 -95.869834) (xy 89.928586 -95.917882) (xy 89.982085 -95.971944) (xy 90.029512 -96.031404)
			(xy 90.070327 -96.095583) (xy 90.104063 -96.163749) (xy 90.130337 -96.235124) (xy 90.148848 -96.308895)
			(xy 90.159385 -96.38422) (xy 90.161341 -96.44507) (xy 91.277697 -96.44507) (xy 91.281732 -96.369366)
			(xy 91.293791 -96.294521) (xy 91.313737 -96.22138) (xy 91.341344 -96.150775) (xy 91.3763 -96.083504)
			(xy 91.418208 -96.020329) (xy 91.466594 -95.961967) (xy 91.52091 -95.909079) (xy 91.580539 -95.862264)
			(xy 91.644807 -95.822052) (xy 91.712984 -95.7889) (xy 91.7843 -95.763182) (xy 91.857945 -95.74519)
			(xy 91.933085 -95.735128) (xy 92.008869 -95.733109) (xy 92.084439 -95.739158) (xy 92.158937 -95.753205)
			(xy 92.23152 -95.775091) (xy 92.301366 -95.804568) (xy 92.367683 -95.841303) (xy 92.429719 -95.884878)
			(xy 92.486772 -95.9348) (xy 92.538196 -95.990504) (xy 92.583407 -96.051359) (xy 92.621894 -96.116674)
			(xy 92.65322 -96.18571) (xy 92.67703 -96.257685) (xy 92.693055 -96.331783) (xy 92.701114 -96.407164)
			(xy 92.701618 -96.44507) (xy 92.701114 -96.482976) (xy 92.693055 -96.558357) (xy 92.67703 -96.632455)
			(xy 92.65322 -96.70443) (xy 92.621894 -96.773466) (xy 92.583407 -96.838781) (xy 92.538196 -96.899636)
			(xy 92.486772 -96.95534) (xy 92.429719 -97.005262) (xy 92.367683 -97.048837) (xy 92.301366 -97.085572)
			(xy 92.23152 -97.115049) (xy 92.158937 -97.136935) (xy 92.084439 -97.150982) (xy 92.008869 -97.157031)
			(xy 91.933085 -97.155012) (xy 91.857945 -97.14495) (xy 91.7843 -97.126958) (xy 91.712984 -97.10124)
			(xy 91.644807 -97.068088) (xy 91.580539 -97.027876) (xy 91.52091 -96.981061) (xy 91.466594 -96.928173)
			(xy 91.418208 -96.869811) (xy 91.3763 -96.806636) (xy 91.341344 -96.739365) (xy 91.313737 -96.66876)
			(xy 91.293791 -96.595619) (xy 91.281732 -96.520774) (xy 91.277697 -96.44507) (xy 90.161341 -96.44507)
			(xy 90.161829 -96.460238) (xy 90.15615 -96.536084) (xy 90.142414 -96.610891) (xy 90.120777 -96.683806)
			(xy 90.091487 -96.753998) (xy 90.054878 -96.820666) (xy 90.011367 -96.883048) (xy 89.96145 -96.940434)
			(xy 89.905697 -96.992168) (xy 89.844745 -97.037661) (xy 89.779288 -97.076393) (xy 89.710073 -97.107922)
			(xy 89.63789 -97.13189) (xy 89.563563 -97.148022) (xy 89.487939 -97.156134) (xy 89.411881 -97.156134)
			(xy 89.336257 -97.148022) (xy 89.26193 -97.13189) (xy 89.189747 -97.107922) (xy 89.120532 -97.076393)
			(xy 89.055075 -97.037661) (xy 88.994123 -96.992168) (xy 88.93837 -96.940434) (xy 88.888453 -96.883048)
			(xy 88.844942 -96.820666) (xy 88.808333 -96.753998) (xy 88.779043 -96.683806) (xy 88.757406 -96.610891)
			(xy 88.74367 -96.536084) (xy 88.737991 -96.460238) (xy 88.740435 -96.38422) (xy 88.750972 -96.308895)
			(xy 88.769483 -96.235124) (xy 88.795757 -96.163749) (xy 88.829493 -96.095583) (xy 88.870308 -96.031404)
			(xy 88.917735 -95.971944) (xy 88.971234 -95.917882) (xy 89.030193 -95.869834) (xy 89.061798 -95.848678)
			(xy 89.07477 -95.839657) (xy 89.096184 -95.816438) (xy 89.111231 -95.788665) (xy 89.118987 -95.758045)
			(xy 89.119456 -95.742252) (xy 89.119456 -95.38335) (xy 89.118967 -95.366693) (xy 89.110354 -95.334512)
			(xy 89.093701 -95.305659) (xy 89.070145 -95.282102) (xy 89.041293 -95.265449) (xy 89.009113 -95.256833)
			(xy 88.992456 -95.25635) (xy 88.992202 -95.25635) (xy 88.975434 -95.25686) (xy 88.943058 -95.2656)
			(xy 88.914079 -95.282477) (xy 88.8905 -95.306324) (xy 88.873952 -95.335492) (xy 88.869266 -95.3516)
			(xy 88.869266 -95.351854) (xy 88.859425 -95.38824) (xy 88.833088 -95.45887) (xy 88.799435 -95.526322)
			(xy 88.758843 -95.58984) (xy 88.711766 -95.648713) (xy 88.658732 -95.702282) (xy 88.600335 -95.749947)
			(xy 88.569038 -95.770954) (xy 88.537354 -95.791068) (xy 88.470545 -95.825265) (xy 88.400509 -95.852242)
			(xy 88.328022 -95.871698) (xy 88.253891 -95.883418) (xy 88.178938 -95.887272) (xy 88.103995 -95.883216)
			(xy 88.029895 -95.871295) (xy 87.957462 -95.851643) (xy 87.887498 -95.824477) (xy 87.820783 -95.790099)
			(xy 87.758055 -95.748891) (xy 87.700013 -95.701311) (xy 87.6473 -95.647886) (xy 87.600502 -95.58921)
			(xy 87.560139 -95.525936) (xy 87.526659 -95.458765) (xy 87.500434 -95.388443) (xy 87.481755 -95.315753)
			(xy 87.47083 -95.2415) (xy 87.467779 -95.16651) (xy 87.472638 -95.091615) (xy 87.485351 -95.017647)
			(xy 87.505778 -94.945428) (xy 87.519256 -94.910402) (xy 87.533416 -94.876275) (xy 87.567824 -94.810885)
			(xy 87.608823 -94.749413) (xy 87.632032 -94.720664) (xy 87.655903 -94.692606) (xy 87.708537 -94.641059)
			(xy 87.766215 -94.595227) (xy 87.828321 -94.555601) (xy 87.89419 -94.522605) (xy 87.963115 -94.496592)
			(xy 88.03436 -94.477842) (xy 88.07069 -94.471744) (xy 88.085449 -94.469014) (xy 88.113192 -94.45758)
			(xy 88.137492 -94.439976) (xy 88.157001 -94.417177) (xy 88.170639 -94.390448) (xy 88.177648 -94.361272)
			(xy 88.178132 -94.346268) (xy 88.178132 -92.955364) (xy 88.847168 -92.286328) (xy 88.847168 -90.322908)
			(xy 91.82354 -87.346282) (xy 91.82354 -86.845902) (xy 91.622626 -86.644988) (xy 91.567762 -86.58987)
			(xy 91.523566 -86.58479) (xy 91.493913 -86.58092) (xy 91.435886 -86.566461) (xy 91.380236 -86.544566)
			(xy 91.327914 -86.515608) (xy 91.279811 -86.480079) (xy 91.236746 -86.438586) (xy 91.199455 -86.391837)
			(xy 91.168572 -86.340627) (xy 91.144624 -86.28583) (xy 91.12802 -86.22838) (xy 91.119042 -86.169256)
			(xy 91.117843 -86.109467) (xy 91.124444 -86.050031) (xy 91.138733 -85.991961) (xy 91.160465 -85.936249)
			(xy 91.18927 -85.883842) (xy 91.224658 -85.835635) (xy 91.244928 -85.813646) (xy 91.244928 -85.555074)
			(xy 91.341956 -85.457792) (xy 91.697048 -85.1027) (xy 91.71298 -85.086056) (xy 91.739146 -85.04814)
			(xy 91.75805 -85.006128) (xy 91.769073 -84.961398) (xy 91.771855 -84.915413) (xy 91.766303 -84.86968)
			(xy 91.7526 -84.825697) (xy 91.731194 -84.784903) (xy 91.702787 -84.748635) (xy 91.668308 -84.718081)
			(xy 91.628888 -84.69424) (xy 91.585816 -84.677895) (xy 91.540504 -84.66958) (xy 91.51747 -84.669122)
			(xy 91.05265 -84.669122) (xy 91.05265 -83.921092) (xy 91.045538 -83.900772) (xy 91.041115 -83.887518)
			(xy 91.034248 -83.860431) (xy 91.031822 -83.84667) (xy 91.029536 -83.830668) (xy 91.028266 -83.816698)
			(xy 91.027504 -83.792314) (xy 91.027504 -81.013808) (xy 90.673174 -80.659478) (xy 90.673174 -79.232506)
			(xy 90.463116 -79.022448) (xy 90.463116 -76.657708) (xy 90.429842 -76.599288) (xy 90.40114 -76.58227)
			(xy 90.381328 -76.56957) (xy 90.355803 -76.551924) (xy 90.309305 -76.510832) (xy 90.268786 -76.463835)
			(xy 90.234987 -76.411795) (xy 90.208529 -76.355665) (xy 90.189898 -76.296475) (xy 90.179434 -76.235311)
			(xy 90.17733 -76.173294) (xy 90.183624 -76.111561) (xy 90.198201 -76.051244) (xy 90.220793 -75.99345)
			(xy 90.250987 -75.939239) (xy 90.288229 -75.889604) (xy 90.331834 -75.845455) (xy 90.381005 -75.807603)
			(xy 90.434839 -75.776741) (xy 90.492349 -75.753435) (xy 90.552481 -75.738114) (xy 90.583258 -75.734164)
			(xy 90.627454 -75.729084) (xy 90.742516 -75.614022) (xy 90.742516 -74.25817) (xy 90.741984 -74.241549)
			(xy 90.733407 -74.209433) (xy 90.716817 -74.180627) (xy 90.705432 -74.168508) (xy 84.991956 -68.455286)
			(xy 84.991956 -57.574688) (xy 88.181688 -54.384956) (xy 88.196479 -54.368168) (xy 88.220521 -54.330438)
			(xy 88.237589 -54.289082) (xy 88.247154 -54.245377) (xy 88.248923 -54.200673) (xy 88.242839 -54.15635)
			(xy 88.229092 -54.113775) (xy 88.208105 -54.074264) (xy 88.180526 -54.039036) (xy 88.147207 -54.009179)
			(xy 88.109177 -53.985614) (xy 88.067609 -53.96907) (xy 88.045798 -53.964078) (xy 88.005731 -53.955811)
			(xy 87.927679 -53.931286) (xy 87.852958 -53.897964) (xy 87.782554 -53.856288) (xy 87.749634 -53.831998)
			(xy 87.720468 -53.809269) (xy 87.666518 -53.758696) (xy 87.618104 -53.702802) (xy 87.575746 -53.642188)
			(xy 87.539902 -53.577509) (xy 87.510957 -53.509463) (xy 87.489225 -53.438781) (xy 87.474938 -53.366227)
			(xy 87.468252 -53.292583) (xy 87.469239 -53.218643) (xy 87.477887 -53.145203) (xy 87.494104 -53.073056)
			(xy 87.517714 -53.002979) (xy 87.548463 -52.935729) (xy 87.58602 -52.872029) (xy 87.62998 -52.812567)
			(xy 87.679869 -52.757984) (xy 87.735148 -52.708869) (xy 87.795222 -52.66575) (xy 87.859444 -52.629092)
			(xy 87.92712 -52.599292) (xy 87.997522 -52.57667) (xy 88.06989 -52.56147) (xy 88.143444 -52.553856)
			(xy 88.180418 -52.553362) (xy 88.181434 -52.553362) (xy 88.19806 -52.552791) (xy 88.230168 -52.544133)
			(xy 88.258945 -52.527467) (xy 88.282434 -52.503928) (xy 88.299037 -52.475115) (xy 88.307626 -52.442989)
			(xy 88.30818 -52.426362) (xy 88.30818 -51.563778) (xy 88.30768 -51.547105) (xy 88.299033 -51.5149)
			(xy 88.282336 -51.486035) (xy 88.258729 -51.462483) (xy 88.229826 -51.445853) (xy 88.1976 -51.437282)
			(xy 88.180926 -51.436778) (xy 88.142906 -51.43634) (xy 88.067289 -51.428342) (xy 87.992956 -51.412328)
			(xy 87.920754 -51.388481) (xy 87.851505 -51.357071) (xy 87.786001 -51.318458) (xy 87.724986 -51.273081)
			(xy 87.669156 -51.221458) (xy 87.619149 -51.164177) (xy 87.575533 -51.101891) (xy 87.538807 -51.03531)
			(xy 87.509388 -50.965193) (xy 87.487613 -50.892339) (xy 87.473728 -50.817579) (xy 87.467894 -50.741764)
			(xy 87.470175 -50.66576) (xy 87.480547 -50.590432) (xy 87.49889 -50.516639) (xy 87.524996 -50.445222)
			(xy 87.558567 -50.376996) (xy 87.578438 -50.344578) (xy 87.594948 -50.319432) (xy 87.616393 -50.289326)
			(xy 87.66458 -50.23327) (xy 87.718318 -50.182511) (xy 87.777028 -50.137596) (xy 87.840078 -50.099008)
			(xy 87.906788 -50.067164) (xy 87.976439 -50.042407) (xy 88.048282 -50.025004) (xy 88.121542 -50.015141)
			(xy 88.195429 -50.012926) (xy 88.269148 -50.018381) (xy 88.341904 -50.031449) (xy 88.412914 -50.051989)
			(xy 88.481412 -50.079778) (xy 88.54666 -50.114519) (xy 88.607956 -50.155836) (xy 88.664639 -50.203284)
			(xy 88.716097 -50.256352) (xy 88.761778 -50.314469) (xy 88.801188 -50.377008) (xy 88.833903 -50.443295)
			(xy 88.85957 -50.512616) (xy 88.869266 -50.548286) (xy 88.869266 -50.54854) (xy 88.873958 -50.564643)
			(xy 88.890519 -50.593797) (xy 88.914098 -50.617635) (xy 88.943071 -50.634513) (xy 88.975438 -50.643266)
			(xy 88.992202 -50.64379) (xy 88.992456 -50.64379) (xy 89.009114 -50.643301) (xy 89.041297 -50.634687)
			(xy 89.070153 -50.618035) (xy 89.093714 -50.59448) (xy 89.110374 -50.565629) (xy 89.118996 -50.533448)
			(xy 89.119456 -50.51679) (xy 89.119456 -50.157888) (xy 89.118978 -50.142096) (xy 89.111216 -50.111482)
			(xy 89.09617 -50.083713) (xy 89.074762 -50.060492) (xy 89.061798 -50.051462) (xy 89.030193 -50.030306)
			(xy 88.971234 -49.982258) (xy 88.917735 -49.928196) (xy 88.870308 -49.868736) (xy 88.829493 -49.804557)
			(xy 88.795757 -49.736391) (xy 88.769483 -49.665016) (xy 88.750972 -49.591245) (xy 88.740435 -49.51592)
			(xy 88.737991 -49.439902) (xy 88.74367 -49.364056) (xy 88.757406 -49.289249) (xy 88.779043 -49.216334)
			(xy 88.808333 -49.146142) (xy 88.844942 -49.079474) (xy 88.888453 -49.017092) (xy 88.93837 -48.959706)
			(xy 88.994123 -48.907972) (xy 89.055075 -48.862479) (xy 89.120532 -48.823747) (xy 89.189747 -48.792218)
			(xy 89.26193 -48.76825) (xy 89.336257 -48.752118) (xy 89.411881 -48.744006) (xy 89.487939 -48.744006)
			(xy 89.563563 -48.752118) (xy 89.63789 -48.76825) (xy 89.710073 -48.792218) (xy 89.779288 -48.823747)
			(xy 89.844745 -48.862479) (xy 89.905697 -48.907972) (xy 89.96145 -48.959706) (xy 90.011367 -49.017092)
			(xy 90.054878 -49.079474) (xy 90.091487 -49.146142) (xy 90.120777 -49.216334) (xy 90.142414 -49.289249)
			(xy 90.15615 -49.364056) (xy 90.161829 -49.439902) (xy 90.161341 -49.45507) (xy 91.277697 -49.45507)
			(xy 91.281732 -49.379366) (xy 91.293791 -49.304521) (xy 91.313737 -49.23138) (xy 91.341344 -49.160775)
			(xy 91.3763 -49.093504) (xy 91.418208 -49.030329) (xy 91.466594 -48.971967) (xy 91.52091 -48.919079)
			(xy 91.580539 -48.872264) (xy 91.644807 -48.832052) (xy 91.712984 -48.7989) (xy 91.7843 -48.773182)
			(xy 91.857945 -48.75519) (xy 91.933085 -48.745128) (xy 92.008869 -48.743109) (xy 92.084439 -48.749158)
			(xy 92.158937 -48.763205) (xy 92.23152 -48.785091) (xy 92.301366 -48.814568) (xy 92.367683 -48.851303)
			(xy 92.429719 -48.894878) (xy 92.486772 -48.9448) (xy 92.538196 -49.000504) (xy 92.583407 -49.061359)
			(xy 92.621894 -49.126674) (xy 92.65322 -49.19571) (xy 92.67703 -49.267685) (xy 92.693055 -49.341783)
			(xy 92.701114 -49.417164) (xy 92.701618 -49.45507) (xy 92.701114 -49.492976) (xy 92.693055 -49.568357)
			(xy 92.67703 -49.642455) (xy 92.65322 -49.71443) (xy 92.621894 -49.783466) (xy 92.583407 -49.848781)
			(xy 92.538196 -49.909636) (xy 92.486772 -49.96534) (xy 92.429719 -50.015262) (xy 92.367683 -50.058837)
			(xy 92.301366 -50.095572) (xy 92.23152 -50.125049) (xy 92.158937 -50.146935) (xy 92.084439 -50.160982)
			(xy 92.008869 -50.167031) (xy 91.933085 -50.165012) (xy 91.857945 -50.15495) (xy 91.7843 -50.136958)
			(xy 91.712984 -50.11124) (xy 91.644807 -50.078088) (xy 91.580539 -50.037876) (xy 91.52091 -49.991061)
			(xy 91.466594 -49.938173) (xy 91.418208 -49.879811) (xy 91.3763 -49.816636) (xy 91.341344 -49.749365)
			(xy 91.313737 -49.67876) (xy 91.293791 -49.605619) (xy 91.281732 -49.530774) (xy 91.277697 -49.45507)
			(xy 90.161341 -49.45507) (xy 90.159385 -49.51592) (xy 90.148848 -49.591245) (xy 90.130337 -49.665016)
			(xy 90.104063 -49.736391) (xy 90.070327 -49.804557) (xy 90.029512 -49.868736) (xy 89.982085 -49.928196)
			(xy 89.928586 -49.982258) (xy 89.869627 -50.030306) (xy 89.838022 -50.051462) (xy 89.825051 -50.060483)
			(xy 89.803641 -50.083703) (xy 89.7886 -50.111476) (xy 89.780853 -50.142096) (xy 89.780364 -50.157888)
			(xy 89.780364 -50.51679) (xy 89.780906 -50.533441) (xy 89.789521 -50.565609) (xy 89.806168 -50.594452)
			(xy 89.829712 -50.618004) (xy 89.858548 -50.634661) (xy 89.890713 -50.643288) (xy 89.907364 -50.64379)
			(xy 89.907618 -50.64379) (xy 89.924382 -50.643277) (xy 89.956749 -50.634531) (xy 89.985717 -50.61765)
			(xy 90.009282 -50.593799) (xy 90.025814 -50.564631) (xy 90.030554 -50.54854) (xy 90.030554 -50.548286)
			(xy 90.040312 -50.512167) (xy 90.066403 -50.442041) (xy 90.099708 -50.37504) (xy 90.139858 -50.311903)
			(xy 90.186411 -50.253327) (xy 90.238852 -50.199959) (xy 90.296604 -50.152387) (xy 90.359028 -50.111136)
			(xy 90.425435 -50.076663) (xy 90.495093 -50.049347) (xy 90.567232 -50.029491) (xy 90.641056 -50.017312)
			(xy 90.71575 -50.012946) (xy 90.790491 -50.016441) (xy 90.864452 -50.027759) (xy 90.936817 -50.046773)
			(xy 91.006788 -50.073275) (xy 91.073593 -50.106973) (xy 91.136493 -50.147493) (xy 91.194795 -50.194388)
			(xy 91.247855 -50.247142) (xy 91.295087 -50.305172) (xy 91.335971 -50.367837) (xy 91.370054 -50.434445)
			(xy 91.39696 -50.504262) (xy 91.416393 -50.576516) (xy 91.428138 -50.65041) (xy 91.432066 -50.725129)
			(xy 91.428132 -50.799848) (xy 91.416381 -50.873741) (xy 91.396942 -50.945994) (xy 91.37003 -51.015808)
			(xy 91.335941 -51.082414) (xy 91.295053 -51.145075) (xy 91.247816 -51.203101) (xy 91.194752 -51.25585)
			(xy 91.136446 -51.302741) (xy 91.073542 -51.343256) (xy 91.006735 -51.376948) (xy 90.936762 -51.403444)
			(xy 90.864395 -51.422453) (xy 90.790433 -51.433764) (xy 90.715692 -51.437253) (xy 90.640998 -51.432881)
			(xy 90.567175 -51.420697) (xy 90.495037 -51.400834) (xy 90.425382 -51.373513) (xy 90.358978 -51.339034)
			(xy 90.296557 -51.297779) (xy 90.23881 -51.250202) (xy 90.186372 -51.196829) (xy 90.139824 -51.138249)
			(xy 90.099679 -51.075109) (xy 90.06638 -51.008105) (xy 90.040295 -50.937978) (xy 90.030554 -50.901854)
			(xy 90.030554 -50.9016) (xy 90.025864 -50.885498) (xy 90.009304 -50.856347) (xy 89.985723 -50.832516)
			(xy 89.956749 -50.815649) (xy 89.924381 -50.806912) (xy 89.907618 -50.80635) (xy 89.907364 -50.80635)
			(xy 89.890715 -50.806849) (xy 89.858553 -50.815477) (xy 89.829721 -50.832136) (xy 89.806183 -50.855689)
			(xy 89.789544 -50.884533) (xy 89.780938 -50.9167) (xy 89.780364 -50.93335) (xy 89.780364 -50.952908)
			(xy 89.774776 -50.95875) (xy 89.753948 -50.979578) (xy 89.738215 -50.995999) (xy 89.712265 -51.033339)
			(xy 89.693371 -51.074699) (xy 89.682135 -51.118761) (xy 89.678914 -51.164118) (xy 89.683813 -51.209325)
			(xy 89.696674 -51.25294) (xy 89.717088 -51.293572) (xy 89.744404 -51.329925) (xy 89.777749 -51.360839)
			(xy 89.79662 -51.373532) (xy 89.829373 -51.392372) (xy 89.891093 -51.435967) (xy 89.947846 -51.485855)
			(xy 89.998995 -51.541475) (xy 90.043964 -51.602202) (xy 90.082245 -51.66735) (xy 90.11341 -51.736188)
			(xy 90.137106 -51.807939) (xy 90.153067 -51.881798) (xy 90.161113 -51.956932) (xy 90.161134 -51.99507)
			(xy 91.277697 -51.99507) (xy 91.281732 -51.919366) (xy 91.293791 -51.844521) (xy 91.313737 -51.77138)
			(xy 91.341344 -51.700775) (xy 91.3763 -51.633504) (xy 91.418208 -51.570329) (xy 91.466594 -51.511967)
			(xy 91.52091 -51.459079) (xy 91.580539 -51.412264) (xy 91.644807 -51.372052) (xy 91.712984 -51.3389)
			(xy 91.7843 -51.313182) (xy 91.857945 -51.29519) (xy 91.933085 -51.285128) (xy 92.008869 -51.283109)
			(xy 92.084439 -51.289158) (xy 92.158937 -51.303205) (xy 92.23152 -51.325091) (xy 92.301366 -51.354568)
			(xy 92.367683 -51.391303) (xy 92.429719 -51.434878) (xy 92.486772 -51.4848) (xy 92.538196 -51.540504)
			(xy 92.583407 -51.601359) (xy 92.621894 -51.666674) (xy 92.65322 -51.73571) (xy 92.67703 -51.807685)
			(xy 92.693055 -51.881783) (xy 92.701114 -51.957164) (xy 92.701618 -51.99507) (xy 92.701114 -52.032976)
			(xy 92.693055 -52.108357) (xy 92.67703 -52.182455) (xy 92.65322 -52.25443) (xy 92.621894 -52.323466)
			(xy 92.583407 -52.388781) (xy 92.538196 -52.449636) (xy 92.486772 -52.50534) (xy 92.429719 -52.555262)
			(xy 92.367683 -52.598837) (xy 92.301366 -52.635572) (xy 92.23152 -52.665049) (xy 92.158937 -52.686935)
			(xy 92.084439 -52.700982) (xy 92.008869 -52.707031) (xy 91.933085 -52.705012) (xy 91.857945 -52.69495)
			(xy 91.7843 -52.676958) (xy 91.712984 -52.65124) (xy 91.644807 -52.618088) (xy 91.580539 -52.577876)
			(xy 91.52091 -52.531061) (xy 91.466594 -52.478173) (xy 91.418208 -52.419811) (xy 91.3763 -52.356636)
			(xy 91.341344 -52.289365) (xy 91.313737 -52.21876) (xy 91.293791 -52.145619) (xy 91.281732 -52.070774)
			(xy 91.277697 -51.99507) (xy 90.161134 -51.99507) (xy 90.161154 -52.032495) (xy 90.153189 -52.107637)
			(xy 90.137309 -52.181513) (xy 90.113691 -52.253291) (xy 90.082601 -52.322162) (xy 90.04439 -52.387352)
			(xy 89.999488 -52.448127) (xy 89.9484 -52.503803) (xy 89.8917 -52.553753) (xy 89.861136 -52.575968)
			(xy 89.83726 -52.592986) (xy 89.780364 -52.697126) (xy 89.780364 -53.05679) (xy 89.780906 -53.073441)
			(xy 89.789521 -53.105609) (xy 89.806168 -53.134452) (xy 89.829712 -53.158004) (xy 89.858548 -53.174661)
			(xy 89.890713 -53.183288) (xy 89.907364 -53.18379) (xy 89.907618 -53.18379) (xy 89.924382 -53.183277)
			(xy 89.956749 -53.174531) (xy 89.985717 -53.15765) (xy 90.009282 -53.133799) (xy 90.025814 -53.104631)
			(xy 90.030554 -53.08854) (xy 90.030554 -53.088286) (xy 90.039237 -53.056052) (xy 90.061822 -52.993228)
			(xy 90.090184 -52.932791) (xy 90.124074 -52.875271) (xy 90.14333 -52.848002) (xy 90.166489 -52.816829)
			(xy 90.218552 -52.759205) (xy 90.276583 -52.707595) (xy 90.339891 -52.662614) (xy 90.407722 -52.624798)
			(xy 90.443304 -52.609242) (xy 90.477771 -52.595231) (xy 90.548973 -52.573627) (xy 90.622039 -52.559569)
			(xy 90.696173 -52.55321) (xy 90.770567 -52.554619) (xy 90.844407 -52.563781) (xy 90.916888 -52.580596)
			(xy 90.987221 -52.60488) (xy 91.054636 -52.636369) (xy 91.118398 -52.674719) (xy 91.165302 -52.71008)
			(xy 93.154506 -52.71008) (xy 93.158522 -52.59381) (xy 93.170549 -52.478095) (xy 93.190531 -52.363485)
			(xy 93.218373 -52.250526) (xy 93.253942 -52.139758) (xy 93.297068 -52.031707) (xy 93.347545 -51.926889)
			(xy 93.405134 -51.825804) (xy 93.46956 -51.728932) (xy 93.540515 -51.636736) (xy 93.617662 -51.549655)
			(xy 93.700633 -51.468104) (xy 93.789033 -51.392472) (xy 93.88244 -51.323118) (xy 93.980409 -51.260375)
			(xy 94.082473 -51.204539) (xy 94.188147 -51.155878) (xy 94.296926 -51.114624) (xy 94.408291 -51.080973)
			(xy 94.521714 -51.055085) (xy 94.636651 -51.037084) (xy 94.752557 -51.027055) (xy 94.868879 -51.025047)
			(xy 94.985062 -51.031069) (xy 95.100553 -51.045092) (xy 95.214801 -51.06705) (xy 95.327262 -51.096837)
			(xy 95.4374 -51.134312) (xy 95.54469 -51.179297) (xy 95.648621 -51.231576) (xy 95.748697 -51.290901)
			(xy 95.844443 -51.356989) (xy 95.9354 -51.429525) (xy 96.021136 -51.508164) (xy 96.101243 -51.59253)
			(xy 96.175339 -51.682222) (xy 96.243069 -51.776812) (xy 96.304113 -51.87585) (xy 96.358178 -51.978863)
			(xy 96.405008 -52.08536) (xy 96.444379 -52.194835) (xy 96.476103 -52.306765) (xy 96.500029 -52.420617)
			(xy 96.516043 -52.535849) (xy 96.52407 -52.651911) (xy 96.524572 -52.71008) (xy 96.52407 -52.768249)
			(xy 96.516043 -52.884311) (xy 96.500029 -52.999543) (xy 96.476103 -53.113395) (xy 96.444379 -53.225325)
			(xy 96.405008 -53.3348) (xy 96.358178 -53.441297) (xy 96.304113 -53.54431) (xy 96.243069 -53.643348)
			(xy 96.175339 -53.737938) (xy 96.101243 -53.82763) (xy 96.021136 -53.911996) (xy 95.9354 -53.990635)
			(xy 95.844443 -54.063171) (xy 95.748697 -54.129259) (xy 95.648621 -54.188584) (xy 95.54469 -54.240863)
			(xy 95.4374 -54.285848) (xy 95.327262 -54.323323) (xy 95.214801 -54.35311) (xy 95.100553 -54.375068)
			(xy 94.985062 -54.389091) (xy 94.868879 -54.395113) (xy 94.752557 -54.393105) (xy 94.636651 -54.383076)
			(xy 94.521714 -54.365075) (xy 94.408291 -54.339187) (xy 94.296926 -54.305536) (xy 94.188147 -54.264282)
			(xy 94.082473 -54.215621) (xy 93.980409 -54.159785) (xy 93.88244 -54.097042) (xy 93.789033 -54.027688)
			(xy 93.700633 -53.952056) (xy 93.617662 -53.870505) (xy 93.540515 -53.783424) (xy 93.46956 -53.691228)
			(xy 93.405134 -53.594356) (xy 93.347545 -53.493271) (xy 93.297068 -53.388453) (xy 93.253942 -53.280402)
			(xy 93.218373 -53.169634) (xy 93.190531 -53.056675) (xy 93.170549 -52.942065) (xy 93.158522 -52.82635)
			(xy 93.154506 -52.71008) (xy 91.165302 -52.71008) (xy 91.177812 -52.719511) (xy 91.232229 -52.770256)
			(xy 91.281055 -52.826402) (xy 91.323758 -52.887335) (xy 91.359871 -52.95239) (xy 91.389001 -53.020857)
			(xy 91.400376 -53.056282) (xy 91.411019 -53.092611) (xy 91.425457 -53.166928) (xy 91.431924 -53.242357)
			(xy 91.430349 -53.318047) (xy 91.420748 -53.393141) (xy 91.40323 -53.466792) (xy 91.377992 -53.538168)
			(xy 91.345322 -53.606461) (xy 91.305586 -53.670901) (xy 91.259235 -53.730759) (xy 91.206791 -53.785358)
			(xy 91.148849 -53.834082) (xy 91.086061 -53.87638) (xy 91.019139 -53.911775) (xy 90.948837 -53.939866)
			(xy 90.875951 -53.960335) (xy 90.801304 -53.972953) (xy 90.72574 -53.977575) (xy 90.650111 -53.97415)
			(xy 90.575274 -53.962716) (xy 90.502073 -53.943404) (xy 90.431335 -53.91643) (xy 90.36386 -53.882099)
			(xy 90.300411 -53.840801) (xy 90.241704 -53.793) (xy 90.214704 -53.766466) (xy 90.198477 -53.750773)
			(xy 90.161555 -53.72481) (xy 90.120629 -53.705772) (xy 90.076985 -53.694259) (xy 90.031994 -53.690631)
			(xy 89.987069 -53.695003) (xy 89.943621 -53.707236) (xy 89.903016 -53.726948) (xy 89.866528 -53.753518)
			(xy 89.835304 -53.786113) (xy 89.810324 -53.823707) (xy 89.792373 -53.865121) (xy 89.782015 -53.909054)
			(xy 89.780364 -53.931566) (xy 89.780364 -54.259734) (xy 86.033864 -58.006234) (xy 86.033864 -64.46012)
			(xy 86.39887 -64.46012) (xy 86.402874 -64.260022) (xy 86.414881 -64.060244) (xy 86.434872 -63.861107)
			(xy 86.462814 -63.662929) (xy 86.498662 -63.466027) (xy 86.54236 -63.270718) (xy 86.593837 -63.077313)
			(xy 86.653011 -62.886123) (xy 86.719787 -62.697453) (xy 86.794059 -62.511606) (xy 86.875706 -62.328879)
			(xy 86.964599 -62.149566) (xy 87.060595 -61.973952) (xy 87.16354 -61.80232) (xy 87.27327 -61.634944)
			(xy 87.389608 -61.472093) (xy 87.512369 -61.314026) (xy 87.641356 -61.160998) (xy 87.776363 -61.013253)
			(xy 87.917172 -60.871027) (xy 88.063559 -60.73455) (xy 88.215289 -60.604038) (xy 88.37212 -60.479702)
			(xy 88.533799 -60.36174) (xy 88.700069 -60.250341) (xy 88.870662 -60.145684) (xy 89.045306 -60.047936)
			(xy 89.223722 -59.957253) (xy 89.405622 -59.873782) (xy 89.590717 -59.797655) (xy 89.778709 -59.728995)
			(xy 89.969298 -59.667911) (xy 90.162178 -59.614501) (xy 90.35704 -59.568852) (xy 90.553573 -59.531035)
			(xy 90.751462 -59.501111) (xy 90.950389 -59.479129) (xy 91.150037 -59.465124) (xy 91.350085 -59.459118)
			(xy 91.550213 -59.46112) (xy 91.750101 -59.471128) (xy 91.949428 -59.489125) (xy 92.147876 -59.515083)
			(xy 92.345126 -59.54896) (xy 92.540863 -59.590702) (xy 92.734773 -59.640241) (xy 92.926546 -59.697499)
			(xy 93.115875 -59.762384) (xy 93.302455 -59.834792) (xy 93.48599 -59.914608) (xy 93.666184 -60.001702)
			(xy 93.842749 -60.095936) (xy 94.015402 -60.197159) (xy 94.183867 -60.305209) (xy 94.347875 -60.419912)
			(xy 94.507162 -60.541086) (xy 94.661473 -60.668535) (xy 94.810561 -60.802056) (xy 94.954188 -60.941436)
			(xy 95.092124 -61.08645) (xy 95.224147 -61.236867) (xy 95.350046 -61.392445) (xy 95.46962 -61.552937)
			(xy 95.582676 -61.718083) (xy 95.689035 -61.887621) (xy 95.788526 -62.061279) (xy 95.880989 -62.238778)
			(xy 95.966276 -62.419834) (xy 96.044251 -62.604158) (xy 96.114788 -62.791454) (xy 96.177776 -62.981422)
			(xy 96.233113 -63.173758) (xy 96.28071 -63.368154) (xy 96.320491 -63.564299) (xy 96.352393 -63.761878)
			(xy 96.376364 -63.960575) (xy 96.392366 -64.160073) (xy 96.400373 -64.360051) (xy 96.400874 -64.46012)
			(xy 96.400373 -64.560189) (xy 96.392366 -64.760167) (xy 96.376364 -64.959665) (xy 96.352393 -65.158362)
			(xy 96.320491 -65.355941) (xy 96.28071 -65.552086) (xy 96.233113 -65.746482) (xy 96.177776 -65.938818)
			(xy 96.114788 -66.128786) (xy 96.044251 -66.316082) (xy 95.966276 -66.500406) (xy 95.880989 -66.681462)
			(xy 95.788526 -66.858961) (xy 95.689035 -67.032619) (xy 95.582676 -67.202157) (xy 95.46962 -67.367303)
			(xy 95.350046 -67.527795) (xy 95.224147 -67.683373) (xy 95.092124 -67.83379) (xy 94.954188 -67.978804)
			(xy 94.810561 -68.118184) (xy 94.661473 -68.251705) (xy 94.507162 -68.379154) (xy 94.347875 -68.500328)
			(xy 94.183867 -68.615031) (xy 94.015402 -68.723081) (xy 93.842749 -68.824304) (xy 93.666184 -68.918538)
			(xy 93.48599 -69.005632) (xy 93.302455 -69.085448) (xy 93.115875 -69.157856) (xy 92.926546 -69.222741)
			(xy 92.734773 -69.279999) (xy 92.540863 -69.329538) (xy 92.345126 -69.37128) (xy 92.147876 -69.405157)
			(xy 91.949428 -69.431115) (xy 91.750101 -69.449112) (xy 91.550213 -69.45912) (xy 91.350085 -69.461122)
			(xy 91.150037 -69.455116) (xy 90.950389 -69.441111) (xy 90.751462 -69.419129) (xy 90.553573 -69.389205)
			(xy 90.35704 -69.351388) (xy 90.162178 -69.305739) (xy 89.969298 -69.252329) (xy 89.778709 -69.191245)
			(xy 89.590717 -69.122585) (xy 89.405622 -69.046458) (xy 89.223722 -68.962987) (xy 89.045306 -68.872304)
			(xy 88.870662 -68.774556) (xy 88.700069 -68.669899) (xy 88.533799 -68.5585) (xy 88.37212 -68.440538)
			(xy 88.215289 -68.316202) (xy 88.063559 -68.18569) (xy 87.917172 -68.049213) (xy 87.776363 -67.906987)
			(xy 87.641356 -67.759242) (xy 87.512369 -67.606214) (xy 87.389608 -67.448147) (xy 87.27327 -67.285296)
			(xy 87.16354 -67.11792) (xy 87.060595 -66.946288) (xy 86.964599 -66.770674) (xy 86.875706 -66.591361)
			(xy 86.794059 -66.408634) (xy 86.719787 -66.222787) (xy 86.653011 -66.034117) (xy 86.593837 -65.842927)
			(xy 86.54236 -65.649522) (xy 86.498662 -65.454213) (xy 86.462814 -65.257311) (xy 86.434872 -65.059133)
			(xy 86.414881 -64.859996) (xy 86.402874 -64.660218) (xy 86.39887 -64.46012) (xy 86.033864 -64.46012)
			(xy 86.033864 -67.971162) (xy 86.034401 -67.98778) (xy 86.042989 -68.019888) (xy 86.05959 -68.048681)
			(xy 86.070948 -68.060824) (xy 91.784424 -73.774046) (xy 91.784424 -75.353672) (xy 91.876118 -75.44562)
			(xy 92.013278 -75.58278) (xy 92.057474 -75.58786) (xy 92.087787 -75.59183) (xy 92.147065 -75.606784)
			(xy 92.203825 -75.629496) (xy 92.257056 -75.659562) (xy 92.305811 -75.696447) (xy 92.349221 -75.739495)
			(xy 92.386514 -75.787938) (xy 92.417026 -75.840915) (xy 92.440214 -75.897483) (xy 92.455664 -75.956633)
			(xy 92.463103 -76.017314) (xy 92.462397 -76.078446) (xy 92.453559 -76.138939) (xy 92.436746 -76.197717)
			(xy 92.412258 -76.253734) (xy 92.380531 -76.305992) (xy 92.342129 -76.353561) (xy 92.297736 -76.395594)
			(xy 92.248142 -76.431344) (xy 92.194231 -76.460172) (xy 92.136962 -76.481567) (xy 92.107258 -76.488798)
			(xy 92.06357 -76.498704) (xy 92.008452 -76.5683) (xy 92.008452 -76.780644) (xy 92.301314 -77.073506)
			(xy 92.850208 -77.073506) (xy 92.866856 -77.072962) (xy 92.899017 -77.064343) (xy 92.927852 -77.047694)
			(xy 92.951395 -77.02415) (xy 92.968044 -76.995315) (xy 92.976662 -76.963154) (xy 92.977208 -76.946506)
			(xy 92.977208 -76.928472) (xy 93.19768 -76.708) (xy 93.209177 -76.69573) (xy 93.225869 -76.666552)
			(xy 93.234379 -76.634033) (xy 93.234121 -76.600419) (xy 93.225111 -76.568034) (xy 93.216984 -76.553314)
			(xy 93.202234 -76.527646) (xy 93.178746 -76.473306) (xy 93.162461 -76.41639) (xy 93.153652 -76.357849)
			(xy 93.152467 -76.298661) (xy 93.158924 -76.239814) (xy 93.172916 -76.182292) (xy 93.19421 -76.127054)
			(xy 93.22245 -76.075024) (xy 93.257163 -76.02707) (xy 93.297771 -75.983993) (xy 93.343596 -75.946513)
			(xy 93.393871 -75.915255) (xy 93.447757 -75.890742) (xy 93.504355 -75.873383) (xy 93.533468 -75.868022)
			(xy 93.5736 -75.861164) (xy 93.681296 -75.753468) (xy 93.681296 -72.971406) (xy 96.909128 -69.743574)
			(xy 96.909128 -36.035996) (xy 84.053172 -23.18004) (xy 84.053172 -16.730472) (xy 84.05264 -16.713851)
			(xy 84.044061 -16.681737) (xy 84.027467 -16.652934) (xy 84.016088 -16.64081) (xy 82.139536 -14.764512)
			(xy 82.139536 -11.650472) (xy 83.775042 -10.01522) (xy 88.2523 -10.01522) (xy 88.389968 -9.877552)
			(xy 88.397969 -9.856945) (xy 88.40753 -9.813792) (xy 88.409484 -9.769635) (xy 88.403772 -9.725805)
			(xy 88.390566 -9.683624) (xy 88.370264 -9.644362) (xy 88.343478 -9.609203) (xy 88.311016 -9.579206)
			(xy 88.273855 -9.555275) (xy 88.233115 -9.538131) (xy 88.190024 -9.528291) (xy 88.167972 -9.526778)
			(xy 88.128928 -9.525581) (xy 88.051437 -9.515703) (xy 87.975495 -9.497396) (xy 87.902014 -9.470881)
			(xy 87.83188 -9.436477) (xy 87.765937 -9.394599) (xy 87.704977 -9.345749) (xy 87.67699 -9.318498)
			(xy 87.6522 -9.293103) (xy 87.607234 -9.238193) (xy 87.567954 -9.179083) (xy 87.534747 -9.116358)
			(xy 87.507944 -9.050642) (xy 87.487811 -8.982586) (xy 87.474547 -8.912864) (xy 87.470996 -8.877554)
			(xy 87.468082 -8.838838) (xy 87.469685 -8.76121) (xy 87.479731 -8.684217) (xy 87.498101 -8.608777)
			(xy 87.524575 -8.535785) (xy 87.55884 -8.46611) (xy 87.600488 -8.40058) (xy 87.649023 -8.339975)
			(xy 87.703869 -8.285015) (xy 87.764373 -8.236353) (xy 87.829816 -8.194569) (xy 87.899419 -8.160158)
			(xy 87.972355 -8.133532) (xy 88.047757 -8.115005) (xy 88.086184 -8.109458) (xy 88.101242 -8.107006)
			(xy 88.129655 -8.09592) (xy 88.154616 -8.078395) (xy 88.174694 -8.055436) (xy 88.188736 -8.028362)
			(xy 88.195936 -7.998725) (xy 88.19642 -7.983474) (xy 88.19642 -7.106666) (xy 88.195969 -7.091417)
			(xy 88.188728 -7.06179) (xy 88.174669 -7.034725) (xy 88.154591 -7.011767) (xy 88.129643 -6.994225)
			(xy 88.101245 -6.9831) (xy 88.086184 -6.980682) (xy 88.047644 -6.975013) (xy 87.972011 -6.956346)
			(xy 87.898869 -6.929532) (xy 87.829091 -6.894894) (xy 87.763512 -6.852844) (xy 87.73287 -6.82879)
			(xy 87.703308 -6.804268) (xy 87.649084 -6.749867) (xy 87.601034 -6.689941) (xy 87.559719 -6.625189)
			(xy 87.525618 -6.556363) (xy 87.499129 -6.484265) (xy 87.48056 -6.409734) (xy 87.470126 -6.333635)
			(xy 87.46795 -6.256856) (xy 87.474057 -6.180289) (xy 87.488374 -6.104825) (xy 87.510737 -6.031342)
			(xy 87.540885 -5.960695) (xy 87.578466 -5.893707) (xy 87.623044 -5.831156) (xy 87.674101 -5.773771)
			(xy 87.731041 -5.722219) (xy 87.761826 -5.699252) (xy 87.793559 -5.676829) (xy 87.861018 -5.638262)
			(xy 87.932276 -5.607272) (xy 88.006486 -5.584228) (xy 88.044528 -5.576316) (xy 88.076378 -5.570524)
			(xy 88.140791 -5.564032) (xy 88.205528 -5.563402) (xy 88.237822 -5.565648) (xy 88.275324 -5.569202)
			(xy 88.349341 -5.583226) (xy 88.421464 -5.604987) (xy 88.490885 -5.634243) (xy 88.556829 -5.670665)
			(xy 88.618559 -5.713847) (xy 88.675383 -5.763307) (xy 88.726667 -5.81849) (xy 88.749632 -5.84835)
			(xy 88.775304 -5.883754) (xy 88.818738 -5.95966) (xy 88.836246 -5.999734) (xy 88.85301 -6.04393)
			(xy 88.85857 -6.058709) (xy 88.875812 -6.08515) (xy 88.89902 -6.106546) (xy 88.926773 -6.121587)
			(xy 88.957369 -6.129351) (xy 88.973152 -6.129782) (xy 89.025984 -6.129782) (xy 89.100152 -6.055614)
			(xy 89.100152 -5.69468) (xy 89.04605 -5.59181) (xy 89.02319 -5.574538) (xy 88.99321 -5.551447) (xy 88.937808 -5.499897)
			(xy 88.888188 -5.442759) (xy 88.844913 -5.380678) (xy 88.80847 -5.314354) (xy 88.77927 -5.244539)
			(xy 88.757645 -5.172018) (xy 88.743837 -5.097612) (xy 88.738004 -5.022162) (xy 88.74021 -4.946518)
			(xy 88.750431 -4.871535) (xy 88.768551 -4.798061) (xy 88.794366 -4.726924) (xy 88.827585 -4.658928)
			(xy 88.867831 -4.594842) (xy 88.914652 -4.535388) (xy 88.967516 -4.481239) (xy 89.025829 -4.433005)
			(xy 89.088931 -4.391232) (xy 89.15611 -4.356391) (xy 89.226607 -4.328876) (xy 89.299625 -4.308997)
			(xy 89.374341 -4.29698) (xy 89.44991 -4.292959) (xy 89.525479 -4.29698) (xy 89.600195 -4.308997)
			(xy 89.673213 -4.328876) (xy 89.74371 -4.356391) (xy 89.810889 -4.391232) (xy 89.873991 -4.433005)
			(xy 89.932304 -4.481239) (xy 89.985168 -4.535388) (xy 90.031989 -4.594842) (xy 90.072235 -4.658928)
			(xy 90.105454 -4.726924) (xy 90.131269 -4.798061) (xy 90.149389 -4.871535) (xy 90.15961 -4.946518)
			(xy 90.161318 -5.00507) (xy 91.277697 -5.00507) (xy 91.281732 -4.929366) (xy 91.293791 -4.854521)
			(xy 91.313737 -4.78138) (xy 91.341344 -4.710775) (xy 91.3763 -4.643504) (xy 91.418208 -4.580329)
			(xy 91.466594 -4.521967) (xy 91.52091 -4.469079) (xy 91.580539 -4.422264) (xy 91.644807 -4.382052)
			(xy 91.712984 -4.3489) (xy 91.7843 -4.323182) (xy 91.857945 -4.30519) (xy 91.933085 -4.295128) (xy 92.008869 -4.293109)
			(xy 92.084439 -4.299158) (xy 92.158937 -4.313205) (xy 92.23152 -4.335091) (xy 92.301366 -4.364568)
			(xy 92.367683 -4.401303) (xy 92.429719 -4.444878) (xy 92.486772 -4.4948) (xy 92.538196 -4.550504)
			(xy 92.583407 -4.611359) (xy 92.621894 -4.676674) (xy 92.65322 -4.74571) (xy 92.67703 -4.817685)
			(xy 92.693055 -4.891783) (xy 92.701114 -4.967164) (xy 92.701618 -5.00507) (xy 92.701114 -5.042976)
			(xy 92.693055 -5.118357) (xy 92.67703 -5.192455) (xy 92.65322 -5.26443) (xy 92.621894 -5.333466)
			(xy 92.583407 -5.398781) (xy 92.538196 -5.459636) (xy 92.486772 -5.51534) (xy 92.429719 -5.565262)
			(xy 92.367683 -5.608837) (xy 92.301366 -5.645572) (xy 92.23152 -5.675049) (xy 92.158937 -5.696935)
			(xy 92.084439 -5.710982) (xy 92.008869 -5.717031) (xy 91.933085 -5.715012) (xy 91.857945 -5.70495)
			(xy 91.7843 -5.686958) (xy 91.712984 -5.66124) (xy 91.644807 -5.628088) (xy 91.580539 -5.587876)
			(xy 91.52091 -5.541061) (xy 91.466594 -5.488173) (xy 91.418208 -5.429811) (xy 91.3763 -5.366636)
			(xy 91.341344 -5.299365) (xy 91.313737 -5.22876) (xy 91.293791 -5.155619) (xy 91.281732 -5.080774)
			(xy 91.277697 -5.00507) (xy 90.161318 -5.00507) (xy 90.161816 -5.022162) (xy 90.155983 -5.097612)
			(xy 90.142175 -5.172018) (xy 90.12055 -5.244539) (xy 90.09135 -5.314354) (xy 90.054907 -5.380678)
			(xy 90.011632 -5.442759) (xy 89.962012 -5.499897) (xy 89.90661 -5.551447) (xy 89.87663 -5.574538)
			(xy 89.85377 -5.59181) (xy 89.799668 -5.69468) (xy 89.799668 -6.002782) (xy 89.800209 -6.019433)
			(xy 89.808823 -6.051603) (xy 89.825469 -6.080447) (xy 89.849013 -6.104) (xy 89.877851 -6.120658)
			(xy 89.910017 -6.129284) (xy 89.926668 -6.129782) (xy 89.967562 -6.129782) (xy 90.033602 -6.082792)
			(xy 90.04681 -6.04393) (xy 90.059578 -6.008311) (xy 90.091621 -5.939759) (xy 90.130756 -5.874994)
			(xy 90.176542 -5.814747) (xy 90.228461 -5.759697) (xy 90.285928 -5.710467) (xy 90.348293 -5.667612)
			(xy 90.414854 -5.631615) (xy 90.484858 -5.602883) (xy 90.557515 -5.581741) (xy 90.632005 -5.568426)
			(xy 90.707487 -5.56309) (xy 90.78311 -5.565792) (xy 90.858019 -5.576502) (xy 90.931368 -5.5951) (xy 91.002331 -5.621374)
			(xy 91.070105 -5.65503) (xy 91.133927 -5.695686) (xy 91.193074 -5.742883) (xy 91.246881 -5.79609)
			(xy 91.294738 -5.854705) (xy 91.336107 -5.918066) (xy 91.370519 -5.98546) (xy 91.397588 -6.056123)
			(xy 91.417006 -6.12926) (xy 91.428555 -6.204044) (xy 91.432105 -6.279632) (xy 91.427615 -6.355169)
			(xy 91.415136 -6.429804) (xy 91.394809 -6.502693) (xy 91.366863 -6.573015) (xy 91.331615 -6.639974)
			(xy 91.289461 -6.702816) (xy 91.240878 -6.760831) (xy 91.186413 -6.813364) (xy 91.126683 -6.859822)
			(xy 91.062361 -6.89968) (xy 90.994173 -6.93249) (xy 90.922889 -6.957879) (xy 90.849313 -6.975562)
			(xy 90.811858 -6.980936) (xy 90.772936 -6.985466) (xy 90.694588 -6.986994) (xy 90.616546 -6.979904)
			(xy 90.539756 -6.964282) (xy 90.465147 -6.940319) (xy 90.393623 -6.908302) (xy 90.32605 -6.868622)
			(xy 90.263245 -6.821757) (xy 90.20597 -6.768275) (xy 90.154917 -6.708824) (xy 90.110706 -6.644124)
			(xy 90.073871 -6.574958) (xy 90.044858 -6.502164) (xy 90.033856 -6.464554) (xy 90.024966 -6.432296)
			(xy 90.001344 -6.408674) (xy 89.989212 -6.397213) (xy 89.960333 -6.380504) (xy 89.92811 -6.371853)
			(xy 89.894746 -6.371853) (xy 89.862523 -6.380504) (xy 89.833644 -6.397213) (xy 89.821512 -6.408674)
			(xy 89.762584 -6.467602) (xy 89.762584 -6.485128) (xy 89.657936 -6.589776) (xy 89.649394 -6.611808)
			(xy 89.639727 -6.658056) (xy 89.638772 -6.705294) (xy 89.646562 -6.751895) (xy 89.662828 -6.796255)
			(xy 89.687011 -6.836845) (xy 89.718277 -6.872268) (xy 89.755551 -6.901303) (xy 89.7763 -6.91261)
			(xy 89.814908 -6.933946) (xy 89.848738 -6.954785) (xy 89.911997 -7.002868) (xy 89.969506 -7.057698)
			(xy 90.020548 -7.118594) (xy 90.064489 -7.184797) (xy 90.100781 -7.255483) (xy 90.128973 -7.329773)
			(xy 90.148713 -7.40674) (xy 90.15476 -7.44601) (xy 90.16007 -7.488291) (xy 90.161198 -7.54507) (xy 91.277697 -7.54507)
			(xy 91.281732 -7.469366) (xy 91.293791 -7.394521) (xy 91.313737 -7.32138) (xy 91.341344 -7.250775)
			(xy 91.3763 -7.183504) (xy 91.418208 -7.120329) (xy 91.466594 -7.061967) (xy 91.52091 -7.009079)
			(xy 91.580539 -6.962264) (xy 91.644807 -6.922052) (xy 91.712984 -6.8889) (xy 91.7843 -6.863182) (xy 91.857945 -6.84519)
			(xy 91.933085 -6.835128) (xy 92.008869 -6.833109) (xy 92.084439 -6.839158) (xy 92.158937 -6.853205)
			(xy 92.23152 -6.875091) (xy 92.301366 -6.904568) (xy 92.367683 -6.941303) (xy 92.429719 -6.984878)
			(xy 92.486772 -7.0348) (xy 92.538196 -7.090504) (xy 92.583407 -7.151359) (xy 92.621894 -7.216674)
			(xy 92.65322 -7.28571) (xy 92.67703 -7.357685) (xy 92.693055 -7.431783) (xy 92.701114 -7.507164)
			(xy 92.701618 -7.54507) (xy 92.701114 -7.582976) (xy 92.693055 -7.658357) (xy 92.67703 -7.732455)
			(xy 92.65322 -7.80443) (xy 92.621894 -7.873466) (xy 92.583407 -7.938781) (xy 92.538196 -7.999636)
			(xy 92.486772 -8.05534) (xy 92.429719 -8.105262) (xy 92.367683 -8.148837) (xy 92.301366 -8.185572)
			(xy 92.23152 -8.215049) (xy 92.158937 -8.236935) (xy 92.084439 -8.250982) (xy 92.008869 -8.257031)
			(xy 91.933085 -8.255012) (xy 91.857945 -8.24495) (xy 91.7843 -8.226958) (xy 91.712984 -8.20124) (xy 91.644807 -8.168088)
			(xy 91.580539 -8.127876) (xy 91.52091 -8.081061) (xy 91.466594 -8.028173) (xy 91.418208 -7.969811)
			(xy 91.3763 -7.906636) (xy 91.341344 -7.839365) (xy 91.313737 -7.76876) (xy 91.293791 -7.695619)
			(xy 91.281732 -7.620774) (xy 91.277697 -7.54507) (xy 90.161198 -7.54507) (xy 90.161762 -7.573493)
			(xy 90.153261 -7.658286) (xy 90.1446 -7.70001) (xy 90.135491 -7.738322) (xy 90.109928 -7.812811)
			(xy 90.076301 -7.884024) (xy 90.035022 -7.951092) (xy 89.986594 -8.013196) (xy 89.93161 -8.069576)
			(xy 89.87074 -8.119546) (xy 89.838022 -8.141462) (xy 89.825051 -8.150483) (xy 89.803641 -8.173703)
			(xy 89.7886 -8.201476) (xy 89.780853 -8.232096) (xy 89.780364 -8.247888) (xy 89.780364 -8.60679)
			(xy 89.780906 -8.623441) (xy 89.789521 -8.655609) (xy 89.806168 -8.684452) (xy 89.829712 -8.708004)
			(xy 89.858548 -8.724661) (xy 89.890713 -8.733288) (xy 89.907364 -8.73379) (xy 89.907618 -8.73379)
			(xy 89.924382 -8.733277) (xy 89.956749 -8.724531) (xy 89.985717 -8.70765) (xy 90.009282 -8.683799)
			(xy 90.025814 -8.654631) (xy 90.030554 -8.63854) (xy 90.030554 -8.638286) (xy 90.039237 -8.606052)
			(xy 90.061822 -8.543228) (xy 90.090184 -8.482791) (xy 90.124074 -8.425271) (xy 90.14333 -8.398002)
			(xy 90.166489 -8.366829) (xy 90.218552 -8.309205) (xy 90.276583 -8.257595) (xy 90.339891 -8.212614)
			(xy 90.407722 -8.174798) (xy 90.443304 -8.159242) (xy 90.477771 -8.145231) (xy 90.548973 -8.123627)
			(xy 90.622039 -8.109569) (xy 90.696173 -8.10321) (xy 90.770567 -8.104619) (xy 90.844407 -8.113781)
			(xy 90.916888 -8.130596) (xy 90.987221 -8.15488) (xy 91.054636 -8.186369) (xy 91.118398 -8.224719)
			(xy 91.165302 -8.26008) (xy 93.154506 -8.26008) (xy 93.158522 -8.14381) (xy 93.170549 -8.028095)
			(xy 93.190531 -7.913485) (xy 93.218373 -7.800526) (xy 93.253942 -7.689758) (xy 93.297068 -7.581707)
			(xy 93.347545 -7.476889) (xy 93.405134 -7.375804) (xy 93.46956 -7.278932) (xy 93.540515 -7.186736)
			(xy 93.617662 -7.099655) (xy 93.700633 -7.018104) (xy 93.789033 -6.942472) (xy 93.88244 -6.873118)
			(xy 93.980409 -6.810375) (xy 94.082473 -6.754539) (xy 94.188147 -6.705878) (xy 94.296926 -6.664624)
			(xy 94.408291 -6.630973) (xy 94.521714 -6.605085) (xy 94.636651 -6.587084) (xy 94.752557 -6.577055)
			(xy 94.868879 -6.575047) (xy 94.985062 -6.581069) (xy 95.100553 -6.595092) (xy 95.214801 -6.61705)
			(xy 95.327262 -6.646837) (xy 95.4374 -6.684312) (xy 95.54469 -6.729297) (xy 95.648621 -6.781576)
			(xy 95.748697 -6.840901) (xy 95.844443 -6.906989) (xy 95.9354 -6.979525) (xy 96.021136 -7.058164)
			(xy 96.101243 -7.14253) (xy 96.175339 -7.232222) (xy 96.243069 -7.326812) (xy 96.304113 -7.42585)
			(xy 96.358178 -7.528863) (xy 96.405008 -7.63536) (xy 96.444379 -7.744835) (xy 96.476103 -7.856765)
			(xy 96.500029 -7.970617) (xy 96.516043 -8.085849) (xy 96.52407 -8.201911) (xy 96.524572 -8.26008)
			(xy 96.52407 -8.318249) (xy 96.516043 -8.434311) (xy 96.500029 -8.549543) (xy 96.476103 -8.663395)
			(xy 96.444379 -8.775325) (xy 96.405008 -8.8848) (xy 96.358178 -8.991297) (xy 96.304113 -9.09431)
			(xy 96.243069 -9.193348) (xy 96.175339 -9.287938) (xy 96.101243 -9.37763) (xy 96.021136 -9.461996)
			(xy 95.9354 -9.540635) (xy 95.844443 -9.613171) (xy 95.748697 -9.679259) (xy 95.648621 -9.738584)
			(xy 95.54469 -9.790863) (xy 95.4374 -9.835848) (xy 95.327262 -9.873323) (xy 95.214801 -9.90311) (xy 95.100553 -9.925068)
			(xy 94.985062 -9.939091) (xy 94.868879 -9.945113) (xy 94.752557 -9.943105) (xy 94.636651 -9.933076)
			(xy 94.521714 -9.915075) (xy 94.408291 -9.889187) (xy 94.296926 -9.855536) (xy 94.188147 -9.814282)
			(xy 94.082473 -9.765621) (xy 93.980409 -9.709785) (xy 93.88244 -9.647042) (xy 93.789033 -9.577688)
			(xy 93.700633 -9.502056) (xy 93.617662 -9.420505) (xy 93.540515 -9.333424) (xy 93.46956 -9.241228)
			(xy 93.405134 -9.144356) (xy 93.347545 -9.043271) (xy 93.297068 -8.938453) (xy 93.253942 -8.830402)
			(xy 93.218373 -8.719634) (xy 93.190531 -8.606675) (xy 93.170549 -8.492065) (xy 93.158522 -8.37635)
			(xy 93.154506 -8.26008) (xy 91.165302 -8.26008) (xy 91.177812 -8.269511) (xy 91.232229 -8.320256)
			(xy 91.281055 -8.376402) (xy 91.323758 -8.437335) (xy 91.359871 -8.50239) (xy 91.389001 -8.570857)
			(xy 91.400376 -8.606282) (xy 91.411019 -8.642611) (xy 91.425457 -8.716928) (xy 91.431924 -8.792357)
			(xy 91.430349 -8.868047) (xy 91.420748 -8.943141) (xy 91.40323 -9.016792) (xy 91.377992 -9.088168)
			(xy 91.345322 -9.156461) (xy 91.305586 -9.220901) (xy 91.259235 -9.280759) (xy 91.206791 -9.335358)
			(xy 91.148849 -9.384082) (xy 91.086061 -9.42638) (xy 91.019139 -9.461775) (xy 90.948837 -9.489866)
			(xy 90.875951 -9.510335) (xy 90.801304 -9.522953) (xy 90.72574 -9.527575) (xy 90.650111 -9.52415)
			(xy 90.575274 -9.512716) (xy 90.502073 -9.493404) (xy 90.431335 -9.46643) (xy 90.36386 -9.432099)
			(xy 90.300411 -9.390801) (xy 90.241704 -9.343) (xy 90.214704 -9.316466) (xy 90.198477 -9.300773)
			(xy 90.161555 -9.27481) (xy 90.120629 -9.255772) (xy 90.076985 -9.244259) (xy 90.031994 -9.240631)
			(xy 89.987069 -9.245003) (xy 89.943621 -9.257236) (xy 89.903016 -9.276948) (xy 89.866528 -9.303518)
			(xy 89.835304 -9.336113) (xy 89.810324 -9.373707) (xy 89.792373 -9.415121) (xy 89.782015 -9.459054)
			(xy 89.780364 -9.481566) (xy 89.780364 -9.95553) (xy 89.228676 -10.507472) (xy 88.682576 -11.053572)
			(xy 84.205318 -11.053572) (xy 83.208876 -12.050014) (xy 83.200225 -12.060464) (xy 83.187116 -12.084208)
			(xy 83.179309 -12.110183) (xy 83.177888 -12.123674) (xy 83.177888 -13.087854) (xy 83.719144 -13.087854)
			(xy 83.719144 -13.027918) (xy 83.726967 -12.968496) (xy 83.74248 -12.910603) (xy 83.765416 -12.85523)
			(xy 83.795383 -12.803324) (xy 83.83187 -12.755774) (xy 83.87425 -12.713394) (xy 83.9218 -12.676907)
			(xy 83.973706 -12.64694) (xy 84.029079 -12.624004) (xy 84.086972 -12.608491) (xy 84.146394 -12.600668)
			(xy 84.20633 -12.600668) (xy 84.265752 -12.608491) (xy 84.323645 -12.624004) (xy 84.379018 -12.64694)
			(xy 84.430924 -12.676907) (xy 84.478474 -12.713394) (xy 84.520854 -12.755774) (xy 84.557341 -12.803324)
			(xy 84.587308 -12.85523) (xy 84.610244 -12.910603) (xy 84.625757 -12.968496) (xy 84.63358 -13.027918)
			(xy 84.63407 -13.057886) (xy 84.63358 -13.087854) (xy 84.627895 -13.131034) (xy 85.997524 -13.131034)
			(xy 85.997524 -13.071098) (xy 86.005347 -13.011676) (xy 86.02086 -12.953783) (xy 86.043796 -12.89841)
			(xy 86.073763 -12.846504) (xy 86.11025 -12.798954) (xy 86.15263 -12.756574) (xy 86.20018 -12.720087)
			(xy 86.252086 -12.69012) (xy 86.307459 -12.667184) (xy 86.365352 -12.651671) (xy 86.424774 -12.643848)
			(xy 86.48471 -12.643848) (xy 86.544132 -12.651671) (xy 86.602025 -12.667184) (xy 86.657398 -12.69012)
			(xy 86.709304 -12.720087) (xy 86.756854 -12.756574) (xy 86.799234 -12.798954) (xy 86.835721 -12.846504)
			(xy 86.865688 -12.89841) (xy 86.886713 -12.94917) (xy 88.008188 -12.94917) (xy 88.008188 -12.889234)
			(xy 88.016011 -12.829812) (xy 88.031524 -12.771919) (xy 88.05446 -12.716546) (xy 88.084427 -12.66464)
			(xy 88.120914 -12.61709) (xy 88.163294 -12.57471) (xy 88.210844 -12.538223) (xy 88.26275 -12.508256)
			(xy 88.318123 -12.48532) (xy 88.376016 -12.469807) (xy 88.435438 -12.461984) (xy 88.495374 -12.461984)
			(xy 88.554796 -12.469807) (xy 88.612689 -12.48532) (xy 88.668062 -12.508256) (xy 88.719968 -12.538223)
			(xy 88.767518 -12.57471) (xy 88.809898 -12.61709) (xy 88.846385 -12.66464) (xy 88.876352 -12.716546)
			(xy 88.899288 -12.771919) (xy 88.914801 -12.829812) (xy 88.922624 -12.889234) (xy 88.923114 -12.919202)
			(xy 88.922624 -12.94917) (xy 88.914801 -13.008592) (xy 88.899288 -13.066485) (xy 88.876352 -13.121858)
			(xy 88.846385 -13.173764) (xy 88.809898 -13.221314) (xy 88.767518 -13.263694) (xy 88.738483 -13.285974)
			(xy 90.965256 -13.285974) (xy 90.965256 -13.226038) (xy 90.973079 -13.166616) (xy 90.988592 -13.108723)
			(xy 91.011528 -13.05335) (xy 91.041495 -13.001444) (xy 91.077982 -12.953894) (xy 91.120362 -12.911514)
			(xy 91.167912 -12.875027) (xy 91.219818 -12.84506) (xy 91.275191 -12.822124) (xy 91.333084 -12.806611)
			(xy 91.392506 -12.798788) (xy 91.452442 -12.798788) (xy 91.511864 -12.806611) (xy 91.569757 -12.822124)
			(xy 91.62513 -12.84506) (xy 91.677036 -12.875027) (xy 91.724586 -12.911514) (xy 91.766966 -12.953894)
			(xy 91.803453 -13.001444) (xy 91.83342 -13.05335) (xy 91.856356 -13.108723) (xy 91.871869 -13.166616)
			(xy 91.879692 -13.226038) (xy 91.880182 -13.256006) (xy 91.879821 -13.2781) (xy 95.87406 -13.2781)
			(xy 95.87406 -13.218164) (xy 95.881883 -13.158742) (xy 95.897396 -13.100849) (xy 95.920332 -13.045476)
			(xy 95.950299 -12.99357) (xy 95.986786 -12.94602) (xy 96.029166 -12.90364) (xy 96.076716 -12.867153)
			(xy 96.128622 -12.837186) (xy 96.183995 -12.81425) (xy 96.241888 -12.798737) (xy 96.30131 -12.790914)
			(xy 96.361246 -12.790914) (xy 96.420668 -12.798737) (xy 96.478561 -12.81425) (xy 96.533934 -12.837186)
			(xy 96.58584 -12.867153) (xy 96.63339 -12.90364) (xy 96.67577 -12.94602) (xy 96.712257 -12.99357)
			(xy 96.742224 -13.045476) (xy 96.76516 -13.100849) (xy 96.780673 -13.158742) (xy 96.788496 -13.218164)
			(xy 96.788986 -13.248132) (xy 96.788496 -13.2781) (xy 96.780673 -13.337522) (xy 96.76516 -13.395415)
			(xy 96.742224 -13.450788) (xy 96.712257 -13.502694) (xy 96.67577 -13.550244) (xy 96.63339 -13.592624)
			(xy 96.58584 -13.629111) (xy 96.533934 -13.659078) (xy 96.478561 -13.682014) (xy 96.420668 -13.697527)
			(xy 96.361246 -13.70535) (xy 96.30131 -13.70535) (xy 96.241888 -13.697527) (xy 96.183995 -13.682014)
			(xy 96.128622 -13.659078) (xy 96.076716 -13.629111) (xy 96.029166 -13.592624) (xy 95.986786 -13.550244)
			(xy 95.950299 -13.502694) (xy 95.920332 -13.450788) (xy 95.897396 -13.395415) (xy 95.881883 -13.337522)
			(xy 95.87406 -13.2781) (xy 91.879821 -13.2781) (xy 91.879692 -13.285974) (xy 91.871869 -13.345396)
			(xy 91.856356 -13.403289) (xy 91.83342 -13.458662) (xy 91.803453 -13.510568) (xy 91.766966 -13.558118)
			(xy 91.724586 -13.600498) (xy 91.677036 -13.636985) (xy 91.62513 -13.666952) (xy 91.569757 -13.689888)
			(xy 91.511864 -13.705401) (xy 91.452442 -13.713224) (xy 91.392506 -13.713224) (xy 91.333084 -13.705401)
			(xy 91.275191 -13.689888) (xy 91.219818 -13.666952) (xy 91.167912 -13.636985) (xy 91.120362 -13.600498)
			(xy 91.077982 -13.558118) (xy 91.041495 -13.510568) (xy 91.011528 -13.458662) (xy 90.988592 -13.403289)
			(xy 90.973079 -13.345396) (xy 90.965256 -13.285974) (xy 88.738483 -13.285974) (xy 88.719968 -13.300181)
			(xy 88.668062 -13.330148) (xy 88.612689 -13.353084) (xy 88.554796 -13.368597) (xy 88.495374 -13.37642)
			(xy 88.435438 -13.37642) (xy 88.376016 -13.368597) (xy 88.318123 -13.353084) (xy 88.26275 -13.330148)
			(xy 88.210844 -13.300181) (xy 88.163294 -13.263694) (xy 88.120914 -13.221314) (xy 88.084427 -13.173764)
			(xy 88.05446 -13.121858) (xy 88.031524 -13.066485) (xy 88.016011 -13.008592) (xy 88.008188 -12.94917)
			(xy 86.886713 -12.94917) (xy 86.888624 -12.953783) (xy 86.904137 -13.011676) (xy 86.91196 -13.071098)
			(xy 86.91245 -13.101066) (xy 86.91196 -13.131034) (xy 86.904137 -13.190456) (xy 86.888624 -13.248349)
			(xy 86.865688 -13.303722) (xy 86.835721 -13.355628) (xy 86.799234 -13.403178) (xy 86.756854 -13.445558)
			(xy 86.709304 -13.482045) (xy 86.657398 -13.512012) (xy 86.602025 -13.534948) (xy 86.544132 -13.550461)
			(xy 86.48471 -13.558284) (xy 86.424774 -13.558284) (xy 86.365352 -13.550461) (xy 86.307459 -13.534948)
			(xy 86.252086 -13.512012) (xy 86.20018 -13.482045) (xy 86.15263 -13.445558) (xy 86.11025 -13.403178)
			(xy 86.073763 -13.355628) (xy 86.043796 -13.303722) (xy 86.02086 -13.248349) (xy 86.005347 -13.190456)
			(xy 85.997524 -13.131034) (xy 84.627895 -13.131034) (xy 84.625757 -13.147276) (xy 84.610244 -13.205169)
			(xy 84.587308 -13.260542) (xy 84.557341 -13.312448) (xy 84.520854 -13.359998) (xy 84.478474 -13.402378)
			(xy 84.430924 -13.438865) (xy 84.379018 -13.468832) (xy 84.323645 -13.491768) (xy 84.265752 -13.507281)
			(xy 84.20633 -13.515104) (xy 84.146394 -13.515104) (xy 84.086972 -13.507281) (xy 84.029079 -13.491768)
			(xy 83.973706 -13.468832) (xy 83.9218 -13.438865) (xy 83.87425 -13.402378) (xy 83.83187 -13.359998)
			(xy 83.795383 -13.312448) (xy 83.765416 -13.260542) (xy 83.74248 -13.205169) (xy 83.726967 -13.147276)
			(xy 83.719144 -13.087854) (xy 83.177888 -13.087854) (xy 83.177888 -14.259302) (xy 84.350588 -14.259302)
			(xy 84.350588 -14.199366) (xy 84.358411 -14.139944) (xy 84.373924 -14.082051) (xy 84.39686 -14.026678)
			(xy 84.426827 -13.974772) (xy 84.463314 -13.927222) (xy 84.505694 -13.884842) (xy 84.553244 -13.848355)
			(xy 84.60515 -13.818388) (xy 84.660523 -13.795452) (xy 84.718416 -13.779939) (xy 84.777838 -13.772116)
			(xy 84.837774 -13.772116) (xy 84.897196 -13.779939) (xy 84.955089 -13.795452) (xy 85.010462 -13.818388)
			(xy 85.062368 -13.848355) (xy 85.109918 -13.884842) (xy 85.152298 -13.927222) (xy 85.188785 -13.974772)
			(xy 85.218752 -14.026678) (xy 85.241688 -14.082051) (xy 85.257201 -14.139944) (xy 85.265024 -14.199366)
			(xy 85.265514 -14.229334) (xy 85.265024 -14.259302) (xy 85.259373 -14.302228) (xy 87.195388 -14.302228)
			(xy 87.195388 -14.242292) (xy 87.203211 -14.18287) (xy 87.218724 -14.124977) (xy 87.24166 -14.069604)
			(xy 87.271627 -14.017698) (xy 87.308114 -13.970148) (xy 87.350494 -13.927768) (xy 87.398044 -13.891281)
			(xy 87.44995 -13.861314) (xy 87.505323 -13.838378) (xy 87.563216 -13.822865) (xy 87.622638 -13.815042)
			(xy 87.682574 -13.815042) (xy 87.741996 -13.822865) (xy 87.799889 -13.838378) (xy 87.855262 -13.861314)
			(xy 87.907168 -13.891281) (xy 87.954718 -13.927768) (xy 87.997098 -13.970148) (xy 88.033585 -14.017698)
			(xy 88.063552 -14.069604) (xy 88.086488 -14.124977) (xy 88.102001 -14.18287) (xy 88.109824 -14.242292)
			(xy 88.110314 -14.27226) (xy 88.11009 -14.285972) (xy 94.082598 -14.285972) (xy 94.082598 -14.226036)
			(xy 94.090421 -14.166614) (xy 94.105934 -14.108721) (xy 94.12887 -14.053348) (xy 94.158837 -14.001442)
			(xy 94.195324 -13.953892) (xy 94.237704 -13.911512) (xy 94.285254 -13.875025) (xy 94.33716 -13.845058)
			(xy 94.392533 -13.822122) (xy 94.450426 -13.806609) (xy 94.509848 -13.798786) (xy 94.569784 -13.798786)
			(xy 94.629206 -13.806609) (xy 94.687099 -13.822122) (xy 94.742472 -13.845058) (xy 94.794378 -13.875025)
			(xy 94.841928 -13.911512) (xy 94.884308 -13.953892) (xy 94.920795 -14.001442) (xy 94.950762 -14.053348)
			(xy 94.973698 -14.108721) (xy 94.989211 -14.166614) (xy 94.997034 -14.226036) (xy 94.997524 -14.256004)
			(xy 94.997034 -14.285972) (xy 94.989211 -14.345394) (xy 94.973698 -14.403287) (xy 94.950762 -14.45866)
			(xy 94.920795 -14.510566) (xy 94.884308 -14.558116) (xy 94.841928 -14.600496) (xy 94.794378 -14.636983)
			(xy 94.742472 -14.66695) (xy 94.687099 -14.689886) (xy 94.629206 -14.705399) (xy 94.569784 -14.713222)
			(xy 94.509848 -14.713222) (xy 94.450426 -14.705399) (xy 94.392533 -14.689886) (xy 94.33716 -14.66695)
			(xy 94.285254 -14.636983) (xy 94.237704 -14.600496) (xy 94.195324 -14.558116) (xy 94.158837 -14.510566)
			(xy 94.12887 -14.45866) (xy 94.105934 -14.403287) (xy 94.090421 -14.345394) (xy 94.082598 -14.285972)
			(xy 88.11009 -14.285972) (xy 88.109824 -14.302228) (xy 88.102001 -14.36165) (xy 88.086488 -14.419543)
			(xy 88.063552 -14.474916) (xy 88.033585 -14.526822) (xy 87.997098 -14.574372) (xy 87.954718 -14.616752)
			(xy 87.907168 -14.653239) (xy 87.855262 -14.683206) (xy 87.799889 -14.706142) (xy 87.741996 -14.721655)
			(xy 87.682574 -14.729478) (xy 87.622638 -14.729478) (xy 87.563216 -14.721655) (xy 87.505323 -14.706142)
			(xy 87.44995 -14.683206) (xy 87.398044 -14.653239) (xy 87.350494 -14.616752) (xy 87.308114 -14.574372)
			(xy 87.271627 -14.526822) (xy 87.24166 -14.474916) (xy 87.218724 -14.419543) (xy 87.203211 -14.36165)
			(xy 87.195388 -14.302228) (xy 85.259373 -14.302228) (xy 85.257201 -14.318724) (xy 85.241688 -14.376617)
			(xy 85.218752 -14.43199) (xy 85.188785 -14.483896) (xy 85.152298 -14.531446) (xy 85.109918 -14.573826)
			(xy 85.062368 -14.610313) (xy 85.010462 -14.64028) (xy 84.955089 -14.663216) (xy 84.897196 -14.678729)
			(xy 84.837774 -14.686552) (xy 84.777838 -14.686552) (xy 84.718416 -14.678729) (xy 84.660523 -14.663216)
			(xy 84.60515 -14.64028) (xy 84.553244 -14.610313) (xy 84.505694 -14.573826) (xy 84.463314 -14.531446)
			(xy 84.426827 -14.483896) (xy 84.39686 -14.43199) (xy 84.373924 -14.376617) (xy 84.358411 -14.318724)
			(xy 84.350588 -14.259302) (xy 83.177888 -14.259302) (xy 83.177888 -14.334236) (xy 84.158074 -15.314422)
			(xy 84.338922 -15.495016) (xy 84.50986 -15.665954) (xy 85.45244 -15.665954) (xy 85.45244 -15.606018)
			(xy 85.460263 -15.546596) (xy 85.475776 -15.488703) (xy 85.498712 -15.43333) (xy 85.528679 -15.381424)
			(xy 85.565166 -15.333874) (xy 85.607546 -15.291494) (xy 85.655096 -15.255007) (xy 85.707002 -15.22504)
			(xy 85.762375 -15.202104) (xy 85.820268 -15.186591) (xy 85.87969 -15.178768) (xy 85.939626 -15.178768)
			(xy 85.999048 -15.186591) (xy 86.056941 -15.202104) (xy 86.112314 -15.22504) (xy 86.16422 -15.255007)
			(xy 86.21177 -15.291494) (xy 86.25415 -15.333874) (xy 86.290637 -15.381424) (xy 86.320604 -15.43333)
			(xy 86.34354 -15.488703) (xy 86.359053 -15.546596) (xy 86.366876 -15.606018) (xy 86.367366 -15.635986)
			(xy 86.366876 -15.665954) (xy 86.359053 -15.725376) (xy 86.34354 -15.783269) (xy 86.320604 -15.838642)
			(xy 86.290637 -15.890548) (xy 86.25415 -15.938098) (xy 86.21177 -15.980478) (xy 86.16422 -16.016965)
			(xy 86.112314 -16.046932) (xy 86.056941 -16.069868) (xy 85.999048 -16.085381) (xy 85.939626 -16.093204)
			(xy 85.87969 -16.093204) (xy 85.820268 -16.085381) (xy 85.762375 -16.069868) (xy 85.707002 -16.046932)
			(xy 85.655096 -16.016965) (xy 85.607546 -15.980478) (xy 85.565166 -15.938098) (xy 85.528679 -15.890548)
			(xy 85.498712 -15.838642) (xy 85.475776 -15.783269) (xy 85.460263 -15.725376) (xy 85.45244 -15.665954)
			(xy 84.50986 -15.665954) (xy 85.091524 -16.247618) (xy 85.091524 -20.01012) (xy 86.39887 -20.01012)
			(xy 86.402874 -19.810022) (xy 86.414881 -19.610244) (xy 86.434872 -19.411107) (xy 86.462814 -19.212929)
			(xy 86.498662 -19.016027) (xy 86.54236 -18.820718) (xy 86.593837 -18.627313) (xy 86.653011 -18.436123)
			(xy 86.719787 -18.247453) (xy 86.794059 -18.061606) (xy 86.875706 -17.878879) (xy 86.964599 -17.699566)
			(xy 87.060595 -17.523952) (xy 87.16354 -17.35232) (xy 87.27327 -17.184944) (xy 87.389608 -17.022093)
			(xy 87.512369 -16.864026) (xy 87.641356 -16.710998) (xy 87.776363 -16.563253) (xy 87.917172 -16.421027)
			(xy 88.063559 -16.28455) (xy 88.215289 -16.154038) (xy 88.37212 -16.029702) (xy 88.533799 -15.91174)
			(xy 88.700069 -15.800341) (xy 88.870662 -15.695684) (xy 89.045306 -15.597936) (xy 89.223722 -15.507253)
			(xy 89.405622 -15.423782) (xy 89.590717 -15.347655) (xy 89.778709 -15.278995) (xy 89.969298 -15.217911)
			(xy 90.162178 -15.164501) (xy 90.35704 -15.118852) (xy 90.553573 -15.081035) (xy 90.751462 -15.051111)
			(xy 90.950389 -15.029129) (xy 91.150037 -15.015124) (xy 91.350085 -15.009118) (xy 91.550213 -15.01112)
			(xy 91.750101 -15.021128) (xy 91.949428 -15.039125) (xy 92.147876 -15.065083) (xy 92.345126 -15.09896)
			(xy 92.540863 -15.140702) (xy 92.734773 -15.190241) (xy 92.926546 -15.247499) (xy 93.115875 -15.312384)
			(xy 93.302455 -15.384792) (xy 93.48599 -15.464608) (xy 93.666184 -15.551702) (xy 93.842749 -15.645936)
			(xy 94.015402 -15.747159) (xy 94.183867 -15.855209) (xy 94.347875 -15.969912) (xy 94.507162 -16.091086)
			(xy 94.661473 -16.218535) (xy 94.810561 -16.352056) (xy 94.954188 -16.491436) (xy 95.092124 -16.63645)
			(xy 95.224147 -16.786867) (xy 95.288997 -16.867005) (xy 97.325422 -16.867005) (xy 97.325422 -16.753451)
			(xy 97.333343 -16.640175) (xy 97.349146 -16.527727) (xy 97.372755 -16.416656) (xy 97.404055 -16.307501)
			(xy 97.442892 -16.200796) (xy 97.489078 -16.097061) (xy 97.542388 -15.996799) (xy 97.602562 -15.900501)
			(xy 97.669307 -15.808635) (xy 97.742297 -15.721648) (xy 97.821178 -15.639965) (xy 97.905564 -15.563983)
			(xy 97.995045 -15.494073) (xy 98.089185 -15.430575) (xy 98.187525 -15.373798) (xy 98.289585 -15.32402)
			(xy 98.39487 -15.281482) (xy 98.502865 -15.246392) (xy 98.613045 -15.218921) (xy 98.724873 -15.199203)
			(xy 98.837804 -15.187333) (xy 98.951288 -15.183371) (xy 99.064772 -15.187333) (xy 99.177703 -15.199203)
			(xy 99.289531 -15.218921) (xy 99.399711 -15.246392) (xy 99.507706 -15.281482) (xy 99.612991 -15.32402)
			(xy 99.715051 -15.373798) (xy 99.813391 -15.430575) (xy 99.907531 -15.494073) (xy 99.997012 -15.563983)
			(xy 100.081398 -15.639965) (xy 100.160279 -15.721648) (xy 100.233269 -15.808635) (xy 100.300014 -15.900501)
			(xy 100.360188 -15.996799) (xy 100.413498 -16.097061) (xy 100.459684 -16.200796) (xy 100.498521 -16.307501)
			(xy 100.529821 -16.416656) (xy 100.55343 -16.527727) (xy 100.569233 -16.640175) (xy 100.577154 -16.753451)
			(xy 100.57765 -16.810228) (xy 100.577154 -16.867005) (xy 100.569233 -16.980281) (xy 100.55343 -17.092729)
			(xy 100.529821 -17.2038) (xy 100.498521 -17.312955) (xy 100.459684 -17.41966) (xy 100.413498 -17.523395)
			(xy 100.360188 -17.623657) (xy 100.300014 -17.719955) (xy 100.233269 -17.811821) (xy 100.160279 -17.898808)
			(xy 100.081398 -17.980491) (xy 99.997012 -18.056473) (xy 99.907531 -18.126383) (xy 99.813391 -18.189881)
			(xy 99.715051 -18.246658) (xy 99.612991 -18.296436) (xy 99.507706 -18.338974) (xy 99.399711 -18.374064)
			(xy 99.289531 -18.401535) (xy 99.177703 -18.421253) (xy 99.064772 -18.433123) (xy 98.951288 -18.437086)
			(xy 98.837804 -18.433123) (xy 98.724873 -18.421253) (xy 98.613045 -18.401535) (xy 98.502865 -18.374064)
			(xy 98.39487 -18.338974) (xy 98.289585 -18.296436) (xy 98.187525 -18.246658) (xy 98.089185 -18.189881)
			(xy 97.995045 -18.126383) (xy 97.905564 -18.056473) (xy 97.821178 -17.980491) (xy 97.742297 -17.898808)
			(xy 97.669307 -17.811821) (xy 97.602562 -17.719955) (xy 97.542388 -17.623657) (xy 97.489078 -17.523395)
			(xy 97.442892 -17.41966) (xy 97.404055 -17.312955) (xy 97.372755 -17.2038) (xy 97.349146 -17.092729)
			(xy 97.333343 -16.980281) (xy 97.325422 -16.867005) (xy 95.288997 -16.867005) (xy 95.350046 -16.942445)
			(xy 95.46962 -17.102937) (xy 95.582676 -17.268083) (xy 95.689035 -17.437621) (xy 95.788526 -17.611279)
			(xy 95.880989 -17.788778) (xy 95.966276 -17.969834) (xy 96.044251 -18.154158) (xy 96.114788 -18.341454)
			(xy 96.177776 -18.531422) (xy 96.233113 -18.723758) (xy 96.28071 -18.918154) (xy 96.320491 -19.114299)
			(xy 96.352393 -19.311878) (xy 96.376364 -19.510575) (xy 96.379455 -19.549106) (xy 97.973878 -19.549106)
			(xy 97.973878 -19.48917) (xy 97.981701 -19.429748) (xy 97.997214 -19.371855) (xy 98.02015 -19.316482)
			(xy 98.050117 -19.264576) (xy 98.086604 -19.217026) (xy 98.128984 -19.174646) (xy 98.176534 -19.138159)
			(xy 98.22844 -19.108192) (xy 98.283813 -19.085256) (xy 98.341706 -19.069743) (xy 98.401128 -19.06192)
			(xy 98.461064 -19.06192) (xy 98.520486 -19.069743) (xy 98.578379 -19.085256) (xy 98.633752 -19.108192)
			(xy 98.685658 -19.138159) (xy 98.733208 -19.174646) (xy 98.775588 -19.217026) (xy 98.812075 -19.264576)
			(xy 98.842042 -19.316482) (xy 98.864978 -19.371855) (xy 98.880491 -19.429748) (xy 98.888314 -19.48917)
			(xy 98.888804 -19.519138) (xy 98.888314 -19.549106) (xy 98.880491 -19.608528) (xy 98.864978 -19.666421)
			(xy 98.842042 -19.721794) (xy 98.812075 -19.7737) (xy 98.775588 -19.82125) (xy 98.733208 -19.86363)
			(xy 98.685658 -19.900117) (xy 98.633752 -19.930084) (xy 98.578379 -19.95302) (xy 98.520486 -19.968533)
			(xy 98.461064 -19.976356) (xy 98.401128 -19.976356) (xy 98.341706 -19.968533) (xy 98.283813 -19.95302)
			(xy 98.22844 -19.930084) (xy 98.176534 -19.900117) (xy 98.128984 -19.86363) (xy 98.086604 -19.82125)
			(xy 98.050117 -19.7737) (xy 98.02015 -19.721794) (xy 97.997214 -19.666421) (xy 97.981701 -19.608528)
			(xy 97.973878 -19.549106) (xy 96.379455 -19.549106) (xy 96.392366 -19.710073) (xy 96.400373 -19.910051)
			(xy 96.400874 -20.01012) (xy 96.400373 -20.110189) (xy 96.392366 -20.310167) (xy 96.376364 -20.509665)
			(xy 96.352393 -20.708362) (xy 96.320491 -20.905941) (xy 96.28071 -21.102086) (xy 96.233113 -21.296482)
			(xy 96.177776 -21.488818) (xy 96.114788 -21.678786) (xy 96.044251 -21.866082) (xy 95.966276 -22.050406)
			(xy 95.880989 -22.231462) (xy 95.788526 -22.408961) (xy 95.689035 -22.582619) (xy 95.582676 -22.752157)
			(xy 95.46962 -22.917303) (xy 95.350046 -23.077795) (xy 95.224147 -23.233373) (xy 95.092124 -23.38379)
			(xy 94.954188 -23.528804) (xy 94.810561 -23.668184) (xy 94.661473 -23.801705) (xy 94.507162 -23.929154)
			(xy 94.347875 -24.050328) (xy 94.183867 -24.165031) (xy 94.015402 -24.273081) (xy 93.842749 -24.374304)
			(xy 93.666184 -24.468538) (xy 93.48599 -24.555632) (xy 93.302455 -24.635448) (xy 93.115875 -24.707856)
			(xy 92.926546 -24.772741) (xy 92.734773 -24.829999) (xy 92.540863 -24.879538) (xy 92.345126 -24.92128)
			(xy 92.147876 -24.955157) (xy 91.949428 -24.981115) (xy 91.750101 -24.999112) (xy 91.550213 -25.00912)
			(xy 91.350085 -25.011122) (xy 91.150037 -25.005116) (xy 90.950389 -24.991111) (xy 90.751462 -24.969129)
			(xy 90.553573 -24.939205) (xy 90.35704 -24.901388) (xy 90.162178 -24.855739) (xy 89.969298 -24.802329)
			(xy 89.778709 -24.741245) (xy 89.590717 -24.672585) (xy 89.405622 -24.596458) (xy 89.223722 -24.512987)
			(xy 89.045306 -24.422304) (xy 88.870662 -24.324556) (xy 88.700069 -24.219899) (xy 88.533799 -24.1085)
			(xy 88.37212 -23.990538) (xy 88.215289 -23.866202) (xy 88.063559 -23.73569) (xy 87.917172 -23.599213)
			(xy 87.776363 -23.456987) (xy 87.641356 -23.309242) (xy 87.512369 -23.156214) (xy 87.389608 -22.998147)
			(xy 87.27327 -22.835296) (xy 87.16354 -22.66792) (xy 87.060595 -22.496288) (xy 86.964599 -22.320674)
			(xy 86.875706 -22.141361) (xy 86.794059 -21.958634) (xy 86.719787 -21.772787) (xy 86.653011 -21.584117)
			(xy 86.593837 -21.392927) (xy 86.54236 -21.199522) (xy 86.498662 -21.004213) (xy 86.462814 -20.807311)
			(xy 86.434872 -20.609133) (xy 86.414881 -20.409996) (xy 86.402874 -20.210218) (xy 86.39887 -20.01012)
			(xy 85.091524 -20.01012) (xy 85.091524 -22.749764) (xy 97.94748 -35.60572) (xy 97.94748 -70.17385)
			(xy 94.719648 -73.401682) (xy 94.719648 -75.399138) (xy 95.311976 -75.991466) (xy 95.311976 -76.01331)
			(xy 95.339662 -76.048108) (xy 95.343472 -76.052934) (xy 95.362867 -76.079032) (xy 95.394861 -76.135637)
			(xy 95.407226 -76.16571) (xy 95.418303 -76.195295) (xy 95.433139 -76.256699) (xy 95.439384 -76.319562)
			(xy 95.43692 -76.382685) (xy 95.431864 -76.413868) (xy 95.425989 -76.443806) (xy 95.407346 -76.501898)
			(xy 95.381148 -76.556997) (xy 95.34786 -76.608126) (xy 95.308072 -76.654377) (xy 95.26249 -76.69493)
			(xy 95.211923 -76.729065) (xy 95.157268 -76.756177) (xy 95.099494 -76.775785) (xy 95.06966 -76.782168)
			(xy 94.997016 -76.796392) (xy 94.967044 -76.826364) (xy 94.967044 -77.02677) (xy 94.97626 -77.037458)
			(xy 94.998471 -77.054859) (xy 95.023962 -77.066955) (xy 95.051488 -77.073155) (xy 95.065596 -77.073506)
			(xy 95.563182 -77.073506) (xy 95.563182 -77.821536) (xy 95.570294 -77.841856) (xy 95.574717 -77.85511)
			(xy 95.581583 -77.882198) (xy 95.58401 -77.895958) (xy 95.586296 -77.91196) (xy 95.587566 -77.92593)
			(xy 95.588328 -77.950314) (xy 95.588328 -79.317088) (xy 95.529908 -79.375762) (xy 95.429324 -79.476346)
			(xy 95.417859 -79.488479) (xy 95.401142 -79.51736) (xy 95.392484 -79.549588) (xy 95.392477 -79.582959)
			(xy 95.401122 -79.61519) (xy 95.417827 -79.644078) (xy 95.429324 -79.656178) (xy 95.573596 -79.80045)
			(xy 95.573596 -82.40268) (xy 95.574088 -82.419337) (xy 95.582706 -82.451516) (xy 95.599359 -82.480368)
			(xy 95.622913 -82.503926) (xy 95.651762 -82.520585) (xy 95.683939 -82.529209) (xy 95.700596 -82.52968)
			(xy 96.477074 -82.52968) (xy 97.132648 -83.185254) (xy 97.132648 -83.316064) (xy 97.133138 -83.33272)
			(xy 97.141754 -83.364897) (xy 97.158408 -83.393746) (xy 97.181963 -83.417299) (xy 97.210814 -83.43395)
			(xy 97.242992 -83.442563) (xy 97.259648 -83.443064) (xy 97.575624 -83.443064) (xy 97.599754 -83.43265)
			(xy 97.635771 -83.417695) (xy 97.710845 -83.39658) (xy 97.788092 -83.385868) (xy 97.827084 -83.385152)
			(xy 98.600514 -83.385152) (xy 98.991166 -83.775804) (xy 99.002686 -83.786655) (xy 99.029874 -83.802831)
			(xy 99.060214 -83.811796) (xy 99.076002 -83.812888) (xy 99.115511 -83.814848) (xy 99.193916 -83.825389)
			(xy 99.270953 -83.843383) (xy 99.345915 -83.868665) (xy 99.418113 -83.901003) (xy 99.486887 -83.940101)
			(xy 99.551604 -83.9856) (xy 99.611671 -84.037082) (xy 99.666537 -84.094074) (xy 99.715698 -84.156055)
			(xy 99.758703 -84.222456) (xy 99.795158 -84.292666) (xy 99.824728 -84.366042) (xy 99.847141 -84.441911)
			(xy 99.862193 -84.519576) (xy 99.869745 -84.598325) (xy 99.87026 -84.63788) (xy 99.87026 -86.472014)
			(xy 99.031552 -87.310722) (xy 99.031552 -167.296846) (xy 96.7867 -169.541698) (xy 96.759112 -169.568667)
			(xy 96.699715 -169.617908) (xy 96.635981 -169.66139) (xy 96.568467 -169.698734) (xy 96.497762 -169.729613)
			(xy 96.424483 -169.753758) (xy 96.349271 -169.770958) (xy 96.272781 -169.781063) (xy 96.23425 -169.782998)
			(xy 96.18472 -169.784776) (xy 96.074738 -169.894758) (xy 96.063347 -169.906889) (xy 96.046675 -169.935674)
			(xy 96.038007 -169.967789) (xy 96.0374 -169.98442) (xy 96.0374 -170.91787) (xy 96.036881 -170.952298)
			(xy 96.028601 -171.020654) (xy 96.012169 -171.087521) (xy 95.987823 -171.151929) (xy 95.955915 -171.212946)
			(xy 95.916909 -171.269688) (xy 95.871368 -171.321333) (xy 95.819953 -171.367133) (xy 95.763408 -171.406424)
			(xy 95.702553 -171.438638) (xy 95.638268 -171.463308) (xy 95.571485 -171.480077) (xy 95.503171 -171.488701)
			(xy 95.434316 -171.489056) (xy 95.365917 -171.481136) (xy 95.298965 -171.465057) (xy 95.26651 -171.453556)
			(xy 95.25635 -171.45) (xy 95.23222 -171.445428) (xy 95.216929 -171.442982) (xy 95.18602 -171.444722)
			(xy 95.156438 -171.45385) (xy 95.129922 -171.469829) (xy 95.118682 -171.48048) (xy 94.248224 -172.351192)
			(xy 94.248224 -174.002446) (xy 94.30639 -174.108364) (xy 94.331028 -174.125382) (xy 94.365064 -174.150274)
			(xy 94.40037 -174.179484) (xy 94.412054 -174.190152) (xy 94.436692 -174.213774) (xy 96.190308 -175.96739)
			(xy 96.190308 -180.274976) (xy 99.775772 -183.86044) (xy 99.775772 -190.501016) (xy 101.041454 -191.766698)
			(xy 101.058094 -191.782626) (xy 101.096003 -191.808786) (xy 101.138007 -191.827685) (xy 101.182728 -191.838703)
			(xy 101.228704 -191.841481) (xy 101.274427 -191.835926) (xy 101.3184 -191.822222) (xy 101.359182 -191.800816)
			(xy 101.395439 -191.77241) (xy 101.425982 -191.737935) (xy 101.449811 -191.698519) (xy 101.466146 -191.655454)
			(xy 101.474451 -191.610149) (xy 101.475032 -191.58712) (xy 101.475032 -1.999996) (xy 101.474545 -1.968897)
			(xy 101.466426 -1.907232) (xy 101.450326 -1.847155) (xy 101.426523 -1.789693) (xy 101.395422 -1.73583)
			(xy 101.357556 -1.686487) (xy 101.313574 -1.642509) (xy 101.264227 -1.604649) (xy 101.210361 -1.573554)
			(xy 101.152896 -1.549757) (xy 101.092817 -1.533664) (xy 101.031151 -1.525551) (xy 101.000052 -1.525016)
			(xy 26.651966 -1.525016) (xy 26.635321 -1.525563) (xy 26.603168 -1.534187) (xy 26.574342 -1.550838)
			(xy 26.550808 -1.574382) (xy 26.534168 -1.603215) (xy 26.525557 -1.635371) (xy 26.524966 -1.652016)
			(xy 26.524966 -2.500122) (xy 26.524481 -2.576763) (xy 26.516717 -2.729848) (xy 26.50121 -2.882343)
			(xy 26.477998 -3.033857) (xy 26.447143 -3.184001) (xy 26.408722 -3.33239) (xy 26.362835 -3.478642)
			(xy 26.3096 -3.622382) (xy 26.249152 -3.763241) (xy 26.181648 -3.900858) (xy 26.10726 -4.034879)
			(xy 26.026179 -4.164961) (xy 25.938614 -4.290769) (xy 25.84479 -4.41198) (xy 25.744946 -4.528284)
			(xy 25.63934 -4.639381) (xy 25.528243 -4.744987) (xy 25.411939 -4.844831) (xy 25.290727 -4.938655)
			(xy 25.164919 -5.02622) (xy 25.034838 -5.107301) (xy 24.900816 -5.181689) (xy 24.763199 -5.249193)
			(xy 24.62234 -5.30964) (xy 24.4786 -5.362876) (xy 24.332348 -5.408763) (xy 24.183959 -5.447183) (xy 24.033815 -5.478039)
			(xy 23.882301 -5.50125) (xy 23.729806 -5.516757) (xy 23.576721 -5.524521) (xy 23.50008 -5.525008)
			(xy 8.875776 -5.525008) (xy 8.852421 -5.525531) (xy 8.806495 -5.534052) (xy 8.7629 -5.550823) (xy 8.723103 -5.575278)
			(xy 8.688446 -5.606592) (xy 8.660094 -5.643713) (xy 8.639002 -5.68539) (xy 8.625882 -5.730219) (xy 8.621174 -5.776691)
			(xy 8.625038 -5.823241) (xy 8.637343 -5.868301) (xy 8.657675 -5.910353) (xy 8.685349 -5.947982) (xy 8.719433 -5.979921)
			(xy 8.73887 -5.992876) (xy 8.792956 -6.028129) (xy 8.89714 -6.104397) (xy 8.996401 -6.18697) (xy 9.090358 -6.275532)
			(xy 9.178651 -6.369743) (xy 9.260939 -6.46924) (xy 9.336908 -6.573643) (xy 9.406266 -6.682549) (xy 9.468746 -6.795542)
			(xy 9.524109 -6.912187) (xy 9.572143 -7.032037) (xy 9.612661 -7.154632) (xy 9.645511 -7.2795) (xy 9.670564 -7.406163)
			(xy 9.687725 -7.534134) (xy 9.696928 -7.662923) (xy 9.698139 -7.792034) (xy 9.691351 -7.920972) (xy 9.676591 -8.049243)
			(xy 9.653916 -8.176353) (xy 9.623413 -8.301815) (xy 9.585199 -8.425147) (xy 9.539421 -8.545876) (xy 9.486254 -8.663539)
			(xy 9.425903 -8.777683) (xy 9.358599 -8.88787) (xy 9.2846 -8.993678) (xy 9.233757 -9.057555) (xy 15.679156 -9.057555)
			(xy 15.679156 -8.976445) (xy 15.687106 -8.895726) (xy 15.702929 -8.816175) (xy 15.726474 -8.738559)
			(xy 15.757513 -8.663623) (xy 15.795748 -8.592091) (xy 15.84081 -8.524651) (xy 15.892265 -8.461952)
			(xy 15.949618 -8.404599) (xy 16.012317 -8.353144) (xy 16.079757 -8.308082) (xy 16.151289 -8.269847)
			(xy 16.226225 -8.238808) (xy 16.303841 -8.215263) (xy 16.383392 -8.19944) (xy 16.464111 -8.19149)
			(xy 16.545221 -8.19149) (xy 16.62594 -8.19944) (xy 16.705491 -8.215263) (xy 16.783107 -8.238808)
			(xy 16.858043 -8.269847) (xy 16.929575 -8.308082) (xy 16.997015 -8.353144) (xy 17.059714 -8.404599)
			(xy 17.117067 -8.461952) (xy 17.168522 -8.524651) (xy 17.213584 -8.592091) (xy 17.251819 -8.663623)
			(xy 17.282858 -8.738559) (xy 17.306403 -8.816175) (xy 17.322226 -8.895726) (xy 17.330176 -8.976445)
			(xy 17.330674 -9.017) (xy 17.330176 -9.057555) (xy 17.322226 -9.138274) (xy 17.306403 -9.217825)
			(xy 17.282858 -9.295441) (xy 17.251819 -9.370377) (xy 17.213584 -9.441909) (xy 17.168522 -9.509349)
			(xy 17.117067 -9.572048) (xy 17.059714 -9.629401) (xy 16.997015 -9.680856) (xy 16.929575 -9.725918)
			(xy 16.858043 -9.764153) (xy 16.783107 -9.795192) (xy 16.705491 -9.818737) (xy 16.62594 -9.83456)
			(xy 16.545221 -9.84251) (xy 16.464111 -9.84251) (xy 16.383392 -9.83456) (xy 16.303841 -9.818737)
			(xy 16.226225 -9.795192) (xy 16.151289 -9.764153) (xy 16.079757 -9.725918) (xy 16.012317 -9.680856)
			(xy 15.949618 -9.629401) (xy 15.892265 -9.572048) (xy 15.84081 -9.509349) (xy 15.795748 -9.441909)
			(xy 15.757513 -9.370377) (xy 15.726474 -9.295441) (xy 15.702929 -9.217825) (xy 15.687106 -9.138274)
			(xy 15.679156 -9.057555) (xy 9.233757 -9.057555) (xy 9.204191 -9.094701) (xy 9.11768 -9.19055) (xy 9.025399 -9.280857)
			(xy 8.927703 -9.365277) (xy 8.824967 -9.443484) (xy 8.717584 -9.515179) (xy 8.605968 -9.580087) (xy 8.490546 -9.637957)
			(xy 8.371762 -9.688569) (xy 8.250072 -9.731728) (xy 8.125943 -9.767268) (xy 7.999851 -9.795052) (xy 7.87228 -9.814975)
			(xy 7.743721 -9.826959) (xy 7.614666 -9.830959) (xy 7.485611 -9.826959) (xy 7.357052 -9.814975) (xy 7.229481 -9.795052)
			(xy 7.103389 -9.767268) (xy 6.97926 -9.731728) (xy 6.85757 -9.688569) (xy 6.738786 -9.637957) (xy 6.623364 -9.580087)
			(xy 6.511748 -9.515179) (xy 6.404365 -9.443484) (xy 6.301629 -9.365277) (xy 6.203933 -9.280857) (xy 6.111652 -9.19055)
			(xy 6.025141 -9.094701) (xy 5.944732 -8.993678) (xy 5.870733 -8.88787) (xy 5.803429 -8.777683) (xy 5.743078 -8.663539)
			(xy 5.689911 -8.545876) (xy 5.644133 -8.425147) (xy 5.605919 -8.301815) (xy 5.575416 -8.176353) (xy 5.552741 -8.049243)
			(xy 5.537981 -7.920972) (xy 5.531193 -7.792034) (xy 5.532404 -7.662923) (xy 5.541607 -7.534134) (xy 5.558768 -7.406163)
			(xy 5.583821 -7.2795) (xy 5.616671 -7.154632) (xy 5.657189 -7.032037) (xy 5.705223 -6.912187) (xy 5.760586 -6.795542)
			(xy 5.823066 -6.682549) (xy 5.892424 -6.573643) (xy 5.968393 -6.46924) (xy 6.050681 -6.369743) (xy 6.138974 -6.275532)
			(xy 6.232931 -6.18697) (xy 6.332192 -6.104397) (xy 6.436376 -6.028129) (xy 6.490462 -5.992876) (xy 6.509836 -5.979842)
			(xy 6.543893 -5.947905) (xy 6.571543 -5.910284) (xy 6.591855 -5.868246) (xy 6.604147 -5.823205) (xy 6.608005 -5.776676)
			(xy 6.603298 -5.730225) (xy 6.590186 -5.685416) (xy 6.569108 -5.643755) (xy 6.540776 -5.606646) (xy 6.506141 -5.575337)
			(xy 6.46637 -5.550881) (xy 6.422801 -5.534101) (xy 6.3769 -5.525562) (xy 6.353556 -5.525008) (xy 1.652016 -5.525008)
			(xy 1.63536 -5.525501) (xy 1.603183 -5.534119) (xy 1.574334 -5.550773) (xy 1.550778 -5.574327) (xy 1.534122 -5.603176)
			(xy 1.525502 -5.635352) (xy 1.525016 -5.652008) (xy 1.525016 -10.327555) (xy 13.139156 -10.327555)
			(xy 13.139156 -10.246445) (xy 13.147106 -10.165726) (xy 13.162929 -10.086175) (xy 13.186474 -10.008559)
			(xy 13.217513 -9.933623) (xy 13.255748 -9.862091) (xy 13.30081 -9.794651) (xy 13.352265 -9.731952)
			(xy 13.409618 -9.674599) (xy 13.472317 -9.623144) (xy 13.539757 -9.578082) (xy 13.611289 -9.539847)
			(xy 13.686225 -9.508808) (xy 13.763841 -9.485263) (xy 13.843392 -9.46944) (xy 13.924111 -9.46149)
			(xy 14.005221 -9.46149) (xy 14.08594 -9.46944) (xy 14.165491 -9.485263) (xy 14.243107 -9.508808)
			(xy 14.318043 -9.539847) (xy 14.389575 -9.578082) (xy 14.457015 -9.623144) (xy 14.519714 -9.674599)
			(xy 14.577067 -9.731952) (xy 14.628522 -9.794651) (xy 14.673584 -9.862091) (xy 14.711819 -9.933623)
			(xy 14.742858 -10.008559) (xy 14.766403 -10.086175) (xy 14.782226 -10.165726) (xy 14.790176 -10.246445)
			(xy 14.790674 -10.287) (xy 14.790176 -10.327555) (xy 14.782226 -10.408274) (xy 14.766403 -10.487825)
			(xy 14.742858 -10.565441) (xy 14.711819 -10.640377) (xy 14.673584 -10.711909) (xy 14.628522 -10.779349)
			(xy 14.577067 -10.842048) (xy 14.519714 -10.899401) (xy 14.457015 -10.950856) (xy 14.389575 -10.995918)
			(xy 14.318043 -11.034153) (xy 14.243107 -11.065192) (xy 14.165491 -11.088737) (xy 14.08594 -11.10456)
			(xy 14.005221 -11.11251) (xy 13.924111 -11.11251) (xy 13.843392 -11.10456) (xy 13.763841 -11.088737)
			(xy 13.686225 -11.065192) (xy 13.611289 -11.034153) (xy 13.539757 -10.995918) (xy 13.472317 -10.950856)
			(xy 13.409618 -10.899401) (xy 13.352265 -10.842048) (xy 13.30081 -10.779349) (xy 13.255748 -10.711909)
			(xy 13.217513 -10.640377) (xy 13.186474 -10.565441) (xy 13.162929 -10.487825) (xy 13.147106 -10.408274)
			(xy 13.139156 -10.327555) (xy 1.525016 -10.327555) (xy 1.525016 -11.597555) (xy 15.679156 -11.597555)
			(xy 15.679156 -11.516445) (xy 15.687106 -11.435726) (xy 15.702929 -11.356175) (xy 15.726474 -11.278559)
			(xy 15.757513 -11.203623) (xy 15.795748 -11.132091) (xy 15.84081 -11.064651) (xy 15.892265 -11.001952)
			(xy 15.949618 -10.944599) (xy 16.012317 -10.893144) (xy 16.079757 -10.848082) (xy 16.151289 -10.809847)
			(xy 16.226225 -10.778808) (xy 16.303841 -10.755263) (xy 16.383392 -10.73944) (xy 16.464111 -10.73149)
			(xy 16.545221 -10.73149) (xy 16.62594 -10.73944) (xy 16.705491 -10.755263) (xy 16.783107 -10.778808)
			(xy 16.858043 -10.809847) (xy 16.929575 -10.848082) (xy 16.997015 -10.893144) (xy 17.059714 -10.944599)
			(xy 17.117067 -11.001952) (xy 17.168522 -11.064651) (xy 17.213584 -11.132091) (xy 17.251819 -11.203623)
			(xy 17.282858 -11.278559) (xy 17.306403 -11.356175) (xy 17.322226 -11.435726) (xy 17.330176 -11.516445)
			(xy 17.330674 -11.557) (xy 17.330176 -11.597555) (xy 17.322226 -11.678274) (xy 17.306403 -11.757825)
			(xy 17.282858 -11.835441) (xy 17.251819 -11.910377) (xy 17.213584 -11.981909) (xy 17.168522 -12.049349)
			(xy 17.117067 -12.112048) (xy 17.059714 -12.169401) (xy 16.997015 -12.220856) (xy 16.929575 -12.265918)
			(xy 16.858043 -12.304153) (xy 16.783107 -12.335192) (xy 16.705491 -12.358737) (xy 16.62594 -12.37456)
			(xy 16.545221 -12.38251) (xy 16.464111 -12.38251) (xy 16.383392 -12.37456) (xy 16.303841 -12.358737)
			(xy 16.226225 -12.335192) (xy 16.151289 -12.304153) (xy 16.079757 -12.265918) (xy 16.012317 -12.220856)
			(xy 15.949618 -12.169401) (xy 15.892265 -12.112048) (xy 15.84081 -12.049349) (xy 15.795748 -11.981909)
			(xy 15.757513 -11.910377) (xy 15.726474 -11.835441) (xy 15.702929 -11.757825) (xy 15.687106 -11.678274)
			(xy 15.679156 -11.597555) (xy 1.525016 -11.597555) (xy 1.525016 -15.407555) (xy 13.139156 -15.407555)
			(xy 13.139156 -15.326445) (xy 13.147106 -15.245726) (xy 13.162929 -15.166175) (xy 13.186474 -15.088559)
			(xy 13.217513 -15.013623) (xy 13.255748 -14.942091) (xy 13.30081 -14.874651) (xy 13.352265 -14.811952)
			(xy 13.409618 -14.754599) (xy 13.472317 -14.703144) (xy 13.539757 -14.658082) (xy 13.611289 -14.619847)
			(xy 13.686225 -14.588808) (xy 13.763841 -14.565263) (xy 13.843392 -14.54944) (xy 13.924111 -14.54149)
			(xy 14.005221 -14.54149) (xy 14.08594 -14.54944) (xy 14.165491 -14.565263) (xy 14.243107 -14.588808)
			(xy 14.318043 -14.619847) (xy 14.389575 -14.658082) (xy 14.457015 -14.703144) (xy 14.519714 -14.754599)
			(xy 14.577067 -14.811952) (xy 14.628522 -14.874651) (xy 14.673584 -14.942091) (xy 14.711819 -15.013623)
			(xy 14.742858 -15.088559) (xy 14.766403 -15.166175) (xy 14.782226 -15.245726) (xy 14.790176 -15.326445)
			(xy 14.790674 -15.367) (xy 14.790176 -15.407555) (xy 14.782226 -15.488274) (xy 14.766403 -15.567825)
			(xy 14.742858 -15.645441) (xy 14.711819 -15.720377) (xy 14.673584 -15.791909) (xy 14.628522 -15.859349)
			(xy 14.577067 -15.922048) (xy 14.519714 -15.979401) (xy 14.457015 -16.030856) (xy 14.389575 -16.075918)
			(xy 14.318043 -16.114153) (xy 14.243107 -16.145192) (xy 14.165491 -16.168737) (xy 14.08594 -16.18456)
			(xy 14.005221 -16.19251) (xy 13.924111 -16.19251) (xy 13.843392 -16.18456) (xy 13.763841 -16.168737)
			(xy 13.686225 -16.145192) (xy 13.611289 -16.114153) (xy 13.539757 -16.075918) (xy 13.472317 -16.030856)
			(xy 13.409618 -15.979401) (xy 13.352265 -15.922048) (xy 13.30081 -15.859349) (xy 13.255748 -15.791909)
			(xy 13.217513 -15.720377) (xy 13.186474 -15.645441) (xy 13.162929 -15.567825) (xy 13.147106 -15.488274)
			(xy 13.139156 -15.407555) (xy 1.525016 -15.407555) (xy 1.525016 -16.677555) (xy 15.679156 -16.677555)
			(xy 15.679156 -16.596445) (xy 15.687106 -16.515726) (xy 15.702929 -16.436175) (xy 15.726474 -16.358559)
			(xy 15.757513 -16.283623) (xy 15.795748 -16.212091) (xy 15.84081 -16.144651) (xy 15.892265 -16.081952)
			(xy 15.949618 -16.024599) (xy 16.012317 -15.973144) (xy 16.079757 -15.928082) (xy 16.151289 -15.889847)
			(xy 16.226225 -15.858808) (xy 16.303841 -15.835263) (xy 16.383392 -15.81944) (xy 16.464111 -15.81149)
			(xy 16.545221 -15.81149) (xy 16.62594 -15.81944) (xy 16.705491 -15.835263) (xy 16.783107 -15.858808)
			(xy 16.858043 -15.889847) (xy 16.929575 -15.928082) (xy 16.997015 -15.973144) (xy 17.059714 -16.024599)
			(xy 17.117067 -16.081952) (xy 17.168522 -16.144651) (xy 17.213584 -16.212091) (xy 17.251819 -16.283623)
			(xy 17.282858 -16.358559) (xy 17.306403 -16.436175) (xy 17.322226 -16.515726) (xy 17.330176 -16.596445)
			(xy 17.330674 -16.637) (xy 17.330176 -16.677555) (xy 17.322226 -16.758274) (xy 17.306403 -16.837825)
			(xy 17.282858 -16.915441) (xy 17.251819 -16.990377) (xy 17.213584 -17.061909) (xy 17.168522 -17.129349)
			(xy 17.117067 -17.192048) (xy 17.059714 -17.249401) (xy 16.997015 -17.300856) (xy 16.929575 -17.345918)
			(xy 16.858043 -17.384153) (xy 16.783107 -17.415192) (xy 16.705491 -17.438737) (xy 16.62594 -17.45456)
			(xy 16.545221 -17.46251) (xy 16.464111 -17.46251) (xy 16.383392 -17.45456) (xy 16.303841 -17.438737)
			(xy 16.226225 -17.415192) (xy 16.151289 -17.384153) (xy 16.079757 -17.345918) (xy 16.012317 -17.300856)
			(xy 15.949618 -17.249401) (xy 15.892265 -17.192048) (xy 15.84081 -17.129349) (xy 15.795748 -17.061909)
			(xy 15.757513 -16.990377) (xy 15.726474 -16.915441) (xy 15.702929 -16.837825) (xy 15.687106 -16.758274)
			(xy 15.679156 -16.677555) (xy 1.525016 -16.677555) (xy 1.525016 -17.080992) (xy 13.138912 -17.080992)
			(xy 14.79042 -17.080992) (xy 14.79042 -18.733008) (xy 13.138912 -18.733008) (xy 13.138912 -17.080992)
			(xy 1.525016 -17.080992) (xy 1.525016 -19.177) (xy 5.5306 -19.177) (xy 5.534631 -19.047434) (xy 5.54671 -18.91837)
			(xy 5.566789 -18.790306) (xy 5.594791 -18.663739) (xy 5.630608 -18.539156) (xy 5.6741 -18.417042)
			(xy 5.7251 -18.297868) (xy 5.783411 -18.182095) (xy 5.848806 -18.070171) (xy 5.921033 -17.962529)
			(xy 5.999813 -17.859586) (xy 6.08484 -17.76174) (xy 6.175785 -17.669368) (xy 6.272297 -17.58283)
			(xy 6.374003 -17.502459) (xy 6.480509 -17.428567) (xy 6.591402 -17.361439) (xy 6.706254 -17.301335)
			(xy 6.824621 -17.248488) (xy 6.946044 -17.203101) (xy 7.070054 -17.165352) (xy 7.196171 -17.135385)
			(xy 7.323907 -17.113316) (xy 7.452768 -17.099232) (xy 7.582255 -17.093186) (xy 7.711868 -17.095202)
			(xy 7.841104 -17.105272) (xy 7.969465 -17.123357) (xy 8.096453 -17.149387) (xy 8.221577 -17.183262)
			(xy 8.344353 -17.22485) (xy 8.464306 -17.273991) (xy 8.580971 -17.330494) (xy 8.693899 -17.394141)
			(xy 8.802651 -17.464685) (xy 8.906807 -17.541854) (xy 9.005964 -17.625349) (xy 9.099738 -17.714847)
			(xy 9.187767 -17.810002) (xy 9.26971 -17.910445) (xy 9.345249 -18.015788) (xy 9.414094 -18.125624)
			(xy 9.475977 -18.239528) (xy 9.530658 -18.357058) (xy 9.577928 -18.477761) (xy 9.617601 -18.601169)
			(xy 9.649526 -18.726805) (xy 9.673578 -18.854182) (xy 9.689665 -18.982808) (xy 9.697724 -19.112186)
			(xy 9.698228 -19.177) (xy 9.697724 -19.241814) (xy 9.689665 -19.371192) (xy 9.673578 -19.499818)
			(xy 9.649526 -19.627195) (xy 9.617601 -19.752831) (xy 9.577928 -19.876239) (xy 9.530658 -19.996942)
			(xy 9.475977 -20.114472) (xy 9.414094 -20.228376) (xy 9.345249 -20.338212) (xy 9.26971 -20.443555)
			(xy 9.187767 -20.543998) (xy 9.099738 -20.639153) (xy 9.005964 -20.728651) (xy 8.906807 -20.812146)
			(xy 8.802651 -20.889315) (xy 8.693899 -20.959859) (xy 8.580971 -21.023506) (xy 8.464306 -21.080009)
			(xy 8.344353 -21.12915) (xy 8.221577 -21.170738) (xy 8.096453 -21.204613) (xy 7.969465 -21.230643)
			(xy 7.841104 -21.248728) (xy 7.711868 -21.258798) (xy 7.582255 -21.260814) (xy 7.452768 -21.254768)
			(xy 7.323907 -21.240684) (xy 7.196171 -21.218615) (xy 7.070054 -21.188648) (xy 6.946044 -21.150899)
			(xy 6.824621 -21.105512) (xy 6.706254 -21.052665) (xy 6.591402 -20.992561) (xy 6.480509 -20.925433)
			(xy 6.374003 -20.851541) (xy 6.272297 -20.77117) (xy 6.175785 -20.684632) (xy 6.08484 -20.59226)
			(xy 5.999813 -20.494414) (xy 5.921033 -20.391471) (xy 5.848806 -20.283829) (xy 5.783411 -20.171905)
			(xy 5.7251 -20.056132) (xy 5.6741 -19.936958) (xy 5.630608 -19.814844) (xy 5.594791 -19.690261) (xy 5.566789 -19.563694)
			(xy 5.54671 -19.43563) (xy 5.534631 -19.306566) (xy 5.5306 -19.177) (xy 1.525016 -19.177) (xy 1.525016 -25.909778)
			(xy 6.671831 -25.909778) (xy 6.675786 -25.817941) (xy 6.687621 -25.726784) (xy 6.707248 -25.636981)
			(xy 6.734522 -25.549199) (xy 6.769242 -25.464085) (xy 6.81115 -25.382272) (xy 6.859936 -25.304364)
			(xy 6.915239 -25.230939) (xy 6.976649 -25.162539) (xy 7.043711 -25.099672) (xy 7.11593 -25.042802)
			(xy 7.19277 -24.992351) (xy 7.273663 -24.948692) (xy 7.358009 -24.912149) (xy 7.445185 -24.882992)
			(xy 7.534544 -24.861438) (xy 7.625425 -24.847644) (xy 7.717156 -24.841714) (xy 7.809057 -24.843692)
			(xy 7.900448 -24.853563) (xy 7.990652 -24.871253) (xy 8.079001 -24.896633) (xy 8.164841 -24.929513)
			(xy 8.247537 -24.969651) (xy 8.326477 -25.01675) (xy 8.401075 -25.07046) (xy 8.470781 -25.130384)
			(xy 8.535076 -25.196078) (xy 8.593487 -25.267056) (xy 8.645579 -25.342793) (xy 8.690968 -25.422728)
			(xy 8.729318 -25.506268) (xy 8.760343 -25.592796) (xy 8.783816 -25.681671) (xy 8.799562 -25.772235)
			(xy 8.807464 -25.863817) (xy 8.807958 -25.909778) (xy 8.807464 -25.955739) (xy 8.799562 -26.047321)
			(xy 8.783816 -26.137885) (xy 8.760343 -26.22676) (xy 8.729318 -26.313288) (xy 8.690968 -26.396828)
			(xy 8.645579 -26.476763) (xy 8.593487 -26.5525) (xy 8.535076 -26.623478) (xy 8.470781 -26.689172)
			(xy 8.401075 -26.749096) (xy 8.326477 -26.802806) (xy 8.247537 -26.849905) (xy 8.164841 -26.890043)
			(xy 8.079001 -26.922923) (xy 7.990652 -26.948303) (xy 7.900448 -26.965993) (xy 7.809057 -26.975864)
			(xy 7.717156 -26.977842) (xy 7.625425 -26.971912) (xy 7.534544 -26.958118) (xy 7.445185 -26.936564)
			(xy 7.358009 -26.907407) (xy 7.273663 -26.870864) (xy 7.19277 -26.827205) (xy 7.11593 -26.776754)
			(xy 7.043711 -26.719884) (xy 6.976649 -26.657017) (xy 6.915239 -26.588617) (xy 6.859936 -26.515192)
			(xy 6.81115 -26.437284) (xy 6.769242 -26.355471) (xy 6.734522 -26.270357) (xy 6.707248 -26.182575)
			(xy 6.687621 -26.092772) (xy 6.675786 -26.001615) (xy 6.671831 -25.909778) (xy 1.525016 -25.909778)
			(xy 1.525016 -29.200094) (xy 11.59841 -29.200094) (xy 11.602414 -28.999986) (xy 11.614422 -28.800198)
			(xy 11.634414 -28.60105) (xy 11.662357 -28.402862) (xy 11.698207 -28.205951) (xy 11.741908 -28.010631)
			(xy 11.793387 -27.817217) (xy 11.852564 -27.626017) (xy 11.919344 -27.437337) (xy 11.993619 -27.251481)
			(xy 12.07527 -27.068745) (xy 12.164168 -26.889422) (xy 12.260168 -26.7138) (xy 12.363119 -26.542159)
			(xy 12.472854 -26.374775) (xy 12.589199 -26.211915) (xy 12.711966 -26.05384) (xy 12.840959 -25.900804)
			(xy 12.975972 -25.753052) (xy 13.116789 -25.610819) (xy 13.263183 -25.474335) (xy 13.414921 -25.343816)
			(xy 13.57176 -25.219474) (xy 13.733447 -25.101506) (xy 13.899726 -24.990101) (xy 14.070328 -24.885439)
			(xy 14.244981 -24.787686) (xy 14.423405 -24.696999) (xy 14.605315 -24.613523) (xy 14.790419 -24.537392)
			(xy 14.978421 -24.468728) (xy 15.169019 -24.407641) (xy 15.361909 -24.354229) (xy 15.556781 -24.308577)
			(xy 15.753324 -24.270758) (xy 15.951223 -24.240834) (xy 16.15016 -24.21885) (xy 16.349818 -24.204844)
			(xy 16.549876 -24.198838) (xy 16.750015 -24.20084) (xy 16.949913 -24.210849) (xy 17.14925 -24.228847)
			(xy 17.347708 -24.254806) (xy 17.544968 -24.288684) (xy 17.740715 -24.330428) (xy 17.934635 -24.37997)
			(xy 18.126418 -24.437231) (xy 18.315756 -24.50212) (xy 18.502346 -24.574532) (xy 18.68589 -24.654351)
			(xy 18.866093 -24.74145) (xy 19.042667 -24.835688) (xy 19.215329 -24.936917) (xy 19.383803 -25.044972)
			(xy 19.547819 -25.159681) (xy 19.707114 -25.280861) (xy 19.861433 -25.408316) (xy 20.010529 -25.541845)
			(xy 20.154163 -25.681231) (xy 20.292105 -25.826253) (xy 20.424135 -25.976677) (xy 20.550041 -26.132264)
			(xy 20.66962 -26.292763) (xy 20.782683 -26.457918) (xy 20.889047 -26.627465) (xy 20.988543 -26.801131)
			(xy 21.08101 -26.978639) (xy 21.166302 -27.159705) (xy 21.244281 -27.344038) (xy 21.314822 -27.531343)
			(xy 21.377813 -27.721321) (xy 21.433152 -27.913667) (xy 21.480752 -28.108072) (xy 21.520535 -28.304227)
			(xy 21.552438 -28.501817) (xy 21.57641 -28.700524) (xy 21.592413 -28.900032) (xy 21.600421 -29.10002)
			(xy 21.600922 -29.200094) (xy 21.600421 -29.300168) (xy 21.592413 -29.500156) (xy 21.57641 -29.699664)
			(xy 21.552438 -29.898371) (xy 21.520535 -30.095961) (xy 21.480752 -30.292116) (xy 21.433152 -30.486521)
			(xy 21.377813 -30.678867) (xy 21.314822 -30.868845) (xy 21.244281 -31.05615) (xy 21.166302 -31.240483)
			(xy 21.08101 -31.421549) (xy 20.988543 -31.599057) (xy 20.889047 -31.772723) (xy 20.782683 -31.94227)
			(xy 20.66962 -32.107425) (xy 20.550041 -32.267924) (xy 20.424135 -32.423511) (xy 20.292105 -32.573935)
			(xy 20.154163 -32.718957) (xy 20.010529 -32.858343) (xy 19.861433 -32.991872) (xy 19.707114 -33.119327)
			(xy 19.547819 -33.240507) (xy 19.383803 -33.355216) (xy 19.215329 -33.463271) (xy 19.042667 -33.5645)
			(xy 18.866093 -33.658738) (xy 18.68589 -33.745837) (xy 18.502346 -33.825656) (xy 18.315756 -33.898068)
			(xy 18.126418 -33.962957) (xy 17.934635 -34.020218) (xy 17.740715 -34.06976) (xy 17.544968 -34.111504)
			(xy 17.347708 -34.145382) (xy 17.14925 -34.171341) (xy 16.949913 -34.189339) (xy 16.750015 -34.199348)
			(xy 16.549876 -34.20135) (xy 16.349818 -34.195344) (xy 16.15016 -34.181338) (xy 15.951223 -34.159354)
			(xy 15.753324 -34.12943) (xy 15.556781 -34.091611) (xy 15.361909 -34.045959) (xy 15.169019 -33.992547)
			(xy 14.978421 -33.93146) (xy 14.790419 -33.862796) (xy 14.605315 -33.786665) (xy 14.423405 -33.703189)
			(xy 14.244981 -33.612502) (xy 14.070328 -33.514749) (xy 13.899726 -33.410087) (xy 13.733447 -33.298682)
			(xy 13.57176 -33.180714) (xy 13.414921 -33.056372) (xy 13.263183 -32.925853) (xy 13.116789 -32.789369)
			(xy 12.975972 -32.647136) (xy 12.840959 -32.499384) (xy 12.711966 -32.346348) (xy 12.589199 -32.188273)
			(xy 12.472854 -32.025413) (xy 12.363119 -31.858029) (xy 12.260168 -31.686388) (xy 12.164168 -31.510766)
			(xy 12.07527 -31.331443) (xy 11.993619 -31.148707) (xy 11.919344 -30.962851) (xy 11.852564 -30.774171)
			(xy 11.793387 -30.582971) (xy 11.741908 -30.389557) (xy 11.698207 -30.194237) (xy 11.662357 -29.997326)
			(xy 11.634414 -29.799138) (xy 11.614422 -29.59999) (xy 11.602414 -29.400202) (xy 11.59841 -29.200094)
			(xy 1.525016 -29.200094) (xy 1.525016 -30.982412) (xy 4.852416 -30.982412) (xy 6.707632 -30.982412)
			(xy 6.707632 -32.83712) (xy 4.852416 -32.83712) (xy 4.852416 -30.982412) (xy 1.525016 -30.982412)
			(xy 1.525016 -34.90976) (xy 6.671831 -34.90976) (xy 6.675786 -34.817923) (xy 6.687621 -34.726766)
			(xy 6.707248 -34.636963) (xy 6.734522 -34.549181) (xy 6.769242 -34.464067) (xy 6.81115 -34.382254)
			(xy 6.859936 -34.304346) (xy 6.915239 -34.230921) (xy 6.976649 -34.162521) (xy 7.043711 -34.099654)
			(xy 7.11593 -34.042784) (xy 7.19277 -33.992333) (xy 7.273663 -33.948674) (xy 7.358009 -33.912131)
			(xy 7.445185 -33.882974) (xy 7.534544 -33.86142) (xy 7.625425 -33.847626) (xy 7.717156 -33.841696)
			(xy 7.809057 -33.843674) (xy 7.900448 -33.853545) (xy 7.990652 -33.871235) (xy 8.079001 -33.896615)
			(xy 8.164841 -33.929495) (xy 8.247537 -33.969633) (xy 8.326477 -34.016732) (xy 8.401075 -34.070442)
			(xy 8.470781 -34.130366) (xy 8.535076 -34.19606) (xy 8.593487 -34.267038) (xy 8.645579 -34.342775)
			(xy 8.690968 -34.42271) (xy 8.729318 -34.50625) (xy 8.760343 -34.592778) (xy 8.783816 -34.681653)
			(xy 8.799562 -34.772217) (xy 8.807464 -34.863799) (xy 8.807958 -34.90976) (xy 8.807464 -34.955721)
			(xy 8.799562 -35.047303) (xy 8.783816 -35.137867) (xy 8.760343 -35.226742) (xy 8.729318 -35.31327)
			(xy 8.690968 -35.39681) (xy 8.645579 -35.476745) (xy 8.593487 -35.552482) (xy 8.535076 -35.62346)
			(xy 8.470781 -35.689154) (xy 8.401075 -35.749078) (xy 8.326477 -35.802788) (xy 8.247537 -35.849887)
			(xy 8.164841 -35.890025) (xy 8.079001 -35.922905) (xy 7.990652 -35.948285) (xy 7.900448 -35.965975)
			(xy 7.809057 -35.975846) (xy 7.717156 -35.977824) (xy 7.625425 -35.971894) (xy 7.534544 -35.9581)
			(xy 7.445185 -35.936546) (xy 7.358009 -35.907389) (xy 7.273663 -35.870846) (xy 7.19277 -35.827187)
			(xy 7.11593 -35.776736) (xy 7.043711 -35.719866) (xy 6.976649 -35.656999) (xy 6.915239 -35.588599)
			(xy 6.859936 -35.515174) (xy 6.81115 -35.437266) (xy 6.769242 -35.355453) (xy 6.734522 -35.270339)
			(xy 6.707248 -35.182557) (xy 6.687621 -35.092754) (xy 6.675786 -35.001597) (xy 6.671831 -34.90976)
			(xy 1.525016 -34.90976) (xy 1.525016 -42.291) (xy 5.5306 -42.291) (xy 5.534631 -42.161434) (xy 5.54671 -42.03237)
			(xy 5.566789 -41.904306) (xy 5.594791 -41.777739) (xy 5.630608 -41.653156) (xy 5.6741 -41.531042)
			(xy 5.7251 -41.411868) (xy 5.783411 -41.296095) (xy 5.848806 -41.184171) (xy 5.921033 -41.076529)
			(xy 5.999813 -40.973586) (xy 6.08484 -40.87574) (xy 6.175785 -40.783368) (xy 6.272297 -40.69683)
			(xy 6.374003 -40.616459) (xy 6.480509 -40.542567) (xy 6.591402 -40.475439) (xy 6.706254 -40.415335)
			(xy 6.824621 -40.362488) (xy 6.946044 -40.317101) (xy 7.070054 -40.279352) (xy 7.196171 -40.249385)
			(xy 7.323907 -40.227316) (xy 7.452768 -40.213232) (xy 7.582255 -40.207186) (xy 7.711868 -40.209202)
			(xy 7.841104 -40.219272) (xy 7.969465 -40.237357) (xy 8.096453 -40.263387) (xy 8.221577 -40.297262)
			(xy 8.344353 -40.33885) (xy 8.464306 -40.387991) (xy 8.580971 -40.444494) (xy 8.693899 -40.508141)
			(xy 8.802651 -40.578685) (xy 8.906807 -40.655854) (xy 9.005964 -40.739349) (xy 9.099738 -40.828847)
			(xy 9.187767 -40.924002) (xy 9.26971 -41.024445) (xy 9.345249 -41.129788) (xy 9.414094 -41.239624)
			(xy 9.475977 -41.353528) (xy 9.530658 -41.471058) (xy 9.577928 -41.591761) (xy 9.617601 -41.715169)
			(xy 9.649526 -41.840805) (xy 9.673578 -41.968182) (xy 9.689665 -42.096808) (xy 9.697724 -42.226186)
			(xy 9.698228 -42.291) (xy 9.697724 -42.355814) (xy 9.689665 -42.485192) (xy 9.673578 -42.613818)
			(xy 9.649526 -42.741195) (xy 9.617601 -42.866831) (xy 9.577928 -42.990239) (xy 9.530658 -43.110942)
			(xy 9.475977 -43.228472) (xy 9.414094 -43.342376) (xy 9.345249 -43.452212) (xy 9.26971 -43.557555)
			(xy 9.233814 -43.601555) (xy 15.679156 -43.601555) (xy 15.679156 -43.520445) (xy 15.687106 -43.439726)
			(xy 15.702929 -43.360175) (xy 15.726474 -43.282559) (xy 15.757513 -43.207623) (xy 15.795748 -43.136091)
			(xy 15.84081 -43.068651) (xy 15.892265 -43.005952) (xy 15.949618 -42.948599) (xy 16.012317 -42.897144)
			(xy 16.079757 -42.852082) (xy 16.151289 -42.813847) (xy 16.226225 -42.782808) (xy 16.303841 -42.759263)
			(xy 16.383392 -42.74344) (xy 16.464111 -42.73549) (xy 16.545221 -42.73549) (xy 16.62594 -42.74344)
			(xy 16.705491 -42.759263) (xy 16.783107 -42.782808) (xy 16.858043 -42.813847) (xy 16.929575 -42.852082)
			(xy 16.997015 -42.897144) (xy 17.059714 -42.948599) (xy 17.117067 -43.005952) (xy 17.168522 -43.068651)
			(xy 17.213584 -43.136091) (xy 17.251819 -43.207623) (xy 17.282858 -43.282559) (xy 17.306403 -43.360175)
			(xy 17.322226 -43.439726) (xy 17.330176 -43.520445) (xy 17.330674 -43.561) (xy 17.330176 -43.601555)
			(xy 17.322226 -43.682274) (xy 17.306403 -43.761825) (xy 17.282858 -43.839441) (xy 17.251819 -43.914377)
			(xy 17.213584 -43.985909) (xy 17.168522 -44.053349) (xy 17.117067 -44.116048) (xy 17.059714 -44.173401)
			(xy 16.997015 -44.224856) (xy 16.929575 -44.269918) (xy 16.858043 -44.308153) (xy 16.783107 -44.339192)
			(xy 16.705491 -44.362737) (xy 16.62594 -44.37856) (xy 16.545221 -44.38651) (xy 16.464111 -44.38651)
			(xy 16.383392 -44.37856) (xy 16.303841 -44.362737) (xy 16.226225 -44.339192) (xy 16.151289 -44.308153)
			(xy 16.079757 -44.269918) (xy 16.012317 -44.224856) (xy 15.949618 -44.173401) (xy 15.892265 -44.116048)
			(xy 15.84081 -44.053349) (xy 15.795748 -43.985909) (xy 15.757513 -43.914377) (xy 15.726474 -43.839441)
			(xy 15.702929 -43.761825) (xy 15.687106 -43.682274) (xy 15.679156 -43.601555) (xy 9.233814 -43.601555)
			(xy 9.187767 -43.657998) (xy 9.099738 -43.753153) (xy 9.005964 -43.842651) (xy 8.906807 -43.926146)
			(xy 8.802651 -44.003315) (xy 8.693899 -44.073859) (xy 8.580971 -44.137506) (xy 8.464306 -44.194009)
			(xy 8.344353 -44.24315) (xy 8.221577 -44.284738) (xy 8.096453 -44.318613) (xy 7.969465 -44.344643)
			(xy 7.841104 -44.362728) (xy 7.711868 -44.372798) (xy 7.582255 -44.374814) (xy 7.452768 -44.368768)
			(xy 7.323907 -44.354684) (xy 7.196171 -44.332615) (xy 7.070054 -44.302648) (xy 6.946044 -44.264899)
			(xy 6.824621 -44.219512) (xy 6.706254 -44.166665) (xy 6.591402 -44.106561) (xy 6.480509 -44.039433)
			(xy 6.374003 -43.965541) (xy 6.272297 -43.88517) (xy 6.175785 -43.798632) (xy 6.08484 -43.70626)
			(xy 5.999813 -43.608414) (xy 5.921033 -43.505471) (xy 5.848806 -43.397829) (xy 5.783411 -43.285905)
			(xy 5.7251 -43.170132) (xy 5.6741 -43.050958) (xy 5.630608 -42.928844) (xy 5.594791 -42.804261) (xy 5.566789 -42.677694)
			(xy 5.54671 -42.54963) (xy 5.534631 -42.420566) (xy 5.5306 -42.291) (xy 1.525016 -42.291) (xy 1.525016 -44.871555)
			(xy 13.139156 -44.871555) (xy 13.139156 -44.790445) (xy 13.147106 -44.709726) (xy 13.162929 -44.630175)
			(xy 13.186474 -44.552559) (xy 13.217513 -44.477623) (xy 13.255748 -44.406091) (xy 13.30081 -44.338651)
			(xy 13.352265 -44.275952) (xy 13.409618 -44.218599) (xy 13.472317 -44.167144) (xy 13.539757 -44.122082)
			(xy 13.611289 -44.083847) (xy 13.686225 -44.052808) (xy 13.763841 -44.029263) (xy 13.843392 -44.01344)
			(xy 13.924111 -44.00549) (xy 14.005221 -44.00549) (xy 14.08594 -44.01344) (xy 14.165491 -44.029263)
			(xy 14.243107 -44.052808) (xy 14.318043 -44.083847) (xy 14.389575 -44.122082) (xy 14.457015 -44.167144)
			(xy 14.519714 -44.218599) (xy 14.577067 -44.275952) (xy 14.628522 -44.338651) (xy 14.673584 -44.406091)
			(xy 14.711819 -44.477623) (xy 14.742858 -44.552559) (xy 14.766403 -44.630175) (xy 14.782226 -44.709726)
			(xy 14.790176 -44.790445) (xy 14.790674 -44.831) (xy 14.790176 -44.871555) (xy 14.782226 -44.952274)
			(xy 14.766403 -45.031825) (xy 14.742858 -45.109441) (xy 14.711819 -45.184377) (xy 14.673584 -45.255909)
			(xy 14.628522 -45.323349) (xy 14.577067 -45.386048) (xy 14.519714 -45.443401) (xy 14.457015 -45.494856)
			(xy 14.389575 -45.539918) (xy 14.318043 -45.578153) (xy 14.243107 -45.609192) (xy 14.165491 -45.632737)
			(xy 14.08594 -45.64856) (xy 14.005221 -45.65651) (xy 13.924111 -45.65651) (xy 13.843392 -45.64856)
			(xy 13.763841 -45.632737) (xy 13.686225 -45.609192) (xy 13.611289 -45.578153) (xy 13.539757 -45.539918)
			(xy 13.472317 -45.494856) (xy 13.409618 -45.443401) (xy 13.352265 -45.386048) (xy 13.30081 -45.323349)
			(xy 13.255748 -45.255909) (xy 13.217513 -45.184377) (xy 13.186474 -45.109441) (xy 13.162929 -45.031825)
			(xy 13.147106 -44.952274) (xy 13.139156 -44.871555) (xy 1.525016 -44.871555) (xy 1.525016 -46.141555)
			(xy 15.679156 -46.141555) (xy 15.679156 -46.060445) (xy 15.687106 -45.979726) (xy 15.702929 -45.900175)
			(xy 15.726474 -45.822559) (xy 15.757513 -45.747623) (xy 15.795748 -45.676091) (xy 15.84081 -45.608651)
			(xy 15.892265 -45.545952) (xy 15.949618 -45.488599) (xy 16.012317 -45.437144) (xy 16.079757 -45.392082)
			(xy 16.151289 -45.353847) (xy 16.226225 -45.322808) (xy 16.303841 -45.299263) (xy 16.383392 -45.28344)
			(xy 16.464111 -45.27549) (xy 16.545221 -45.27549) (xy 16.62594 -45.28344) (xy 16.705491 -45.299263)
			(xy 16.783107 -45.322808) (xy 16.858043 -45.353847) (xy 16.929575 -45.392082) (xy 16.997015 -45.437144)
			(xy 17.059714 -45.488599) (xy 17.117067 -45.545952) (xy 17.168522 -45.608651) (xy 17.213584 -45.676091)
			(xy 17.251819 -45.747623) (xy 17.282858 -45.822559) (xy 17.306403 -45.900175) (xy 17.322226 -45.979726)
			(xy 17.330176 -46.060445) (xy 17.330674 -46.101) (xy 17.330176 -46.141555) (xy 17.322226 -46.222274)
			(xy 17.306403 -46.301825) (xy 17.282858 -46.379441) (xy 17.251819 -46.454377) (xy 17.213584 -46.525909)
			(xy 17.168522 -46.593349) (xy 17.117067 -46.656048) (xy 17.059714 -46.713401) (xy 16.997015 -46.764856)
			(xy 16.929575 -46.809918) (xy 16.858043 -46.848153) (xy 16.783107 -46.879192) (xy 16.705491 -46.902737)
			(xy 16.62594 -46.91856) (xy 16.545221 -46.92651) (xy 16.464111 -46.92651) (xy 16.383392 -46.91856)
			(xy 16.303841 -46.902737) (xy 16.226225 -46.879192) (xy 16.151289 -46.848153) (xy 16.079757 -46.809918)
			(xy 16.012317 -46.764856) (xy 15.949618 -46.713401) (xy 15.892265 -46.656048) (xy 15.84081 -46.593349)
			(xy 15.795748 -46.525909) (xy 15.757513 -46.454377) (xy 15.726474 -46.379441) (xy 15.702929 -46.301825)
			(xy 15.687106 -46.222274) (xy 15.679156 -46.141555) (xy 1.525016 -46.141555) (xy 1.525016 -49.951555)
			(xy 13.139156 -49.951555) (xy 13.139156 -49.870445) (xy 13.147106 -49.789726) (xy 13.162929 -49.710175)
			(xy 13.186474 -49.632559) (xy 13.217513 -49.557623) (xy 13.255748 -49.486091) (xy 13.30081 -49.418651)
			(xy 13.352265 -49.355952) (xy 13.409618 -49.298599) (xy 13.472317 -49.247144) (xy 13.539757 -49.202082)
			(xy 13.611289 -49.163847) (xy 13.686225 -49.132808) (xy 13.763841 -49.109263) (xy 13.843392 -49.09344)
			(xy 13.924111 -49.08549) (xy 14.005221 -49.08549) (xy 14.08594 -49.09344) (xy 14.165491 -49.109263)
			(xy 14.243107 -49.132808) (xy 14.318043 -49.163847) (xy 14.389575 -49.202082) (xy 14.457015 -49.247144)
			(xy 14.519714 -49.298599) (xy 14.577067 -49.355952) (xy 14.628522 -49.418651) (xy 14.673584 -49.486091)
			(xy 14.711819 -49.557623) (xy 14.742858 -49.632559) (xy 14.766403 -49.710175) (xy 14.782226 -49.789726)
			(xy 14.790176 -49.870445) (xy 14.790674 -49.911) (xy 14.790176 -49.951555) (xy 14.782226 -50.032274)
			(xy 14.766403 -50.111825) (xy 14.742858 -50.189441) (xy 14.711819 -50.264377) (xy 14.673584 -50.335909)
			(xy 14.628522 -50.403349) (xy 14.577067 -50.466048) (xy 14.519714 -50.523401) (xy 14.457015 -50.574856)
			(xy 14.389575 -50.619918) (xy 14.318043 -50.658153) (xy 14.243107 -50.689192) (xy 14.165491 -50.712737)
			(xy 14.08594 -50.72856) (xy 14.005221 -50.73651) (xy 13.924111 -50.73651) (xy 13.843392 -50.72856)
			(xy 13.763841 -50.712737) (xy 13.686225 -50.689192) (xy 13.611289 -50.658153) (xy 13.539757 -50.619918)
			(xy 13.472317 -50.574856) (xy 13.409618 -50.523401) (xy 13.352265 -50.466048) (xy 13.30081 -50.403349)
			(xy 13.255748 -50.335909) (xy 13.217513 -50.264377) (xy 13.186474 -50.189441) (xy 13.162929 -50.111825)
			(xy 13.147106 -50.032274) (xy 13.139156 -49.951555) (xy 1.525016 -49.951555) (xy 1.525016 -51.221555)
			(xy 15.679156 -51.221555) (xy 15.679156 -51.140445) (xy 15.687106 -51.059726) (xy 15.702929 -50.980175)
			(xy 15.726474 -50.902559) (xy 15.757513 -50.827623) (xy 15.795748 -50.756091) (xy 15.84081 -50.688651)
			(xy 15.892265 -50.625952) (xy 15.949618 -50.568599) (xy 16.012317 -50.517144) (xy 16.079757 -50.472082)
			(xy 16.151289 -50.433847) (xy 16.226225 -50.402808) (xy 16.303841 -50.379263) (xy 16.383392 -50.36344)
			(xy 16.464111 -50.35549) (xy 16.545221 -50.35549) (xy 16.62594 -50.36344) (xy 16.705491 -50.379263)
			(xy 16.783107 -50.402808) (xy 16.858043 -50.433847) (xy 16.929575 -50.472082) (xy 16.997015 -50.517144)
			(xy 17.059714 -50.568599) (xy 17.117067 -50.625952) (xy 17.168522 -50.688651) (xy 17.213584 -50.756091)
			(xy 17.251819 -50.827623) (xy 17.282858 -50.902559) (xy 17.306403 -50.980175) (xy 17.322226 -51.059726)
			(xy 17.330176 -51.140445) (xy 17.330674 -51.181) (xy 17.330176 -51.221555) (xy 17.322226 -51.302274)
			(xy 17.306403 -51.381825) (xy 17.282858 -51.459441) (xy 17.251819 -51.534377) (xy 17.213584 -51.605909)
			(xy 17.168522 -51.673349) (xy 17.117067 -51.736048) (xy 17.059714 -51.793401) (xy 16.997015 -51.844856)
			(xy 16.929575 -51.889918) (xy 16.858043 -51.928153) (xy 16.783107 -51.959192) (xy 16.705491 -51.982737)
			(xy 16.62594 -51.99856) (xy 16.545221 -52.00651) (xy 16.464111 -52.00651) (xy 16.383392 -51.99856)
			(xy 16.303841 -51.982737) (xy 16.226225 -51.959192) (xy 16.151289 -51.928153) (xy 16.079757 -51.889918)
			(xy 16.012317 -51.844856) (xy 15.949618 -51.793401) (xy 15.892265 -51.736048) (xy 15.84081 -51.673349)
			(xy 15.795748 -51.605909) (xy 15.757513 -51.534377) (xy 15.726474 -51.459441) (xy 15.702929 -51.381825)
			(xy 15.687106 -51.302274) (xy 15.679156 -51.221555) (xy 1.525016 -51.221555) (xy 1.525016 -51.624992)
			(xy 13.138912 -51.624992) (xy 14.79042 -51.624992) (xy 14.79042 -53.277008) (xy 13.138912 -53.277008)
			(xy 13.138912 -51.624992) (xy 1.525016 -51.624992) (xy 1.525016 -53.721) (xy 5.5306 -53.721) (xy 5.534631 -53.591434)
			(xy 5.54671 -53.46237) (xy 5.566789 -53.334306) (xy 5.594791 -53.207739) (xy 5.630608 -53.083156)
			(xy 5.6741 -52.961042) (xy 5.7251 -52.841868) (xy 5.783411 -52.726095) (xy 5.848806 -52.614171) (xy 5.921033 -52.506529)
			(xy 5.999813 -52.403586) (xy 6.08484 -52.30574) (xy 6.175785 -52.213368) (xy 6.272297 -52.12683)
			(xy 6.374003 -52.046459) (xy 6.480509 -51.972567) (xy 6.591402 -51.905439) (xy 6.706254 -51.845335)
			(xy 6.824621 -51.792488) (xy 6.946044 -51.747101) (xy 7.070054 -51.709352) (xy 7.196171 -51.679385)
			(xy 7.323907 -51.657316) (xy 7.452768 -51.643232) (xy 7.582255 -51.637186) (xy 7.711868 -51.639202)
			(xy 7.841104 -51.649272) (xy 7.969465 -51.667357) (xy 8.096453 -51.693387) (xy 8.221577 -51.727262)
			(xy 8.344353 -51.76885) (xy 8.464306 -51.817991) (xy 8.580971 -51.874494) (xy 8.693899 -51.938141)
			(xy 8.802651 -52.008685) (xy 8.906807 -52.085854) (xy 9.005964 -52.169349) (xy 9.099738 -52.258847)
			(xy 9.187767 -52.354002) (xy 9.26971 -52.454445) (xy 9.345249 -52.559788) (xy 9.414094 -52.669624)
			(xy 9.475977 -52.783528) (xy 9.530658 -52.901058) (xy 9.577928 -53.021761) (xy 9.617601 -53.145169)
			(xy 9.649526 -53.270805) (xy 9.673578 -53.398182) (xy 9.689665 -53.526808) (xy 9.697724 -53.656186)
			(xy 9.698228 -53.721) (xy 9.697724 -53.785814) (xy 9.689665 -53.915192) (xy 9.673578 -54.043818)
			(xy 9.649526 -54.171195) (xy 9.617601 -54.296831) (xy 9.577928 -54.420239) (xy 9.530658 -54.540942)
			(xy 9.475977 -54.658472) (xy 9.414094 -54.772376) (xy 9.345249 -54.882212) (xy 9.26971 -54.987555)
			(xy 9.187767 -55.087998) (xy 9.099738 -55.183153) (xy 9.005964 -55.272651) (xy 8.906807 -55.356146)
			(xy 8.802651 -55.433315) (xy 8.693899 -55.503859) (xy 8.580971 -55.567506) (xy 8.464306 -55.624009)
			(xy 8.344353 -55.67315) (xy 8.221577 -55.714738) (xy 8.096453 -55.748613) (xy 7.969465 -55.774643)
			(xy 7.841104 -55.792728) (xy 7.711868 -55.802798) (xy 7.582255 -55.804814) (xy 7.452768 -55.798768)
			(xy 7.323907 -55.784684) (xy 7.196171 -55.762615) (xy 7.070054 -55.732648) (xy 6.946044 -55.694899)
			(xy 6.824621 -55.649512) (xy 6.706254 -55.596665) (xy 6.591402 -55.536561) (xy 6.480509 -55.469433)
			(xy 6.374003 -55.395541) (xy 6.272297 -55.31517) (xy 6.175785 -55.228632) (xy 6.08484 -55.13626)
			(xy 5.999813 -55.038414) (xy 5.921033 -54.935471) (xy 5.848806 -54.827829) (xy 5.783411 -54.715905)
			(xy 5.7251 -54.600132) (xy 5.6741 -54.480958) (xy 5.630608 -54.358844) (xy 5.594791 -54.234261) (xy 5.566789 -54.107694)
			(xy 5.54671 -53.97963) (xy 5.534631 -53.850566) (xy 5.5306 -53.721) (xy 1.525016 -53.721) (xy 1.525016 -60.833)
			(xy 5.5306 -60.833) (xy 5.534631 -60.703434) (xy 5.54671 -60.57437) (xy 5.566789 -60.446306) (xy 5.594791 -60.319739)
			(xy 5.630608 -60.195156) (xy 5.6741 -60.073042) (xy 5.7251 -59.953868) (xy 5.783411 -59.838095) (xy 5.848806 -59.726171)
			(xy 5.921033 -59.618529) (xy 5.999813 -59.515586) (xy 6.08484 -59.41774) (xy 6.175785 -59.325368)
			(xy 6.272297 -59.23883) (xy 6.374003 -59.158459) (xy 6.480509 -59.084567) (xy 6.591402 -59.017439)
			(xy 6.706254 -58.957335) (xy 6.824621 -58.904488) (xy 6.946044 -58.859101) (xy 7.070054 -58.821352)
			(xy 7.196171 -58.791385) (xy 7.323907 -58.769316) (xy 7.452768 -58.755232) (xy 7.582255 -58.749186)
			(xy 7.711868 -58.751202) (xy 7.841104 -58.761272) (xy 7.969465 -58.779357) (xy 8.096453 -58.805387)
			(xy 8.221577 -58.839262) (xy 8.344353 -58.88085) (xy 8.464306 -58.929991) (xy 8.580971 -58.986494)
			(xy 8.693899 -59.050141) (xy 8.802651 -59.120685) (xy 8.906807 -59.197854) (xy 9.005964 -59.281349)
			(xy 9.099738 -59.370847) (xy 9.187767 -59.466002) (xy 9.26971 -59.566445) (xy 9.345249 -59.671788)
			(xy 9.414094 -59.781624) (xy 9.475977 -59.895528) (xy 9.530658 -60.013058) (xy 9.577928 -60.133761)
			(xy 9.617601 -60.257169) (xy 9.649526 -60.382805) (xy 9.673578 -60.510182) (xy 9.689665 -60.638808)
			(xy 9.697724 -60.768186) (xy 9.698228 -60.833) (xy 9.697724 -60.897814) (xy 9.689665 -61.027192)
			(xy 9.673578 -61.155818) (xy 9.649526 -61.283195) (xy 9.617601 -61.408831) (xy 9.577928 -61.532239)
			(xy 9.530658 -61.652942) (xy 9.475977 -61.770472) (xy 9.414094 -61.884376) (xy 9.345249 -61.994212)
			(xy 9.26971 -62.099555) (xy 9.233814 -62.143555) (xy 15.679156 -62.143555) (xy 15.679156 -62.062445)
			(xy 15.687106 -61.981726) (xy 15.702929 -61.902175) (xy 15.726474 -61.824559) (xy 15.757513 -61.749623)
			(xy 15.795748 -61.678091) (xy 15.84081 -61.610651) (xy 15.892265 -61.547952) (xy 15.949618 -61.490599)
			(xy 16.012317 -61.439144) (xy 16.079757 -61.394082) (xy 16.151289 -61.355847) (xy 16.226225 -61.324808)
			(xy 16.303841 -61.301263) (xy 16.383392 -61.28544) (xy 16.464111 -61.27749) (xy 16.545221 -61.27749)
			(xy 16.62594 -61.28544) (xy 16.705491 -61.301263) (xy 16.783107 -61.324808) (xy 16.858043 -61.355847)
			(xy 16.929575 -61.394082) (xy 16.997015 -61.439144) (xy 17.059714 -61.490599) (xy 17.117067 -61.547952)
			(xy 17.168522 -61.610651) (xy 17.213584 -61.678091) (xy 17.251819 -61.749623) (xy 17.282858 -61.824559)
			(xy 17.306403 -61.902175) (xy 17.322226 -61.981726) (xy 17.330176 -62.062445) (xy 17.330674 -62.103)
			(xy 17.330176 -62.143555) (xy 17.322226 -62.224274) (xy 17.306403 -62.303825) (xy 17.282858 -62.381441)
			(xy 17.251819 -62.456377) (xy 17.213584 -62.527909) (xy 17.168522 -62.595349) (xy 17.117067 -62.658048)
			(xy 17.059714 -62.715401) (xy 16.997015 -62.766856) (xy 16.929575 -62.811918) (xy 16.858043 -62.850153)
			(xy 16.783107 -62.881192) (xy 16.705491 -62.904737) (xy 16.62594 -62.92056) (xy 16.545221 -62.92851)
			(xy 16.464111 -62.92851) (xy 16.383392 -62.92056) (xy 16.303841 -62.904737) (xy 16.226225 -62.881192)
			(xy 16.151289 -62.850153) (xy 16.079757 -62.811918) (xy 16.012317 -62.766856) (xy 15.949618 -62.715401)
			(xy 15.892265 -62.658048) (xy 15.84081 -62.595349) (xy 15.795748 -62.527909) (xy 15.757513 -62.456377)
			(xy 15.726474 -62.381441) (xy 15.702929 -62.303825) (xy 15.687106 -62.224274) (xy 15.679156 -62.143555)
			(xy 9.233814 -62.143555) (xy 9.187767 -62.199998) (xy 9.099738 -62.295153) (xy 9.005964 -62.384651)
			(xy 8.906807 -62.468146) (xy 8.802651 -62.545315) (xy 8.693899 -62.615859) (xy 8.580971 -62.679506)
			(xy 8.464306 -62.736009) (xy 8.344353 -62.78515) (xy 8.221577 -62.826738) (xy 8.096453 -62.860613)
			(xy 7.969465 -62.886643) (xy 7.841104 -62.904728) (xy 7.711868 -62.914798) (xy 7.582255 -62.916814)
			(xy 7.452768 -62.910768) (xy 7.323907 -62.896684) (xy 7.196171 -62.874615) (xy 7.070054 -62.844648)
			(xy 6.946044 -62.806899) (xy 6.824621 -62.761512) (xy 6.706254 -62.708665) (xy 6.591402 -62.648561)
			(xy 6.480509 -62.581433) (xy 6.374003 -62.507541) (xy 6.272297 -62.42717) (xy 6.175785 -62.340632)
			(xy 6.08484 -62.24826) (xy 5.999813 -62.150414) (xy 5.921033 -62.047471) (xy 5.848806 -61.939829)
			(xy 5.783411 -61.827905) (xy 5.7251 -61.712132) (xy 5.6741 -61.592958) (xy 5.630608 -61.470844) (xy 5.594791 -61.346261)
			(xy 5.566789 -61.219694) (xy 5.54671 -61.09163) (xy 5.534631 -60.962566) (xy 5.5306 -60.833) (xy 1.525016 -60.833)
			(xy 1.525016 -63.413555) (xy 13.139156 -63.413555) (xy 13.139156 -63.332445) (xy 13.147106 -63.251726)
			(xy 13.162929 -63.172175) (xy 13.186474 -63.094559) (xy 13.217513 -63.019623) (xy 13.255748 -62.948091)
			(xy 13.30081 -62.880651) (xy 13.352265 -62.817952) (xy 13.409618 -62.760599) (xy 13.472317 -62.709144)
			(xy 13.539757 -62.664082) (xy 13.611289 -62.625847) (xy 13.686225 -62.594808) (xy 13.763841 -62.571263)
			(xy 13.843392 -62.55544) (xy 13.924111 -62.54749) (xy 14.005221 -62.54749) (xy 14.08594 -62.55544)
			(xy 14.165491 -62.571263) (xy 14.243107 -62.594808) (xy 14.318043 -62.625847) (xy 14.389575 -62.664082)
			(xy 14.457015 -62.709144) (xy 14.519714 -62.760599) (xy 14.577067 -62.817952) (xy 14.628522 -62.880651)
			(xy 14.673584 -62.948091) (xy 14.711819 -63.019623) (xy 14.742858 -63.094559) (xy 14.766403 -63.172175)
			(xy 14.782226 -63.251726) (xy 14.790176 -63.332445) (xy 14.790674 -63.373) (xy 14.790176 -63.413555)
			(xy 14.782226 -63.494274) (xy 14.766403 -63.573825) (xy 14.742858 -63.651441) (xy 14.711819 -63.726377)
			(xy 14.673584 -63.797909) (xy 14.628522 -63.865349) (xy 14.577067 -63.928048) (xy 14.519714 -63.985401)
			(xy 14.457015 -64.036856) (xy 14.389575 -64.081918) (xy 14.318043 -64.120153) (xy 14.243107 -64.151192)
			(xy 14.165491 -64.174737) (xy 14.08594 -64.19056) (xy 14.005221 -64.19851) (xy 13.924111 -64.19851)
			(xy 13.843392 -64.19056) (xy 13.763841 -64.174737) (xy 13.686225 -64.151192) (xy 13.611289 -64.120153)
			(xy 13.539757 -64.081918) (xy 13.472317 -64.036856) (xy 13.409618 -63.985401) (xy 13.352265 -63.928048)
			(xy 13.30081 -63.865349) (xy 13.255748 -63.797909) (xy 13.217513 -63.726377) (xy 13.186474 -63.651441)
			(xy 13.162929 -63.573825) (xy 13.147106 -63.494274) (xy 13.139156 -63.413555) (xy 1.525016 -63.413555)
			(xy 1.525016 -64.683555) (xy 15.679156 -64.683555) (xy 15.679156 -64.602445) (xy 15.687106 -64.521726)
			(xy 15.702929 -64.442175) (xy 15.726474 -64.364559) (xy 15.757513 -64.289623) (xy 15.795748 -64.218091)
			(xy 15.84081 -64.150651) (xy 15.892265 -64.087952) (xy 15.949618 -64.030599) (xy 16.012317 -63.979144)
			(xy 16.079757 -63.934082) (xy 16.151289 -63.895847) (xy 16.226225 -63.864808) (xy 16.303841 -63.841263)
			(xy 16.383392 -63.82544) (xy 16.464111 -63.81749) (xy 16.545221 -63.81749) (xy 16.62594 -63.82544)
			(xy 16.705491 -63.841263) (xy 16.783107 -63.864808) (xy 16.858043 -63.895847) (xy 16.929575 -63.934082)
			(xy 16.997015 -63.979144) (xy 17.059714 -64.030599) (xy 17.117067 -64.087952) (xy 17.168522 -64.150651)
			(xy 17.213584 -64.218091) (xy 17.251819 -64.289623) (xy 17.282858 -64.364559) (xy 17.306403 -64.442175)
			(xy 17.322226 -64.521726) (xy 17.330176 -64.602445) (xy 17.330674 -64.643) (xy 17.330176 -64.683555)
			(xy 17.322226 -64.764274) (xy 17.306403 -64.843825) (xy 17.282858 -64.921441) (xy 17.251819 -64.996377)
			(xy 17.213584 -65.067909) (xy 17.168522 -65.135349) (xy 17.117067 -65.198048) (xy 17.059714 -65.255401)
			(xy 16.997015 -65.306856) (xy 16.929575 -65.351918) (xy 16.858043 -65.390153) (xy 16.783107 -65.421192)
			(xy 16.705491 -65.444737) (xy 16.62594 -65.46056) (xy 16.545221 -65.46851) (xy 16.464111 -65.46851)
			(xy 16.383392 -65.46056) (xy 16.303841 -65.444737) (xy 16.226225 -65.421192) (xy 16.151289 -65.390153)
			(xy 16.079757 -65.351918) (xy 16.012317 -65.306856) (xy 15.949618 -65.255401) (xy 15.892265 -65.198048)
			(xy 15.84081 -65.135349) (xy 15.795748 -65.067909) (xy 15.757513 -64.996377) (xy 15.726474 -64.921441)
			(xy 15.702929 -64.843825) (xy 15.687106 -64.764274) (xy 15.679156 -64.683555) (xy 1.525016 -64.683555)
			(xy 1.525016 -67.223555) (xy 15.679156 -67.223555) (xy 15.679156 -67.142445) (xy 15.687106 -67.061726)
			(xy 15.702929 -66.982175) (xy 15.726474 -66.904559) (xy 15.757513 -66.829623) (xy 15.795748 -66.758091)
			(xy 15.84081 -66.690651) (xy 15.892265 -66.627952) (xy 15.949618 -66.570599) (xy 16.012317 -66.519144)
			(xy 16.079757 -66.474082) (xy 16.151289 -66.435847) (xy 16.226225 -66.404808) (xy 16.303841 -66.381263)
			(xy 16.383392 -66.36544) (xy 16.464111 -66.35749) (xy 16.545221 -66.35749) (xy 16.62594 -66.36544)
			(xy 16.705491 -66.381263) (xy 16.783107 -66.404808) (xy 16.858043 -66.435847) (xy 16.929575 -66.474082)
			(xy 16.997015 -66.519144) (xy 17.059714 -66.570599) (xy 17.117067 -66.627952) (xy 17.168522 -66.690651)
			(xy 17.213584 -66.758091) (xy 17.251819 -66.829623) (xy 17.282858 -66.904559) (xy 17.306403 -66.982175)
			(xy 17.322226 -67.061726) (xy 17.330176 -67.142445) (xy 17.330674 -67.183) (xy 17.330176 -67.223555)
			(xy 17.322226 -67.304274) (xy 17.306403 -67.383825) (xy 17.282858 -67.461441) (xy 17.251819 -67.536377)
			(xy 17.213584 -67.607909) (xy 17.168522 -67.675349) (xy 17.117067 -67.738048) (xy 17.059714 -67.795401)
			(xy 16.997015 -67.846856) (xy 16.929575 -67.891918) (xy 16.858043 -67.930153) (xy 16.783107 -67.961192)
			(xy 16.705491 -67.984737) (xy 16.62594 -68.00056) (xy 16.545221 -68.00851) (xy 16.464111 -68.00851)
			(xy 16.383392 -68.00056) (xy 16.303841 -67.984737) (xy 16.226225 -67.961192) (xy 16.151289 -67.930153)
			(xy 16.079757 -67.891918) (xy 16.012317 -67.846856) (xy 15.949618 -67.795401) (xy 15.892265 -67.738048)
			(xy 15.84081 -67.675349) (xy 15.795748 -67.607909) (xy 15.757513 -67.536377) (xy 15.726474 -67.461441)
			(xy 15.702929 -67.383825) (xy 15.687106 -67.304274) (xy 15.679156 -67.223555) (xy 1.525016 -67.223555)
			(xy 1.525016 -68.493555) (xy 13.139156 -68.493555) (xy 13.139156 -68.412445) (xy 13.147106 -68.331726)
			(xy 13.162929 -68.252175) (xy 13.186474 -68.174559) (xy 13.217513 -68.099623) (xy 13.255748 -68.028091)
			(xy 13.30081 -67.960651) (xy 13.352265 -67.897952) (xy 13.409618 -67.840599) (xy 13.472317 -67.789144)
			(xy 13.539757 -67.744082) (xy 13.611289 -67.705847) (xy 13.686225 -67.674808) (xy 13.763841 -67.651263)
			(xy 13.843392 -67.63544) (xy 13.924111 -67.62749) (xy 14.005221 -67.62749) (xy 14.08594 -67.63544)
			(xy 14.165491 -67.651263) (xy 14.243107 -67.674808) (xy 14.318043 -67.705847) (xy 14.389575 -67.744082)
			(xy 14.457015 -67.789144) (xy 14.519714 -67.840599) (xy 14.577067 -67.897952) (xy 14.628522 -67.960651)
			(xy 14.673584 -68.028091) (xy 14.711819 -68.099623) (xy 14.742858 -68.174559) (xy 14.766403 -68.252175)
			(xy 14.782226 -68.331726) (xy 14.790176 -68.412445) (xy 14.790674 -68.453) (xy 14.790176 -68.493555)
			(xy 14.782226 -68.574274) (xy 14.766403 -68.653825) (xy 14.742858 -68.731441) (xy 14.711819 -68.806377)
			(xy 14.673584 -68.877909) (xy 14.628522 -68.945349) (xy 14.577067 -69.008048) (xy 14.519714 -69.065401)
			(xy 14.457015 -69.116856) (xy 14.389575 -69.161918) (xy 14.318043 -69.200153) (xy 14.243107 -69.231192)
			(xy 14.165491 -69.254737) (xy 14.08594 -69.27056) (xy 14.005221 -69.27851) (xy 13.924111 -69.27851)
			(xy 13.843392 -69.27056) (xy 13.763841 -69.254737) (xy 13.686225 -69.231192) (xy 13.611289 -69.200153)
			(xy 13.539757 -69.161918) (xy 13.472317 -69.116856) (xy 13.409618 -69.065401) (xy 13.352265 -69.008048)
			(xy 13.30081 -68.945349) (xy 13.255748 -68.877909) (xy 13.217513 -68.806377) (xy 13.186474 -68.731441)
			(xy 13.162929 -68.653825) (xy 13.147106 -68.574274) (xy 13.139156 -68.493555) (xy 1.525016 -68.493555)
			(xy 1.525016 -69.763555) (xy 15.679156 -69.763555) (xy 15.679156 -69.682445) (xy 15.687106 -69.601726)
			(xy 15.702929 -69.522175) (xy 15.726474 -69.444559) (xy 15.757513 -69.369623) (xy 15.795748 -69.298091)
			(xy 15.84081 -69.230651) (xy 15.892265 -69.167952) (xy 15.949618 -69.110599) (xy 16.012317 -69.059144)
			(xy 16.079757 -69.014082) (xy 16.151289 -68.975847) (xy 16.226225 -68.944808) (xy 16.303841 -68.921263)
			(xy 16.383392 -68.90544) (xy 16.464111 -68.89749) (xy 16.545221 -68.89749) (xy 16.62594 -68.90544)
			(xy 16.705491 -68.921263) (xy 16.783107 -68.944808) (xy 16.858043 -68.975847) (xy 16.929575 -69.014082)
			(xy 16.997015 -69.059144) (xy 17.059714 -69.110599) (xy 17.117067 -69.167952) (xy 17.168522 -69.230651)
			(xy 17.213584 -69.298091) (xy 17.251819 -69.369623) (xy 17.282858 -69.444559) (xy 17.306403 -69.522175)
			(xy 17.322226 -69.601726) (xy 17.330176 -69.682445) (xy 17.330674 -69.723) (xy 17.330176 -69.763555)
			(xy 17.322226 -69.844274) (xy 17.306403 -69.923825) (xy 17.282858 -70.001441) (xy 17.251819 -70.076377)
			(xy 17.213584 -70.147909) (xy 17.168522 -70.215349) (xy 17.117067 -70.278048) (xy 17.059714 -70.335401)
			(xy 16.997015 -70.386856) (xy 16.929575 -70.431918) (xy 16.858043 -70.470153) (xy 16.783107 -70.501192)
			(xy 16.705491 -70.524737) (xy 16.62594 -70.54056) (xy 16.545221 -70.54851) (xy 16.464111 -70.54851)
			(xy 16.383392 -70.54056) (xy 16.303841 -70.524737) (xy 16.226225 -70.501192) (xy 16.151289 -70.470153)
			(xy 16.079757 -70.431918) (xy 16.012317 -70.386856) (xy 15.949618 -70.335401) (xy 15.892265 -70.278048)
			(xy 15.84081 -70.215349) (xy 15.795748 -70.147909) (xy 15.757513 -70.076377) (xy 15.726474 -70.001441)
			(xy 15.702929 -69.923825) (xy 15.687106 -69.844274) (xy 15.679156 -69.763555) (xy 1.525016 -69.763555)
			(xy 1.525016 -70.166992) (xy 13.138912 -70.166992) (xy 14.79042 -70.166992) (xy 14.79042 -71.819008)
			(xy 13.138912 -71.819008) (xy 13.138912 -70.166992) (xy 1.525016 -70.166992) (xy 1.525016 -72.263)
			(xy 5.5306 -72.263) (xy 5.534631 -72.133434) (xy 5.54671 -72.00437) (xy 5.566789 -71.876306) (xy 5.594791 -71.749739)
			(xy 5.630608 -71.625156) (xy 5.6741 -71.503042) (xy 5.7251 -71.383868) (xy 5.783411 -71.268095) (xy 5.848806 -71.156171)
			(xy 5.921033 -71.048529) (xy 5.999813 -70.945586) (xy 6.08484 -70.84774) (xy 6.175785 -70.755368)
			(xy 6.272297 -70.66883) (xy 6.374003 -70.588459) (xy 6.480509 -70.514567) (xy 6.591402 -70.447439)
			(xy 6.706254 -70.387335) (xy 6.824621 -70.334488) (xy 6.946044 -70.289101) (xy 7.070054 -70.251352)
			(xy 7.196171 -70.221385) (xy 7.323907 -70.199316) (xy 7.452768 -70.185232) (xy 7.582255 -70.179186)
			(xy 7.711868 -70.181202) (xy 7.841104 -70.191272) (xy 7.969465 -70.209357) (xy 8.096453 -70.235387)
			(xy 8.221577 -70.269262) (xy 8.344353 -70.31085) (xy 8.464306 -70.359991) (xy 8.580971 -70.416494)
			(xy 8.693899 -70.480141) (xy 8.802651 -70.550685) (xy 8.906807 -70.627854) (xy 9.005964 -70.711349)
			(xy 9.099738 -70.800847) (xy 9.187767 -70.896002) (xy 9.26971 -70.996445) (xy 9.345249 -71.101788)
			(xy 9.414094 -71.211624) (xy 9.475977 -71.325528) (xy 9.530658 -71.443058) (xy 9.577928 -71.563761)
			(xy 9.617601 -71.687169) (xy 9.649526 -71.812805) (xy 9.673578 -71.940182) (xy 9.689665 -72.068808)
			(xy 9.697724 -72.198186) (xy 9.698228 -72.263) (xy 9.697724 -72.327814) (xy 9.689665 -72.457192)
			(xy 9.673578 -72.585818) (xy 9.649526 -72.713195) (xy 9.617601 -72.838831) (xy 9.577928 -72.962239)
			(xy 9.530658 -73.082942) (xy 9.475977 -73.200472) (xy 9.414094 -73.314376) (xy 9.345249 -73.424212)
			(xy 9.26971 -73.529555) (xy 9.187767 -73.629998) (xy 9.099738 -73.725153) (xy 9.005964 -73.814651)
			(xy 8.906807 -73.898146) (xy 8.802651 -73.975315) (xy 8.693899 -74.045859) (xy 8.580971 -74.109506)
			(xy 8.464306 -74.166009) (xy 8.344353 -74.21515) (xy 8.221577 -74.256738) (xy 8.096453 -74.290613)
			(xy 7.969465 -74.316643) (xy 7.841104 -74.334728) (xy 7.711868 -74.344798) (xy 7.582255 -74.346814)
			(xy 7.452768 -74.340768) (xy 7.323907 -74.326684) (xy 7.196171 -74.304615) (xy 7.070054 -74.274648)
			(xy 6.946044 -74.236899) (xy 6.824621 -74.191512) (xy 6.706254 -74.138665) (xy 6.591402 -74.078561)
			(xy 6.480509 -74.011433) (xy 6.374003 -73.937541) (xy 6.272297 -73.85717) (xy 6.175785 -73.770632)
			(xy 6.08484 -73.67826) (xy 5.999813 -73.580414) (xy 5.921033 -73.477471) (xy 5.848806 -73.369829)
			(xy 5.783411 -73.257905) (xy 5.7251 -73.142132) (xy 5.6741 -73.022958) (xy 5.630608 -72.900844) (xy 5.594791 -72.776261)
			(xy 5.566789 -72.649694) (xy 5.54671 -72.52163) (xy 5.534631 -72.392566) (xy 5.5306 -72.263) (xy 1.525016 -72.263)
			(xy 1.525016 -77.476858) (xy 6.601727 -77.476858) (xy 6.605682 -77.385021) (xy 6.617517 -77.293864)
			(xy 6.637144 -77.204061) (xy 6.664418 -77.116279) (xy 6.699138 -77.031165) (xy 6.741046 -76.949352)
			(xy 6.789832 -76.871444) (xy 6.845135 -76.798019) (xy 6.906545 -76.729619) (xy 6.973607 -76.666752)
			(xy 7.045826 -76.609882) (xy 7.122666 -76.559431) (xy 7.203559 -76.515772) (xy 7.287905 -76.479229)
			(xy 7.375081 -76.450072) (xy 7.46444 -76.428518) (xy 7.555321 -76.414724) (xy 7.647052 -76.408794)
			(xy 7.738953 -76.410772) (xy 7.830344 -76.420643) (xy 7.920548 -76.438333) (xy 8.008897 -76.463713)
			(xy 8.094737 -76.496593) (xy 8.177433 -76.536731) (xy 8.256373 -76.58383) (xy 8.330971 -76.63754)
			(xy 8.400677 -76.697464) (xy 8.464972 -76.763158) (xy 8.523383 -76.834136) (xy 8.575475 -76.909873)
			(xy 8.620864 -76.989808) (xy 8.659214 -77.073348) (xy 8.690239 -77.159876) (xy 8.713712 -77.248751)
			(xy 8.729458 -77.339315) (xy 8.73736 -77.430897) (xy 8.737854 -77.476858) (xy 8.73736 -77.522819)
			(xy 8.729458 -77.614401) (xy 8.713712 -77.704965) (xy 8.690239 -77.79384) (xy 8.659214 -77.880368)
			(xy 8.620864 -77.963908) (xy 8.575475 -78.043843) (xy 8.523383 -78.11958) (xy 8.464972 -78.190558)
			(xy 8.400677 -78.256252) (xy 8.330971 -78.316176) (xy 8.256373 -78.369886) (xy 8.177433 -78.416985)
			(xy 8.094737 -78.457123) (xy 8.008897 -78.490003) (xy 7.920548 -78.515383) (xy 7.830344 -78.533073)
			(xy 7.738953 -78.542944) (xy 7.647052 -78.544922) (xy 7.555321 -78.538992) (xy 7.46444 -78.525198)
			(xy 7.375081 -78.503644) (xy 7.287905 -78.474487) (xy 7.203559 -78.437944) (xy 7.122666 -78.394285)
			(xy 7.045826 -78.343834) (xy 6.973607 -78.286964) (xy 6.906545 -78.224097) (xy 6.845135 -78.155697)
			(xy 6.789832 -78.082272) (xy 6.741046 -78.004364) (xy 6.699138 -77.922551) (xy 6.664418 -77.837437)
			(xy 6.637144 -77.749655) (xy 6.617517 -77.659852) (xy 6.605682 -77.568695) (xy 6.601727 -77.476858)
			(xy 1.525016 -77.476858) (xy 1.525016 -83.519709) (xy 4.782807 -83.519709) (xy 4.782807 -83.433983)
			(xy 4.790717 -83.348623) (xy 4.806469 -83.264356) (xy 4.829929 -83.181903) (xy 4.860897 -83.101966)
			(xy 4.899108 -83.025227) (xy 4.944237 -82.952341) (xy 4.995898 -82.88393) (xy 5.053652 -82.820578)
			(xy 5.117004 -82.762824) (xy 5.185415 -82.711163) (xy 5.258301 -82.666034) (xy 5.33504 -82.627823)
			(xy 5.414977 -82.596855) (xy 5.49743 -82.573395) (xy 5.581697 -82.557643) (xy 5.667057 -82.549733)
			(xy 5.752783 -82.549733) (xy 5.838143 -82.557643) (xy 5.92241 -82.573395) (xy 6.004863 -82.596855)
			(xy 6.0848 -82.627823) (xy 6.161539 -82.666034) (xy 6.234425 -82.711163) (xy 6.302836 -82.762824)
			(xy 6.366188 -82.820578) (xy 6.423942 -82.88393) (xy 6.475603 -82.952341) (xy 6.520732 -83.025227)
			(xy 6.558943 -83.101966) (xy 6.589911 -83.181903) (xy 6.613371 -83.264356) (xy 6.629123 -83.348623)
			(xy 6.637033 -83.433983) (xy 6.637528 -83.476846) (xy 6.637033 -83.519709) (xy 6.629123 -83.605069)
			(xy 6.613371 -83.689336) (xy 6.589911 -83.771789) (xy 6.558943 -83.851726) (xy 6.520732 -83.928465)
			(xy 6.475603 -84.001351) (xy 6.423942 -84.069762) (xy 6.366188 -84.133114) (xy 6.302836 -84.190868)
			(xy 6.234425 -84.242529) (xy 6.161539 -84.287658) (xy 6.0848 -84.325869) (xy 6.004863 -84.356837)
			(xy 5.92241 -84.380297) (xy 5.838143 -84.396049) (xy 5.752783 -84.403959) (xy 5.667057 -84.403959)
			(xy 5.581697 -84.396049) (xy 5.49743 -84.380297) (xy 5.414977 -84.356837) (xy 5.33504 -84.325869)
			(xy 5.258301 -84.287658) (xy 5.185415 -84.242529) (xy 5.117004 -84.190868) (xy 5.053652 -84.133114)
			(xy 4.995898 -84.069762) (xy 4.944237 -84.001351) (xy 4.899108 -83.928465) (xy 4.860897 -83.851726)
			(xy 4.829929 -83.771789) (xy 4.806469 -83.689336) (xy 4.790717 -83.605069) (xy 4.782807 -83.519709)
			(xy 1.525016 -83.519709) (xy 1.525016 -89.476834) (xy 6.601727 -89.476834) (xy 6.605682 -89.384997)
			(xy 6.617517 -89.29384) (xy 6.637144 -89.204037) (xy 6.664418 -89.116255) (xy 6.699138 -89.031141)
			(xy 6.741046 -88.949328) (xy 6.789832 -88.87142) (xy 6.845135 -88.797995) (xy 6.906545 -88.729595)
			(xy 6.973607 -88.666728) (xy 7.045826 -88.609858) (xy 7.122666 -88.559407) (xy 7.203559 -88.515748)
			(xy 7.287905 -88.479205) (xy 7.375081 -88.450048) (xy 7.46444 -88.428494) (xy 7.555321 -88.4147)
			(xy 7.647052 -88.40877) (xy 7.738953 -88.410748) (xy 7.830344 -88.420619) (xy 7.920548 -88.438309)
			(xy 8.008897 -88.463689) (xy 8.094737 -88.496569) (xy 8.177433 -88.536707) (xy 8.256373 -88.583806)
			(xy 8.330971 -88.637516) (xy 8.400677 -88.69744) (xy 8.464972 -88.763134) (xy 8.523383 -88.834112)
			(xy 8.575475 -88.909849) (xy 8.620864 -88.989784) (xy 8.659214 -89.073324) (xy 8.690239 -89.159852)
			(xy 8.713712 -89.248727) (xy 8.729458 -89.339291) (xy 8.73736 -89.430873) (xy 8.737854 -89.476834)
			(xy 8.73736 -89.522795) (xy 8.729458 -89.614377) (xy 8.713712 -89.704941) (xy 8.690239 -89.793816)
			(xy 8.659214 -89.880344) (xy 8.620864 -89.963884) (xy 8.575475 -90.043819) (xy 8.523383 -90.119556)
			(xy 8.464972 -90.190534) (xy 8.400677 -90.256228) (xy 8.330971 -90.316152) (xy 8.256373 -90.369862)
			(xy 8.177433 -90.416961) (xy 8.094737 -90.457099) (xy 8.008897 -90.489979) (xy 7.920548 -90.515359)
			(xy 7.830344 -90.533049) (xy 7.738953 -90.54292) (xy 7.647052 -90.544898) (xy 7.555321 -90.538968)
			(xy 7.46444 -90.525174) (xy 7.375081 -90.50362) (xy 7.287905 -90.474463) (xy 7.203559 -90.43792)
			(xy 7.122666 -90.394261) (xy 7.045826 -90.34381) (xy 6.973607 -90.28694) (xy 6.906545 -90.224073)
			(xy 6.845135 -90.155673) (xy 6.789832 -90.082248) (xy 6.741046 -90.00434) (xy 6.699138 -89.922527)
			(xy 6.664418 -89.837413) (xy 6.637144 -89.749631) (xy 6.617517 -89.659828) (xy 6.605682 -89.568671)
			(xy 6.601727 -89.476834) (xy 1.525016 -89.476834) (xy 1.525016 -95.377) (xy 5.5306 -95.377) (xy 5.534631 -95.247434)
			(xy 5.54671 -95.11837) (xy 5.566789 -94.990306) (xy 5.594791 -94.863739) (xy 5.630608 -94.739156)
			(xy 5.6741 -94.617042) (xy 5.7251 -94.497868) (xy 5.783411 -94.382095) (xy 5.848806 -94.270171) (xy 5.921033 -94.162529)
			(xy 5.999813 -94.059586) (xy 6.08484 -93.96174) (xy 6.175785 -93.869368) (xy 6.272297 -93.78283)
			(xy 6.374003 -93.702459) (xy 6.480509 -93.628567) (xy 6.591402 -93.561439) (xy 6.706254 -93.501335)
			(xy 6.824621 -93.448488) (xy 6.946044 -93.403101) (xy 7.070054 -93.365352) (xy 7.196171 -93.335385)
			(xy 7.323907 -93.313316) (xy 7.452768 -93.299232) (xy 7.582255 -93.293186) (xy 7.711868 -93.295202)
			(xy 7.841104 -93.305272) (xy 7.969465 -93.323357) (xy 8.096453 -93.349387) (xy 8.221577 -93.383262)
			(xy 8.344353 -93.42485) (xy 8.464306 -93.473991) (xy 8.580971 -93.530494) (xy 8.693899 -93.594141)
			(xy 8.802651 -93.664685) (xy 8.906807 -93.741854) (xy 9.005964 -93.825349) (xy 9.099738 -93.914847)
			(xy 9.187767 -94.010002) (xy 9.26971 -94.110445) (xy 9.345249 -94.215788) (xy 9.414094 -94.325624)
			(xy 9.475977 -94.439528) (xy 9.530658 -94.557058) (xy 9.577928 -94.677761) (xy 9.617601 -94.801169)
			(xy 9.649526 -94.926805) (xy 9.673578 -95.054182) (xy 9.689665 -95.182808) (xy 9.697724 -95.312186)
			(xy 9.698228 -95.377) (xy 9.697724 -95.441814) (xy 9.689665 -95.571192) (xy 9.673578 -95.699818)
			(xy 9.649526 -95.827195) (xy 9.617601 -95.952831) (xy 9.577928 -96.076239) (xy 9.530658 -96.196942)
			(xy 9.475977 -96.314472) (xy 9.414094 -96.428376) (xy 9.345249 -96.538212) (xy 9.26971 -96.643555)
			(xy 9.187767 -96.743998) (xy 9.099738 -96.839153) (xy 9.005964 -96.928651) (xy 8.906807 -97.012146)
			(xy 8.802651 -97.089315) (xy 8.693899 -97.159859) (xy 8.580971 -97.223506) (xy 8.464306 -97.280009)
			(xy 8.344353 -97.32915) (xy 8.221577 -97.370738) (xy 8.096453 -97.404613) (xy 7.969465 -97.430643)
			(xy 7.841104 -97.448728) (xy 7.711868 -97.458798) (xy 7.582255 -97.460814) (xy 7.452768 -97.454768)
			(xy 7.323907 -97.440684) (xy 7.196171 -97.418615) (xy 7.070054 -97.388648) (xy 6.946044 -97.350899)
			(xy 6.824621 -97.305512) (xy 6.706254 -97.252665) (xy 6.591402 -97.192561) (xy 6.480509 -97.125433)
			(xy 6.374003 -97.051541) (xy 6.272297 -96.97117) (xy 6.175785 -96.884632) (xy 6.08484 -96.79226)
			(xy 5.999813 -96.694414) (xy 5.921033 -96.591471) (xy 5.848806 -96.483829) (xy 5.783411 -96.371905)
			(xy 5.7251 -96.256132) (xy 5.6741 -96.136958) (xy 5.630608 -96.014844) (xy 5.594791 -95.890261) (xy 5.566789 -95.763694)
			(xy 5.54671 -95.63563) (xy 5.534631 -95.506566) (xy 5.5306 -95.377) (xy 1.525016 -95.377) (xy 1.525016 -106.807)
			(xy 5.5306 -106.807) (xy 5.534631 -106.677434) (xy 5.54671 -106.54837) (xy 5.566789 -106.420306)
			(xy 5.594791 -106.293739) (xy 5.630608 -106.169156) (xy 5.6741 -106.047042) (xy 5.7251 -105.927868)
			(xy 5.783411 -105.812095) (xy 5.848806 -105.700171) (xy 5.921033 -105.592529) (xy 5.999813 -105.489586)
			(xy 6.08484 -105.39174) (xy 6.175785 -105.299368) (xy 6.272297 -105.21283) (xy 6.374003 -105.132459)
			(xy 6.480509 -105.058567) (xy 6.591402 -104.991439) (xy 6.706254 -104.931335) (xy 6.824621 -104.878488)
			(xy 6.946044 -104.833101) (xy 7.070054 -104.795352) (xy 7.196171 -104.765385) (xy 7.323907 -104.743316)
			(xy 7.452768 -104.729232) (xy 7.582255 -104.723186) (xy 7.711868 -104.725202) (xy 7.841104 -104.735272)
			(xy 7.969465 -104.753357) (xy 8.096453 -104.779387) (xy 8.221577 -104.813262) (xy 8.344353 -104.85485)
			(xy 8.464306 -104.903991) (xy 8.580971 -104.960494) (xy 8.693899 -105.024141) (xy 8.802651 -105.094685)
			(xy 8.906807 -105.171854) (xy 9.005964 -105.255349) (xy 9.099738 -105.344847) (xy 9.187767 -105.440002)
			(xy 9.26971 -105.540445) (xy 9.345249 -105.645788) (xy 9.414094 -105.755624) (xy 9.475977 -105.869528)
			(xy 9.530658 -105.987058) (xy 9.577928 -106.107761) (xy 9.617601 -106.231169) (xy 9.649526 -106.356805)
			(xy 9.673578 -106.484182) (xy 9.689665 -106.612808) (xy 9.697724 -106.742186) (xy 9.698228 -106.807)
			(xy 9.697724 -106.871814) (xy 9.689665 -107.001192) (xy 9.673578 -107.129818) (xy 9.649526 -107.257195)
			(xy 9.617601 -107.382831) (xy 9.577928 -107.506239) (xy 9.530658 -107.626942) (xy 9.475977 -107.744472)
			(xy 9.414094 -107.858376) (xy 9.345249 -107.968212) (xy 9.26971 -108.073555) (xy 9.187767 -108.173998)
			(xy 9.099738 -108.269153) (xy 9.005964 -108.358651) (xy 8.906807 -108.442146) (xy 8.802651 -108.519315)
			(xy 8.693899 -108.589859) (xy 8.580971 -108.653506) (xy 8.464306 -108.710009) (xy 8.344353 -108.75915)
			(xy 8.221577 -108.800738) (xy 8.096453 -108.834613) (xy 7.969465 -108.860643) (xy 7.841104 -108.878728)
			(xy 7.711868 -108.888798) (xy 7.582255 -108.890814) (xy 7.452768 -108.884768) (xy 7.323907 -108.870684)
			(xy 7.196171 -108.848615) (xy 7.070054 -108.818648) (xy 6.946044 -108.780899) (xy 6.824621 -108.735512)
			(xy 6.706254 -108.682665) (xy 6.591402 -108.622561) (xy 6.480509 -108.555433) (xy 6.374003 -108.481541)
			(xy 6.272297 -108.40117) (xy 6.175785 -108.314632) (xy 6.08484 -108.22226) (xy 5.999813 -108.124414)
			(xy 5.921033 -108.021471) (xy 5.848806 -107.913829) (xy 5.783411 -107.801905) (xy 5.7251 -107.686132)
			(xy 5.6741 -107.566958) (xy 5.630608 -107.444844) (xy 5.594791 -107.320261) (xy 5.566789 -107.193694)
			(xy 5.54671 -107.06563) (xy 5.534631 -106.936566) (xy 5.5306 -106.807) (xy 1.525016 -106.807) (xy 1.525016 -125.600206)
			(xy 2.008886 -126.084076) (xy 9.600438 -126.084076) (xy 10.157714 -125.5268) (xy 10.157714 -124.57811)
			(xy 6.410452 -120.830848) (xy 6.410452 -120.691656) (xy 6.387592 -120.668542) (xy 6.387592 -113.943638)
			(xy 6.392418 -113.938558) (xy 6.401308 -113.929668) (xy 7.115302 -113.208054) (xy 10.52322 -109.800898)
			(xy 10.534567 -109.788749) (xy 10.55115 -109.759952) (xy 10.559738 -109.727851) (xy 10.560304 -109.711236)
			(xy 10.560304 -100.256086) (xy 11.395964 -99.420426) (xy 11.395964 -97.766886) (xy 11.570462 -97.592134)
			(xy 11.743182 -97.419414) (xy 11.743182 -97.26549) (xy 12.951968 -96.056704) (xy 13.105892 -96.056704)
			(xy 13.11275 -96.0501) (xy 15.933928 -96.0501) (xy 15.964416 -96.021675) (xy 16.030167 -95.970434)
			(xy 16.100744 -95.926073) (xy 16.175428 -95.889045) (xy 16.253462 -95.859724) (xy 16.334051 -95.83841)
			(xy 16.416376 -95.825319) (xy 16.499602 -95.820583) (xy 16.582881 -95.824252) (xy 16.665368 -95.836287)
			(xy 16.746223 -95.856567) (xy 16.78559 -95.870268) (xy 16.824296 -95.884799) (xy 16.898855 -95.920534)
			(xy 16.969477 -95.96353) (xy 17.035457 -96.013357) (xy 17.096137 -96.069519) (xy 17.123918 -96.100138)
			(xy 17.150883 -96.131428) (xy 17.199113 -96.198494) (xy 17.240408 -96.270038) (xy 17.274357 -96.345346)
			(xy 17.30062 -96.423666) (xy 17.318936 -96.504217) (xy 17.32912 -96.586193) (xy 17.331073 -96.668776)
			(xy 17.324774 -96.751142) (xy 17.310286 -96.832468) (xy 17.287753 -96.911942) (xy 17.273016 -96.95053)
			(xy 17.259046 -96.985836) (xy 17.27454 -97.060258) (xy 17.838928 -97.624646) (xy 17.838928 -98.216974)
			(xy 17.890236 -98.268536) (xy 17.890236 -100.883212) (xy 17.838928 -100.934774) (xy 17.838928 -102.997)
			(xy 17.879922 -103.040784) (xy 17.956781 -103.132884) (xy 18.027483 -103.229789) (xy 18.091731 -103.331089)
			(xy 18.149251 -103.436354) (xy 18.1998 -103.54514) (xy 18.243164 -103.656984) (xy 18.279158 -103.771412)
			(xy 18.307631 -103.88794) (xy 18.328461 -104.006074) (xy 18.34156 -104.125313) (xy 18.346873 -104.245151)
			(xy 18.344377 -104.365081) (xy 18.334083 -104.484595) (xy 18.316035 -104.603185) (xy 18.290308 -104.72035)
			(xy 18.257012 -104.835593) (xy 18.216289 -104.948425) (xy 18.16831 -105.058368) (xy 18.113279 -105.164956)
			(xy 18.051429 -105.267738) (xy 17.983023 -105.366277) (xy 17.90835 -105.460157) (xy 17.827726 -105.548979)
			(xy 17.741494 -105.632367) (xy 17.650019 -105.709967) (xy 17.553689 -105.781451) (xy 17.452912 -105.846515)
			(xy 17.348114 -105.904885) (xy 17.239741 -105.956311) (xy 17.128251 -106.000578) (xy 17.014118 -106.037496)
			(xy 16.897823 -106.066909) (xy 16.83893 -106.078274) (xy 16.824531 -106.081352) (xy 16.80455 -106.090123)
			(xy 23.296903 -106.090123) (xy 23.303161 -106.03449) (xy 23.317481 -105.980369) (xy 23.339556 -105.928921)
			(xy 23.368912 -105.881252) (xy 23.404919 -105.838384) (xy 23.446803 -105.801237) (xy 23.493666 -105.77061)
			(xy 23.544502 -105.74716) (xy 23.598219 -105.73139) (xy 23.653663 -105.723639) (xy 23.709645 -105.724073)
			(xy 23.764962 -105.732683) (xy 23.818428 -105.749284) (xy 23.868894 -105.773519) (xy 23.915277 -105.804869)
			(xy 23.95658 -105.84266) (xy 23.991918 -105.886082) (xy 24.020531 -105.9342) (xy 24.041806 -105.985984)
			(xy 24.055285 -106.040321) (xy 24.06068 -106.096044) (xy 24.057874 -106.151957) (xy 24.046927 -106.20686)
			(xy 24.028075 -106.259574) (xy 24.001722 -106.308967) (xy 23.985474 -106.331766) (xy 23.972027 -106.350969)
			(xy 23.951534 -106.393123) (xy 23.939123 -106.43832) (xy 23.935214 -106.485028) (xy 23.93994 -106.53166)
			(xy 23.953141 -106.576633) (xy 23.974369 -106.618421) (xy 24.002903 -106.655606) (xy 24.037775 -106.686924)
			(xy 24.077801 -106.711313) (xy 24.09952 -106.720132) (xy 24.125536 -106.730475) (xy 24.174412 -106.757783)
			(xy 24.218772 -106.79194) (xy 24.257665 -106.832213) (xy 24.290255 -106.877738) (xy 24.315843 -106.927535)
			(xy 24.333879 -106.980538) (xy 24.343976 -107.035607) (xy 24.345918 -107.09156) (xy 24.339663 -107.147197)
			(xy 24.325344 -107.201322) (xy 24.30327 -107.252774) (xy 24.273914 -107.300448) (xy 24.237907 -107.34332)
			(xy 24.196021 -107.38047) (xy 24.149156 -107.411101) (xy 24.098318 -107.434555) (xy 24.044599 -107.450328)
			(xy 23.989151 -107.458081) (xy 23.933166 -107.457649) (xy 23.877844 -107.44904) (xy 23.824375 -107.43244)
			(xy 23.773905 -107.408204) (xy 23.727519 -107.376854) (xy 23.686212 -107.339061) (xy 23.65087 -107.295638)
			(xy 23.622254 -107.247517) (xy 23.600977 -107.19573) (xy 23.587495 -107.141391) (xy 23.5821 -107.085664)
			(xy 23.584905 -107.029747) (xy 23.595851 -106.974841) (xy 23.614703 -106.922123) (xy 23.641057 -106.872726)
			(xy 23.657306 -106.849926) (xy 23.670771 -106.830734) (xy 23.691266 -106.788579) (xy 23.703678 -106.743378)
			(xy 23.707587 -106.696668) (xy 23.702859 -106.650034) (xy 23.689656 -106.605058) (xy 23.668425 -106.563268)
			(xy 23.639887 -106.526083) (xy 23.605011 -106.494765) (xy 23.564981 -106.470378) (xy 23.54326 -106.46156)
			(xy 23.517253 -106.451197) (xy 23.468382 -106.423888) (xy 23.424026 -106.38973) (xy 23.385138 -106.349458)
			(xy 23.352553 -106.303935) (xy 23.326969 -106.254139) (xy 23.308936 -106.201139) (xy 23.298842 -106.146073)
			(xy 23.296903 -106.090123) (xy 16.80455 -106.090123) (xy 16.797577 -106.093184) (xy 16.77406 -106.110888)
			(xy 16.755235 -106.133518) (xy 16.742109 -106.159866) (xy 16.735383 -106.188523) (xy 16.735044 -106.203242)
			(xy 16.735044 -109.874812) (xy 10.325354 -116.284502) (xy 10.325354 -118.100094) (xy 11.59841 -118.100094)
			(xy 11.602414 -117.899986) (xy 11.614422 -117.700198) (xy 11.634414 -117.50105) (xy 11.662357 -117.302862)
			(xy 11.698207 -117.105951) (xy 11.741908 -116.910631) (xy 11.793387 -116.717217) (xy 11.852564 -116.526017)
			(xy 11.919344 -116.337337) (xy 11.993619 -116.151481) (xy 12.07527 -115.968745) (xy 12.164168 -115.789422)
			(xy 12.260168 -115.6138) (xy 12.363119 -115.442159) (xy 12.472854 -115.274775) (xy 12.589199 -115.111915)
			(xy 12.711966 -114.95384) (xy 12.840959 -114.800804) (xy 12.975972 -114.653052) (xy 13.116789 -114.510819)
			(xy 13.263183 -114.374335) (xy 13.414921 -114.243816) (xy 13.57176 -114.119474) (xy 13.733447 -114.001506)
			(xy 13.899726 -113.890101) (xy 14.070328 -113.785439) (xy 14.244981 -113.687686) (xy 14.423405 -113.596999)
			(xy 14.605315 -113.513523) (xy 14.790419 -113.437392) (xy 14.978421 -113.368728) (xy 15.169019 -113.307641)
			(xy 15.361909 -113.254229) (xy 15.556781 -113.208577) (xy 15.753324 -113.170758) (xy 15.951223 -113.140834)
			(xy 16.15016 -113.11885) (xy 16.349818 -113.104844) (xy 16.549876 -113.098838) (xy 16.750015 -113.10084)
			(xy 16.949913 -113.110849) (xy 17.14925 -113.128847) (xy 17.347708 -113.154806) (xy 17.544968 -113.188684)
			(xy 17.740715 -113.230428) (xy 17.934635 -113.27997) (xy 18.126418 -113.337231) (xy 18.315756 -113.40212)
			(xy 18.502346 -113.474532) (xy 18.68589 -113.554351) (xy 18.866093 -113.64145) (xy 19.042667 -113.735688)
			(xy 19.215329 -113.836917) (xy 19.383803 -113.944972) (xy 19.547819 -114.059681) (xy 19.707114 -114.180861)
			(xy 19.861433 -114.308316) (xy 20.010529 -114.441845) (xy 20.154163 -114.581231) (xy 20.292105 -114.726253)
			(xy 20.424135 -114.876677) (xy 20.550041 -115.032264) (xy 20.66962 -115.192763) (xy 20.782683 -115.357918)
			(xy 20.889047 -115.527465) (xy 20.988543 -115.701131) (xy 21.08101 -115.878639) (xy 21.166302 -116.059705)
			(xy 21.244281 -116.244038) (xy 21.314822 -116.431343) (xy 21.377813 -116.621321) (xy 21.433152 -116.813667)
			(xy 21.480752 -117.008072) (xy 21.520535 -117.204227) (xy 21.552438 -117.401817) (xy 21.57641 -117.600524)
			(xy 21.592413 -117.800032) (xy 21.600421 -118.00002) (xy 21.600922 -118.100094) (xy 21.600421 -118.200168)
			(xy 21.592413 -118.400156) (xy 21.57641 -118.599664) (xy 21.552438 -118.798371) (xy 21.520535 -118.995961)
			(xy 21.480752 -119.192116) (xy 21.433152 -119.386521) (xy 21.377813 -119.578867) (xy 21.314822 -119.768845)
			(xy 21.244281 -119.95615) (xy 21.166302 -120.140483) (xy 21.08101 -120.321549) (xy 20.988543 -120.499057)
			(xy 20.889047 -120.672723) (xy 20.782683 -120.84227) (xy 20.66962 -121.007425) (xy 20.550041 -121.167924)
			(xy 20.424135 -121.323511) (xy 20.292105 -121.473935) (xy 20.154163 -121.618957) (xy 20.010529 -121.758343)
			(xy 19.861433 -121.891872) (xy 19.707114 -122.019327) (xy 19.547819 -122.140507) (xy 19.383803 -122.255216)
			(xy 19.215329 -122.363271) (xy 19.042667 -122.4645) (xy 18.866093 -122.558738) (xy 18.68589 -122.645837)
			(xy 18.502346 -122.725656) (xy 18.315756 -122.798068) (xy 18.126418 -122.862957) (xy 17.934635 -122.920218)
			(xy 17.740715 -122.96976) (xy 17.544968 -123.011504) (xy 17.347708 -123.045382) (xy 17.14925 -123.071341)
			(xy 16.949913 -123.089339) (xy 16.750015 -123.099348) (xy 16.549876 -123.10135) (xy 16.349818 -123.095344)
			(xy 16.15016 -123.081338) (xy 15.951223 -123.059354) (xy 15.753324 -123.02943) (xy 15.556781 -122.991611)
			(xy 15.361909 -122.945959) (xy 15.169019 -122.892547) (xy 14.978421 -122.83146) (xy 14.790419 -122.762796)
			(xy 14.605315 -122.686665) (xy 14.423405 -122.603189) (xy 14.244981 -122.512502) (xy 14.070328 -122.414749)
			(xy 13.899726 -122.310087) (xy 13.733447 -122.198682) (xy 13.57176 -122.080714) (xy 13.414921 -121.956372)
			(xy 13.263183 -121.825853) (xy 13.116789 -121.689369) (xy 12.975972 -121.547136) (xy 12.840959 -121.399384)
			(xy 12.711966 -121.246348) (xy 12.589199 -121.088273) (xy 12.472854 -120.925413) (xy 12.363119 -120.758029)
			(xy 12.260168 -120.586388) (xy 12.164168 -120.410766) (xy 12.07527 -120.231443) (xy 11.993619 -120.048707)
			(xy 11.919344 -119.862851) (xy 11.852564 -119.674171) (xy 11.793387 -119.482971) (xy 11.741908 -119.289557)
			(xy 11.698207 -119.094237) (xy 11.662357 -118.897326) (xy 11.634414 -118.699138) (xy 11.614422 -118.49999)
			(xy 11.602414 -118.300202) (xy 11.59841 -118.100094) (xy 10.325354 -118.100094) (xy 10.325354 -120.632728)
			(xy 21.405088 -131.712462) (xy 21.405088 -131.733544) (xy 21.738336 -132.066792) (xy 21.738336 -141.31417)
			(xy 21.405088 -141.647418) (xy 21.405088 -142.162784) (xy 19.919696 -143.648176) (xy 19.919696 -184.27344)
			(xy 26.727132 -184.27344) (xy 26.727132 -184.213504) (xy 26.734955 -184.154082) (xy 26.750468 -184.096189)
			(xy 26.773404 -184.040816) (xy 26.803371 -183.98891) (xy 26.839858 -183.94136) (xy 26.882238 -183.89898)
			(xy 26.929788 -183.862493) (xy 26.981694 -183.832526) (xy 27.037067 -183.80959) (xy 27.09496 -183.794077)
			(xy 27.154382 -183.786254) (xy 27.214318 -183.786254) (xy 27.27374 -183.794077) (xy 27.331633 -183.80959)
			(xy 27.387006 -183.832526) (xy 27.438912 -183.862493) (xy 27.486462 -183.89898) (xy 27.528842 -183.94136)
			(xy 27.565329 -183.98891) (xy 27.595296 -184.040816) (xy 27.618232 -184.096189) (xy 27.633745 -184.154082)
			(xy 27.641568 -184.213504) (xy 27.642058 -184.243472) (xy 27.641568 -184.27344) (xy 27.633745 -184.332862)
			(xy 27.618232 -184.390755) (xy 27.595296 -184.446128) (xy 27.565329 -184.498034) (xy 27.528842 -184.545584)
			(xy 27.486462 -184.587964) (xy 27.438912 -184.624451) (xy 27.387006 -184.654418) (xy 27.331633 -184.677354)
			(xy 27.27374 -184.692867) (xy 27.214318 -184.70069) (xy 27.154382 -184.70069) (xy 27.09496 -184.692867)
			(xy 27.037067 -184.677354) (xy 26.981694 -184.654418) (xy 26.929788 -184.624451) (xy 26.882238 -184.587964)
			(xy 26.839858 -184.545584) (xy 26.803371 -184.498034) (xy 26.773404 -184.446128) (xy 26.750468 -184.390755)
			(xy 26.734955 -184.332862) (xy 26.727132 -184.27344) (xy 19.919696 -184.27344) (xy 19.919696 -186.775594)
			(xy 26.764724 -186.775594) (xy 26.764724 -186.715658) (xy 26.772547 -186.656236) (xy 26.78806 -186.598343)
			(xy 26.810996 -186.54297) (xy 26.840963 -186.491064) (xy 26.87745 -186.443514) (xy 26.91983 -186.401134)
			(xy 26.96738 -186.364647) (xy 27.019286 -186.33468) (xy 27.074659 -186.311744) (xy 27.132552 -186.296231)
			(xy 27.191974 -186.288408) (xy 27.25191 -186.288408) (xy 27.311332 -186.296231) (xy 27.369225 -186.311744)
			(xy 27.424598 -186.33468) (xy 27.476504 -186.364647) (xy 27.524054 -186.401134) (xy 27.566434 -186.443514)
			(xy 27.602921 -186.491064) (xy 27.632888 -186.54297) (xy 27.655824 -186.598343) (xy 27.671337 -186.656236)
			(xy 27.67916 -186.715658) (xy 27.67965 -186.745626) (xy 27.67916 -186.775594) (xy 27.671337 -186.835016)
			(xy 27.655824 -186.892909) (xy 27.632888 -186.948282) (xy 27.602921 -187.000188) (xy 27.566434 -187.047738)
			(xy 27.524054 -187.090118) (xy 27.476504 -187.126605) (xy 27.424598 -187.156572) (xy 27.369225 -187.179508)
			(xy 27.311332 -187.195021) (xy 27.25191 -187.202844) (xy 27.191974 -187.202844) (xy 27.132552 -187.195021)
			(xy 27.074659 -187.179508) (xy 27.019286 -187.156572) (xy 26.96738 -187.126605) (xy 26.91983 -187.090118)
			(xy 26.87745 -187.047738) (xy 26.840963 -187.000188) (xy 26.810996 -186.948282) (xy 26.78806 -186.892909)
			(xy 26.772547 -186.835016) (xy 26.764724 -186.775594) (xy 19.919696 -186.775594) (xy 19.919696 -191.627252)
			(xy 20.152868 -191.860424) (xy 21.062696 -191.860424) (xy 23.396448 -189.526672) (xy 23.727156 -189.526672)
			(xy 23.751032 -189.516512) (xy 23.799383 -189.496478) (xy 23.898385 -189.462502) (xy 23.999549 -189.435638)
			(xy 24.102364 -189.416019) (xy 24.206312 -189.403745) (xy 24.310869 -189.398878) (xy 24.415507 -189.401442)
			(xy 24.5197 -189.411424) (xy 24.622922 -189.428774) (xy 24.724653 -189.453405) (xy 24.82438 -189.485191)
			(xy 24.921599 -189.523974) (xy 25.015822 -189.569558) (xy 25.061418 -189.595252) (xy 25.075388 -189.603126)
			(xy 25.10917 -189.612524) (xy 25.125497 -189.616505) (xy 25.159092 -189.616693) (xy 25.19157 -189.6081)
			(xy 25.220676 -189.591323) (xy 25.232868 -189.579758) (xy 25.694386 -189.11824) (xy 25.699974 -189.075314)
			(xy 25.707436 -189.021701) (xy 25.729227 -188.915662) (xy 25.75874 -188.811507) (xy 25.795818 -188.7098)
			(xy 25.840258 -188.611087) (xy 25.891823 -188.515901) (xy 25.950234 -188.424757) (xy 26.015176 -188.338144)
			(xy 26.086298 -188.256531) (xy 26.163218 -188.180356) (xy 26.24552 -188.110032) (xy 26.332761 -188.045937)
			(xy 26.424471 -187.988416) (xy 26.520154 -187.937781) (xy 26.619294 -187.894303) (xy 26.721358 -187.858218)
			(xy 26.825795 -187.82972) (xy 26.932042 -187.808963) (xy 27.039525 -187.796059) (xy 27.147665 -187.791076)
			(xy 27.25588 -187.794043) (xy 27.363585 -187.804943) (xy 27.4702 -187.823717) (xy 27.57515 -187.850264)
			(xy 27.677868 -187.884441) (xy 27.777802 -187.926063) (xy 27.874412 -187.974907) (xy 27.967177 -188.030709)
			(xy 28.055597 -188.093168) (xy 28.139195 -188.161946) (xy 28.217521 -188.236674) (xy 28.254198 -188.276484)
			(xy 28.269958 -188.293142) (xy 28.306344 -188.321043) (xy 28.347144 -188.341967) (xy 28.391034 -188.355237)
			(xy 28.436592 -188.360423) (xy 28.482342 -188.357356) (xy 28.5268 -188.346136) (xy 28.568526 -188.327126)
			(xy 28.606168 -188.300943) (xy 28.638504 -188.268435) (xy 28.664488 -188.230655) (xy 28.674314 -188.209936)
			(xy 28.698128 -188.157844) (xy 28.751028 -188.056239) (xy 28.809776 -187.9579) (xy 28.874171 -187.863163)
			(xy 28.908756 -187.817506) (xy 28.918554 -187.803975) (xy 28.931377 -187.773137) (xy 28.935756 -187.740029)
			(xy 28.931392 -187.706918) (xy 28.918582 -187.676075) (xy 28.908756 -187.662566) (xy 28.871902 -187.613864)
			(xy 28.803634 -187.512578) (xy 28.741819 -187.40723) (xy 28.686696 -187.298231) (xy 28.638481 -187.186005)
			(xy 28.597361 -187.07099) (xy 28.563497 -186.953633) (xy 28.53702 -186.834392) (xy 28.518034 -186.713732)
			(xy 28.506613 -186.592122) (xy 28.502801 -186.470037) (xy 28.506614 -186.347951) (xy 28.518035 -186.226342)
			(xy 28.537021 -186.105682) (xy 28.563498 -185.986441) (xy 28.597363 -185.869084) (xy 28.638483 -185.754069)
			(xy 28.686698 -185.641843) (xy 28.741822 -185.532844) (xy 28.803638 -185.427496) (xy 28.871906 -185.32621)
			(xy 28.908756 -185.277506) (xy 28.918554 -185.263975) (xy 28.931377 -185.233137) (xy 28.935756 -185.200029)
			(xy 28.931392 -185.166918) (xy 28.918582 -185.136075) (xy 28.908756 -185.122566) (xy 28.871902 -185.073864)
			(xy 28.803634 -184.972578) (xy 28.741819 -184.86723) (xy 28.686696 -184.758231) (xy 28.638481 -184.646005)
			(xy 28.597361 -184.53099) (xy 28.563497 -184.413633) (xy 28.53702 -184.294392) (xy 28.518034 -184.173732)
			(xy 28.506613 -184.052122) (xy 28.502801 -183.930037) (xy 28.506614 -183.807951) (xy 28.518035 -183.686342)
			(xy 28.537021 -183.565682) (xy 28.563498 -183.446441) (xy 28.597363 -183.329084) (xy 28.638483 -183.214069)
			(xy 28.686698 -183.101843) (xy 28.741822 -182.992844) (xy 28.803638 -182.887496) (xy 28.871906 -182.78621)
			(xy 28.908756 -182.737506) (xy 28.918554 -182.723975) (xy 28.931377 -182.693137) (xy 28.935756 -182.660029)
			(xy 28.931392 -182.626918) (xy 28.918582 -182.596075) (xy 28.908756 -182.582566) (xy 28.870107 -182.531442)
			(xy 28.798812 -182.424928) (xy 28.73464 -182.313975) (xy 28.677868 -182.199061) (xy 28.628738 -182.080677)
			(xy 28.587462 -181.959332) (xy 28.554216 -181.835545) (xy 28.529142 -181.709848) (xy 28.512349 -181.58278)
			(xy 28.503909 -181.454884) (xy 28.503372 -181.390798) (xy 28.503372 -181.33822) (xy 25.375616 -178.210464)
			(xy 24.749506 -178.210464) (xy 24.695275 -178.209987) (xy 24.587095 -178.202155) (xy 24.479765 -178.186522)
			(xy 24.373845 -178.163172) (xy 24.269891 -178.132227) (xy 24.168445 -178.093848) (xy 24.070039 -178.048236)
			(xy 23.975188 -177.99563) (xy 23.884387 -177.936305) (xy 23.798113 -177.870571) (xy 23.716816 -177.798773)
			(xy 23.640921 -177.721287) (xy 23.570827 -177.638516) (xy 23.506899 -177.550896) (xy 23.449472 -177.458883)
			(xy 23.398847 -177.36296) (xy 23.355288 -177.263628) (xy 23.319023 -177.161407) (xy 23.290243 -177.056833)
			(xy 23.269097 -176.950451) (xy 23.255697 -176.84282) (xy 23.250112 -176.734501) (xy 23.252372 -176.626061)
			(xy 23.262464 -176.518069) (xy 23.280337 -176.411089) (xy 23.305896 -176.305681) (xy 23.322026 -176.253902)
			(xy 23.332948 -176.219866) (xy 23.316184 -176.150778) (xy 23.062692 -175.897286) (xy 23.062692 -110.525306)
			(xy 24.875998 -108.712508) (xy 24.886856 -108.701082) (xy 24.903089 -108.674076) (xy 24.912157 -108.643899)
			(xy 24.913336 -108.62818) (xy 24.913336 -104.003602) (xy 24.989028 -103.92791) (xy 25.039574 -103.87711)
			(xy 25.039574 -102.994206) (xy 27.735784 -100.297996) (xy 27.735784 -99.972876) (xy 27.735315 -99.950558)
			(xy 27.727516 -99.90661) (xy 27.712161 -99.864699) (xy 27.689723 -99.826114) (xy 27.660891 -99.79204)
			(xy 27.626552 -99.763525) (xy 27.58776 -99.741446) (xy 27.545709 -99.72648) (xy 27.50169 -99.719088)
			(xy 27.457056 -99.719498) (xy 27.413181 -99.727696) (xy 27.371411 -99.743431) (xy 27.35199 -99.754436)
			(xy 27.32594 -99.770631) (xy 27.270398 -99.796663) (xy 27.211878 -99.815046) (xy 27.151427 -99.825449)
			(xy 27.090128 -99.827686) (xy 27.029079 -99.821717) (xy 26.969374 -99.807649) (xy 26.912083 -99.785734)
			(xy 26.858231 -99.756365) (xy 26.808784 -99.720067) (xy 26.764627 -99.677491) (xy 26.726552 -99.629399)
			(xy 26.695239 -99.576653) (xy 26.671251 -99.520199) (xy 26.655017 -99.461046) (xy 26.646827 -99.400256)
			(xy 26.646829 -99.338916) (xy 26.655022 -99.278126) (xy 26.67126 -99.218975) (xy 26.695252 -99.162521)
			(xy 26.726568 -99.109778) (xy 26.764646 -99.061688) (xy 26.808806 -99.019115) (xy 26.858255 -98.98282)
			(xy 26.912109 -98.953454) (xy 26.969401 -98.931542) (xy 27.029107 -98.917478) (xy 27.090156 -98.911513)
			(xy 27.151455 -98.913754) (xy 27.211905 -98.924161) (xy 27.270424 -98.942547) (xy 27.325964 -98.968583)
			(xy 27.35199 -98.984816) (xy 27.371416 -98.995823) (xy 27.413186 -99.011583) (xy 27.457068 -99.019802)
			(xy 27.501711 -99.020227) (xy 27.545742 -99.012843) (xy 27.587804 -98.99788) (xy 27.626605 -98.975797)
			(xy 27.66095 -98.947273) (xy 27.689782 -98.913187) (xy 27.712215 -98.874587) (xy 27.727557 -98.832661)
			(xy 27.735337 -98.788699) (xy 27.735784 -98.766376) (xy 27.735784 -96.243394) (xy 27.735324 -96.221393)
			(xy 27.727757 -96.178048) (xy 27.712834 -96.136655) (xy 27.691001 -96.098454) (xy 27.662911 -96.064586)
			(xy 27.629404 -96.036066) (xy 27.591484 -96.013746) (xy 27.550286 -95.998296) (xy 27.50704 -95.990176)
			(xy 27.463043 -95.989631) (xy 27.41961 -95.996676) (xy 27.378041 -96.0111) (xy 27.358594 -96.021398)
			(xy 27.331514 -96.035868) (xy 27.274333 -96.05823) (xy 27.214675 -96.07275) (xy 27.153613 -96.079168)
			(xy 27.092241 -96.077367) (xy 27.031659 -96.067381) (xy 26.972956 -96.049388) (xy 26.917184 -96.023712)
			(xy 26.865344 -95.990812) (xy 26.818365 -95.95128) (xy 26.777091 -95.905824) (xy 26.742261 -95.85526)
			(xy 26.714502 -95.800495) (xy 26.69431 -95.742511) (xy 26.682048 -95.682349) (xy 26.677937 -95.621088)
			(xy 26.682049 -95.559827) (xy 26.694311 -95.499665) (xy 26.714503 -95.441682) (xy 26.742263 -95.386917)
			(xy 26.777093 -95.336353) (xy 26.818368 -95.290898) (xy 26.865347 -95.251366) (xy 26.917187 -95.218467)
			(xy 26.97296 -95.192791) (xy 27.031663 -95.174798) (xy 27.092244 -95.164813) (xy 27.153617 -95.163012)
			(xy 27.214679 -95.16943) (xy 27.274336 -95.183951) (xy 27.331518 -95.206314) (xy 27.358594 -95.22079)
			(xy 27.378053 -95.23105) (xy 27.419616 -95.245446) (xy 27.463038 -95.252468) (xy 27.507021 -95.251908)
			(xy 27.55025 -95.243781) (xy 27.591434 -95.228332) (xy 27.629341 -95.206021) (xy 27.66284 -95.177515)
			(xy 27.69093 -95.143665) (xy 27.71277 -95.105485) (xy 27.727709 -95.064113) (xy 27.7353 -95.020787)
			(xy 27.735784 -94.998794) (xy 27.735784 -94.72803) (xy 22.184868 -89.177114) (xy 22.184868 -12.291822)
			(xy 24.547322 -9.929622) (xy 24.555704 -9.915398) (xy 24.582439 -9.870364) (xy 24.641712 -9.784009)
			(xy 24.707285 -9.702335) (xy 24.778791 -9.625802) (xy 24.855828 -9.554839) (xy 24.937963 -9.489845)
			(xy 25.024735 -9.431185) (xy 25.115657 -9.379188) (xy 25.210218 -9.334147) (xy 25.307886 -9.296314)
			(xy 25.408113 -9.265902) (xy 25.510337 -9.243082) (xy 25.613983 -9.227982) (xy 25.718468 -9.220686)
			(xy 25.77084 -9.220454) (xy 26.492962 -9.220454) (xy 26.515547 -9.219958) (xy 26.560004 -9.211964)
			(xy 26.602348 -9.196239) (xy 26.641246 -9.173277) (xy 26.675474 -9.143802) (xy 26.703953 -9.108742)
			(xy 26.725788 -9.0692) (xy 26.74029 -9.026422) (xy 26.747004 -8.981754) (xy 26.745718 -8.936602)
			(xy 26.741628 -8.914384) (xy 26.734516 -8.876792) (xy 26.732992 -8.865108) (xy 26.729917 -8.835553)
			(xy 26.730522 -8.776134) (xy 26.738813 -8.717293) (xy 26.754648 -8.660019) (xy 26.777763 -8.605278)
			(xy 26.807769 -8.553988) (xy 26.84416 -8.507012) (xy 26.886325 -8.465142) (xy 26.933554 -8.429081)
			(xy 26.985053 -8.399436) (xy 27.039956 -8.376705) (xy 27.068526 -8.368538) (xy 27.096364 -8.361495)
			(xy 27.153242 -8.353601) (xy 27.21066 -8.352891) (xy 27.267716 -8.359376) (xy 27.32351 -8.372954)
			(xy 27.377166 -8.393412) (xy 27.427837 -8.420427) (xy 27.451558 -8.43661) (xy 27.470282 -8.449265)
			(xy 27.511197 -8.468445) (xy 27.554858 -8.480092) (xy 27.59989 -8.483838) (xy 27.644876 -8.479565)
			(xy 27.688397 -8.467408) (xy 27.729085 -8.44775) (xy 27.765658 -8.421209) (xy 27.796963 -8.388622)
			(xy 27.822015 -8.351015) (xy 27.840026 -8.309572) (xy 27.850428 -8.265597) (xy 27.852116 -8.243062)
			(xy 27.852116 -7.229094) (xy 27.850358 -7.206187) (xy 27.839631 -7.16152) (xy 27.821056 -7.119505)
			(xy 27.795238 -7.08151) (xy 27.763015 -7.048768) (xy 27.725437 -7.022347) (xy 27.683724 -7.003103)
			(xy 27.639234 -6.991664) (xy 27.593412 -6.9884) (xy 27.54775 -6.993419) (xy 27.503731 -7.006557)
			(xy 27.462787 -7.027387) (xy 27.444192 -7.04088) (xy 27.420096 -7.058576) (xy 27.368187 -7.088236)
			(xy 27.312859 -7.110885) (xy 27.255053 -7.126138) (xy 27.195753 -7.133735) (xy 27.135969 -7.133547)
			(xy 27.076718 -7.125576) (xy 27.019009 -7.10996) (xy 26.963825 -7.086963) (xy 26.912104 -7.056978)
			(xy 26.864727 -7.020514) (xy 26.822501 -6.978192) (xy 26.786144 -6.930732) (xy 26.756276 -6.878944)
			(xy 26.733405 -6.823707) (xy 26.717919 -6.765963) (xy 26.710084 -6.706694) (xy 26.710031 -6.64691)
			(xy 26.713434 -6.617208) (xy 26.717793 -6.587452) (xy 26.73331 -6.52935) (xy 26.7563 -6.473779) (xy 26.786369 -6.421697)
			(xy 26.822999 -6.374) (xy 26.865558 -6.331509) (xy 26.913314 -6.294957) (xy 26.965444 -6.264973)
			(xy 27.021052 -6.242072) (xy 27.07918 -6.226649) (xy 27.138827 -6.21897) (xy 27.198966 -6.219167)
			(xy 27.258561 -6.227236) (xy 27.316586 -6.243039) (xy 27.372043 -6.266303) (xy 27.423977 -6.296628)
			(xy 27.471493 -6.333492) (xy 27.513773 -6.37626) (xy 27.550089 -6.424195) (xy 27.579817 -6.476473)
			(xy 27.591512 -6.504178) (xy 27.601111 -6.524355) (xy 27.626297 -6.561258) (xy 27.657547 -6.593188)
			(xy 27.6939 -6.619161) (xy 27.734235 -6.638377) (xy 27.777309 -6.650242) (xy 27.821794 -6.654392)
			(xy 27.866319 -6.650699) (xy 27.909513 -6.639276) (xy 27.950043 -6.620476) (xy 27.98666 -6.594877)
			(xy 28.002738 -6.579362) (xy 29.544264 -5.037836) (xy 29.556478 -5.024715) (xy 29.573727 -4.993309)
			(xy 29.58158 -4.958349) (xy 29.579418 -4.922583) (xy 29.573982 -4.905502) (xy 29.560004 -4.864824)
			(xy 29.538661 -4.781494) (xy 29.52502 -4.696563) (xy 29.519194 -4.610741) (xy 29.521231 -4.524746)
			(xy 29.531115 -4.439296) (xy 29.548763 -4.355106) (xy 29.574027 -4.27288) (xy 29.606696 -4.193306)
			(xy 29.646497 -4.117048) (xy 29.693098 -4.044745) (xy 29.746108 -3.977001) (xy 29.805084 -3.914382)
			(xy 29.869534 -3.857411) (xy 29.938918 -3.806566) (xy 30.012656 -3.762272) (xy 30.090132 -3.724898)
			(xy 30.170698 -3.694757) (xy 30.253681 -3.672101) (xy 30.338386 -3.65712) (xy 30.424105 -3.649939)
			(xy 30.510122 -3.650617) (xy 30.595717 -3.65915) (xy 30.680175 -3.675466) (xy 30.76279 -3.699428)
			(xy 30.84287 -3.730836) (xy 30.919747 -3.769428) (xy 30.992778 -3.81488) (xy 31.061351 -3.866814)
			(xy 31.124894 -3.924794) (xy 31.182875 -3.988335) (xy 31.234809 -4.056908) (xy 31.280263 -4.129937)
			(xy 31.318857 -4.206813) (xy 31.350266 -4.286893) (xy 31.37423 -4.369507) (xy 31.390547 -4.453965)
			(xy 31.399082 -4.53956) (xy 31.399762 -4.625577) (xy 31.392582 -4.711297) (xy 31.377603 -4.796002)
			(xy 31.354949 -4.878985) (xy 31.324809 -4.959551) (xy 31.287437 -5.037028) (xy 31.243143 -5.110767)
			(xy 31.1923 -5.180152) (xy 31.135331 -5.244603) (xy 31.072713 -5.303581) (xy 31.004969 -5.356592)
			(xy 30.932667 -5.403194) (xy 30.85641 -5.442997) (xy 30.776836 -5.475667) (xy 30.694611 -5.500933)
			(xy 30.610422 -5.518582) (xy 30.524972 -5.528468) (xy 30.438977 -5.530507) (xy 30.353154 -5.524682)
			(xy 30.268223 -5.511042) (xy 30.184893 -5.489702) (xy 30.144212 -5.475732) (xy 30.127129 -5.470276)
			(xy 30.091352 -5.468078) (xy 30.056377 -5.475924) (xy 30.024966 -5.493193) (xy 30.011878 -5.50545)
			(xy 29.082492 -6.434836) (xy 28.866846 -6.650228) (xy 28.544012 -6.973316) (xy 28.535359 -6.983765)
			(xy 28.522247 -7.007508) (xy 28.514438 -7.033484) (xy 28.513024 -7.046976) (xy 28.513024 -7.173484)
			(xy 29.519874 -7.173484) (xy 29.519874 -7.086584) (xy 29.527892 -7.000055) (xy 29.54386 -6.914635)
			(xy 29.567641 -6.831053) (xy 29.599033 -6.750021) (xy 29.637767 -6.672232) (xy 29.683514 -6.598348)
			(xy 29.735883 -6.529001) (xy 29.794427 -6.464781) (xy 29.858647 -6.406237) (xy 29.927994 -6.353868)
			(xy 30.001878 -6.308121) (xy 30.079667 -6.269387) (xy 30.160699 -6.237995) (xy 30.244281 -6.214214)
			(xy 30.329701 -6.198246) (xy 30.41623 -6.190228) (xy 30.50313 -6.190228) (xy 30.589659 -6.198246)
			(xy 30.675079 -6.214214) (xy 30.758661 -6.237995) (xy 30.839693 -6.269387) (xy 30.917482 -6.308121)
			(xy 30.991366 -6.353868) (xy 31.060713 -6.406237) (xy 31.124933 -6.464781) (xy 31.183477 -6.529001)
			(xy 31.235846 -6.598348) (xy 31.281593 -6.672232) (xy 31.320327 -6.750021) (xy 31.351719 -6.831053)
			(xy 31.3755 -6.914635) (xy 31.391468 -7.000055) (xy 31.399486 -7.086584) (xy 31.399988 -7.130034)
			(xy 31.399486 -7.173484) (xy 34.599874 -7.173484) (xy 34.599874 -7.086584) (xy 34.607892 -7.000055)
			(xy 34.62386 -6.914635) (xy 34.647641 -6.831053) (xy 34.679033 -6.750021) (xy 34.717767 -6.672232)
			(xy 34.763514 -6.598348) (xy 34.815883 -6.529001) (xy 34.874427 -6.464781) (xy 34.938647 -6.406237)
			(xy 35.007994 -6.353868) (xy 35.081878 -6.308121) (xy 35.159667 -6.269387) (xy 35.240699 -6.237995)
			(xy 35.324281 -6.214214) (xy 35.409701 -6.198246) (xy 35.49623 -6.190228) (xy 35.58313 -6.190228)
			(xy 35.669659 -6.198246) (xy 35.755079 -6.214214) (xy 35.838661 -6.237995) (xy 35.919693 -6.269387)
			(xy 35.997482 -6.308121) (xy 36.071366 -6.353868) (xy 36.140713 -6.406237) (xy 36.204933 -6.464781)
			(xy 36.263477 -6.529001) (xy 36.315846 -6.598348) (xy 36.361593 -6.672232) (xy 36.400327 -6.750021)
			(xy 36.431719 -6.831053) (xy 36.4555 -6.914635) (xy 36.471468 -7.000055) (xy 36.479486 -7.086584)
			(xy 36.479988 -7.130034) (xy 36.479486 -7.173484) (xy 36.471468 -7.260013) (xy 36.4555 -7.345433)
			(xy 36.431719 -7.429015) (xy 36.400327 -7.510047) (xy 36.361593 -7.587836) (xy 36.315846 -7.66172)
			(xy 36.263477 -7.731067) (xy 36.204933 -7.795287) (xy 36.140713 -7.853831) (xy 36.071366 -7.9062)
			(xy 35.997482 -7.951947) (xy 35.919693 -7.990681) (xy 35.838661 -8.022073) (xy 35.755079 -8.045854)
			(xy 35.669659 -8.061822) (xy 35.58313 -8.06984) (xy 35.49623 -8.06984) (xy 35.409701 -8.061822) (xy 35.324281 -8.045854)
			(xy 35.240699 -8.022073) (xy 35.159667 -7.990681) (xy 35.081878 -7.951947) (xy 35.007994 -7.9062)
			(xy 34.938647 -7.853831) (xy 34.874427 -7.795287) (xy 34.815883 -7.731067) (xy 34.763514 -7.66172)
			(xy 34.717767 -7.587836) (xy 34.679033 -7.510047) (xy 34.647641 -7.429015) (xy 34.62386 -7.345433)
			(xy 34.607892 -7.260013) (xy 34.599874 -7.173484) (xy 31.399486 -7.173484) (xy 31.391468 -7.260013)
			(xy 31.3755 -7.345433) (xy 31.351719 -7.429015) (xy 31.320327 -7.510047) (xy 31.281593 -7.587836)
			(xy 31.235846 -7.66172) (xy 31.183477 -7.731067) (xy 31.124933 -7.795287) (xy 31.060713 -7.853831)
			(xy 30.991366 -7.9062) (xy 30.917482 -7.951947) (xy 30.839693 -7.990681) (xy 30.758661 -8.022073)
			(xy 30.675079 -8.045854) (xy 30.589659 -8.061822) (xy 30.50313 -8.06984) (xy 30.41623 -8.06984) (xy 30.329701 -8.061822)
			(xy 30.244281 -8.045854) (xy 30.160699 -8.022073) (xy 30.079667 -7.990681) (xy 30.001878 -7.951947)
			(xy 29.927994 -7.9062) (xy 29.858647 -7.853831) (xy 29.794427 -7.795287) (xy 29.735883 -7.731067)
			(xy 29.683514 -7.66172) (xy 29.637767 -7.587836) (xy 29.599033 -7.510047) (xy 29.567641 -7.429015)
			(xy 29.54386 -7.345433) (xy 29.527892 -7.260013) (xy 29.519874 -7.173484) (xy 28.513024 -7.173484)
			(xy 28.513024 -9.103106) (xy 28.514769 -9.118874) (xy 28.524995 -9.148894) (xy 28.542282 -9.175481)
			(xy 28.565572 -9.197007) (xy 28.593437 -9.212151) (xy 28.624168 -9.219985) (xy 28.640024 -9.220454)
			(xy 29.561536 -9.220454) (xy 29.667454 -9.162542) (xy 29.684726 -9.13765) (xy 29.70726 -9.105567)
			(xy 29.756886 -9.044865) (xy 29.811392 -8.988503) (xy 29.870401 -8.936874) (xy 29.933502 -8.890336)
			(xy 29.966666 -8.869426) (xy 29.994905 -8.852335) (xy 30.05338 -8.8217) (xy 30.083506 -8.808212)
			(xy 30.127122 -8.789816) (xy 30.217248 -8.760851) (xy 30.309826 -8.74108) (xy 30.35681 -8.735314)
			(xy 30.400489 -8.731015) (xy 30.488251 -8.729583) (xy 30.575764 -8.736337) (xy 30.662267 -8.751218)
			(xy 30.747007 -8.774096) (xy 30.829246 -8.804772) (xy 30.908267 -8.842979) (xy 30.983384 -8.888385)
			(xy 31.053942 -8.940594) (xy 31.119327 -8.999152) (xy 31.17897 -9.063549) (xy 31.232351 -9.133224)
			(xy 31.279006 -9.207571) (xy 31.318529 -9.285943) (xy 31.350576 -9.367657) (xy 31.374868 -9.452003)
			(xy 31.391192 -9.538245) (xy 31.399408 -9.625633) (xy 31.399444 -9.713407) (xy 31.395924 -9.757156)
			(xy 31.395924 -9.757664) (xy 31.395416 -9.76376) (xy 31.395416 -9.829292) (xy 32.165036 -10.598912)
			(xy 34.02838 -10.598912) (xy 34.043386 -10.597278) (xy 34.07206 -10.587871) (xy 34.097726 -10.571998)
			(xy 34.108644 -10.561574) (xy 34.638234 -10.031984) (xy 34.638234 -9.938512) (xy 34.633662 -9.921748)
			(xy 34.633662 -9.921494) (xy 34.622552 -9.879596) (xy 34.607163 -9.794286) (xy 34.599691 -9.707923)
			(xy 34.6002 -9.621238) (xy 34.608686 -9.534968) (xy 34.625077 -9.449845) (xy 34.649233 -9.366592)
			(xy 34.68095 -9.285917) (xy 34.719958 -9.208503) (xy 34.765927 -9.135008) (xy 34.818465 -9.066057)
			(xy 34.877127 -9.002234) (xy 34.941414 -8.944082) (xy 35.010781 -8.892094) (xy 35.084639 -8.846712)
			(xy 35.162361 -8.808321) (xy 35.243286 -8.777247) (xy 35.326728 -8.753753) (xy 35.411979 -8.73804)
			(xy 35.498314 -8.730241) (xy 35.585 -8.730421) (xy 35.671302 -8.73858) (xy 35.756486 -8.754648) (xy 35.839829 -8.778489)
			(xy 35.920625 -8.8099) (xy 35.998186 -8.848614) (xy 36.071854 -8.894304) (xy 36.141004 -8.94658)
			(xy 36.205049 -9.004999) (xy 36.263444 -9.069066) (xy 36.315695 -9.138235) (xy 36.361357 -9.211921)
			(xy 36.400042 -9.289496) (xy 36.431423 -9.370303) (xy 36.455233 -9.453656) (xy 36.471269 -9.538846)
			(xy 36.479395 -9.625151) (xy 36.479544 -9.711837) (xy 36.471712 -9.798169) (xy 36.455967 -9.883413)
			(xy 36.432443 -9.966847) (xy 36.401338 -10.047761) (xy 36.362918 -10.125468) (xy 36.317508 -10.199309)
			(xy 36.265495 -10.268657) (xy 36.207319 -10.332922) (xy 36.143474 -10.39156) (xy 36.074503 -10.444073)
			(xy 36.000991 -10.490014) (xy 35.923563 -10.528993) (xy 35.842876 -10.56068) (xy 35.759614 -10.584805)
			(xy 35.674485 -10.601164) (xy 35.588212 -10.609618) (xy 35.501527 -10.610095) (xy 35.415166 -10.602591)
			(xy 35.329862 -10.587169) (xy 35.287966 -10.576052) (xy 35.271202 -10.57148) (xy 35.17773 -10.57148)
			(xy 34.638234 -11.110976) (xy 34.622296 -11.127617) (xy 34.596118 -11.165531) (xy 34.577203 -11.207543)
			(xy 34.566172 -11.252276) (xy 34.563386 -11.298265) (xy 34.568936 -11.344003) (xy 34.58264 -11.387991)
			(xy 34.604049 -11.428788) (xy 34.632462 -11.465057) (xy 34.666948 -11.49561) (xy 34.706377 -11.519445)
			(xy 34.749456 -11.535783) (xy 34.794775 -11.544086) (xy 34.817812 -11.544554) (xy 34.873438 -11.544554)
			(xy 34.90976 -11.511788) (xy 34.942174 -11.483202) (xy 35.01139 -11.431437) (xy 35.085066 -11.386246)
			(xy 35.162579 -11.348009) (xy 35.243276 -11.317052) (xy 35.326475 -11.293633) (xy 35.411472 -11.277953)
			(xy 35.49755 -11.270142) (xy 35.583981 -11.270268) (xy 35.627056 -11.27379) (xy 35.632644 -11.274298)
			(xy 35.678404 -11.279423) (xy 35.768705 -11.29747) (xy 35.85681 -11.324254) (xy 35.941877 -11.359518)
			(xy 36.023091 -11.402926) (xy 36.099674 -11.454061) (xy 36.170895 -11.512435) (xy 36.20389 -11.544554)
			(xy 36.623752 -11.544554) (xy 36.639943 -11.544077) (xy 36.671286 -11.535937) (xy 36.69957 -11.52017)
			(xy 36.722975 -11.497791) (xy 36.739992 -11.470241) (xy 36.749527 -11.439295) (xy 36.750752 -11.423142)
			(xy 36.750752 -6.26872) (xy 35.987482 -5.50545) (xy 35.974361 -5.493241) (xy 35.942956 -5.476004)
			(xy 35.908 -5.468164) (xy 35.872242 -5.470339) (xy 35.855148 -5.475732) (xy 35.814203 -5.489789)
			(xy 35.73032 -5.511215) (xy 35.644823 -5.524838) (xy 35.558436 -5.530543) (xy 35.471889 -5.528283)
			(xy 35.385917 -5.518075) (xy 35.301248 -5.500007) (xy 35.218598 -5.474232) (xy 35.138668 -5.440968)
			(xy 35.062134 -5.400496) (xy 34.989645 -5.35316) (xy 34.921815 -5.29936) (xy 34.859218 -5.239552)
			(xy 34.802385 -5.174242) (xy 34.751796 -5.103984) (xy 34.70788 -5.029373) (xy 34.67101 -4.951041)
			(xy 34.641497 -4.869651) (xy 34.619592 -4.785892) (xy 34.605479 -4.700474) (xy 34.599279 -4.614121)
			(xy 34.601044 -4.527563) (xy 34.610759 -4.441534) (xy 34.628342 -4.356762) (xy 34.653644 -4.273966)
			(xy 34.68645 -4.193847) (xy 34.726483 -4.117083) (xy 34.773403 -4.044324) (xy 34.826814 -3.976187)
			(xy 34.856166 -3.944366) (xy 34.886789 -3.912677) (xy 34.953016 -3.854533) (xy 35.024394 -3.802841)
			(xy 35.100296 -3.758056) (xy 35.180055 -3.720569) (xy 35.262973 -3.690711) (xy 35.34832 -3.668742)
			(xy 35.435349 -3.654856) (xy 35.523295 -3.649175) (xy 35.611387 -3.651749) (xy 35.698851 -3.662554)
			(xy 35.784921 -3.681496) (xy 35.868841 -3.70841) (xy 35.949874 -3.743058) (xy 36.027309 -3.785136)
			(xy 36.100467 -3.834276) (xy 36.168705 -3.890047) (xy 36.231426 -3.951957) (xy 36.288077 -4.019466)
			(xy 36.338164 -4.091979) (xy 36.381245 -4.168861) (xy 36.416943 -4.249437) (xy 36.444944 -4.333)
			(xy 36.465003 -4.418816) (xy 36.476943 -4.506133) (xy 36.480661 -4.594184) (xy 36.476123 -4.682197)
			(xy 36.463369 -4.769398) (xy 36.442511 -4.855024) (xy 36.42868 -4.896866) (xy 36.425124 -4.906518)
			(xy 36.421314 -4.927346) (xy 36.419109 -4.94247) (xy 36.421113 -4.972959) (xy 36.430304 -5.002099)
			(xy 36.446154 -5.02822) (xy 36.45662 -5.03936) (xy 36.515294 -5.098034) (xy 37.41166 -5.994654) (xy 37.41166 -6.91007)
			(xy 39.818564 -6.91007) (xy 39.819054 -6.852663) (xy 39.826889 -6.738117) (xy 39.842523 -6.624372)
			(xy 39.865882 -6.51196) (xy 39.896859 -6.401403) (xy 39.935308 -6.293218) (xy 39.98105 -6.18791)
			(xy 40.033872 -6.085968) (xy 40.093527 -5.987869) (xy 40.159738 -5.894069) (xy 40.232196 -5.805007)
			(xy 40.310562 -5.721096) (xy 40.394473 -5.64273) (xy 40.483535 -5.570272) (xy 40.577335 -5.504061)
			(xy 40.675434 -5.444406) (xy 40.777376 -5.391584) (xy 40.882684 -5.345842) (xy 40.990869 -5.307393)
			(xy 41.101426 -5.276416) (xy 41.213838 -5.253057) (xy 41.327583 -5.237423) (xy 41.442129 -5.229588)
			(xy 41.556943 -5.229588) (xy 41.671489 -5.237423) (xy 41.785234 -5.253057) (xy 41.897646 -5.276416)
			(xy 42.008203 -5.307393) (xy 42.116388 -5.345842) (xy 42.221696 -5.391584) (xy 42.323638 -5.444406)
			(xy 42.421737 -5.504061) (xy 42.50107 -5.56006) (xy 63.647577 -5.56006) (xy 63.651612 -5.484356)
			(xy 63.663671 -5.409511) (xy 63.683617 -5.33637) (xy 63.711224 -5.265765) (xy 63.74618 -5.198494)
			(xy 63.788088 -5.135319) (xy 63.836474 -5.076957) (xy 63.89079 -5.024069) (xy 63.950419 -4.977254)
			(xy 64.014687 -4.937042) (xy 64.082864 -4.90389) (xy 64.15418 -4.878172) (xy 64.227825 -4.86018)
			(xy 64.302965 -4.850118) (xy 64.378749 -4.848099) (xy 64.454319 -4.854148) (xy 64.528817 -4.868195)
			(xy 64.6014 -4.890081) (xy 64.671246 -4.919558) (xy 64.737563 -4.956293) (xy 64.799599 -4.999868)
			(xy 64.856652 -5.04979) (xy 64.908076 -5.105494) (xy 64.953287 -5.166349) (xy 64.991774 -5.231664)
			(xy 65.0231 -5.3007) (xy 65.04691 -5.372675) (xy 65.062935 -5.446773) (xy 65.070994 -5.522154) (xy 65.071498 -5.56006)
			(xy 66.187577 -5.56006) (xy 66.191612 -5.484356) (xy 66.203671 -5.409511) (xy 66.223617 -5.33637)
			(xy 66.251224 -5.265765) (xy 66.28618 -5.198494) (xy 66.328088 -5.135319) (xy 66.376474 -5.076957)
			(xy 66.43079 -5.024069) (xy 66.490419 -4.977254) (xy 66.554687 -4.937042) (xy 66.622864 -4.90389)
			(xy 66.69418 -4.878172) (xy 66.767825 -4.86018) (xy 66.842965 -4.850118) (xy 66.918749 -4.848099)
			(xy 66.994319 -4.854148) (xy 67.068817 -4.868195) (xy 67.1414 -4.890081) (xy 67.211246 -4.919558)
			(xy 67.277563 -4.956293) (xy 67.339599 -4.999868) (xy 67.396652 -5.04979) (xy 67.448076 -5.105494)
			(xy 67.493287 -5.166349) (xy 67.531774 -5.231664) (xy 67.5631 -5.3007) (xy 67.58691 -5.372675) (xy 67.602935 -5.446773)
			(xy 67.610994 -5.522154) (xy 67.611498 -5.56006) (xy 68.727577 -5.56006) (xy 68.731612 -5.484356)
			(xy 68.743671 -5.409511) (xy 68.763617 -5.33637) (xy 68.791224 -5.265765) (xy 68.82618 -5.198494)
			(xy 68.868088 -5.135319) (xy 68.916474 -5.076957) (xy 68.97079 -5.024069) (xy 69.030419 -4.977254)
			(xy 69.094687 -4.937042) (xy 69.162864 -4.90389) (xy 69.23418 -4.878172) (xy 69.307825 -4.86018)
			(xy 69.382965 -4.850118) (xy 69.458749 -4.848099) (xy 69.534319 -4.854148) (xy 69.608817 -4.868195)
			(xy 69.6814 -4.890081) (xy 69.751246 -4.919558) (xy 69.817563 -4.956293) (xy 69.879599 -4.999868)
			(xy 69.936652 -5.04979) (xy 69.988076 -5.105494) (xy 70.033287 -5.166349) (xy 70.071774 -5.231664)
			(xy 70.1031 -5.3007) (xy 70.12691 -5.372675) (xy 70.142935 -5.446773) (xy 70.150994 -5.522154) (xy 70.151498 -5.56006)
			(xy 71.267577 -5.56006) (xy 71.271612 -5.484356) (xy 71.283671 -5.409511) (xy 71.303617 -5.33637)
			(xy 71.331224 -5.265765) (xy 71.36618 -5.198494) (xy 71.408088 -5.135319) (xy 71.456474 -5.076957)
			(xy 71.51079 -5.024069) (xy 71.570419 -4.977254) (xy 71.634687 -4.937042) (xy 71.702864 -4.90389)
			(xy 71.77418 -4.878172) (xy 71.847825 -4.86018) (xy 71.922965 -4.850118) (xy 71.998749 -4.848099)
			(xy 72.074319 -4.854148) (xy 72.148817 -4.868195) (xy 72.2214 -4.890081) (xy 72.291246 -4.919558)
			(xy 72.357563 -4.956293) (xy 72.419599 -4.999868) (xy 72.476652 -5.04979) (xy 72.528076 -5.105494)
			(xy 72.573287 -5.166349) (xy 72.611774 -5.231664) (xy 72.6431 -5.3007) (xy 72.66691 -5.372675) (xy 72.682935 -5.446773)
			(xy 72.690994 -5.522154) (xy 72.691498 -5.56006) (xy 73.807577 -5.56006) (xy 73.811612 -5.484356)
			(xy 73.823671 -5.409511) (xy 73.843617 -5.33637) (xy 73.871224 -5.265765) (xy 73.90618 -5.198494)
			(xy 73.948088 -5.135319) (xy 73.996474 -5.076957) (xy 74.05079 -5.024069) (xy 74.110419 -4.977254)
			(xy 74.174687 -4.937042) (xy 74.242864 -4.90389) (xy 74.31418 -4.878172) (xy 74.387825 -4.86018)
			(xy 74.462965 -4.850118) (xy 74.538749 -4.848099) (xy 74.614319 -4.854148) (xy 74.688817 -4.868195)
			(xy 74.7614 -4.890081) (xy 74.831246 -4.919558) (xy 74.897563 -4.956293) (xy 74.959599 -4.999868)
			(xy 75.016652 -5.04979) (xy 75.068076 -5.105494) (xy 75.113287 -5.166349) (xy 75.151774 -5.231664)
			(xy 75.1831 -5.3007) (xy 75.20691 -5.372675) (xy 75.222935 -5.446773) (xy 75.230994 -5.522154) (xy 75.231498 -5.56006)
			(xy 76.347577 -5.56006) (xy 76.351612 -5.484356) (xy 76.363671 -5.409511) (xy 76.383617 -5.33637)
			(xy 76.411224 -5.265765) (xy 76.44618 -5.198494) (xy 76.488088 -5.135319) (xy 76.536474 -5.076957)
			(xy 76.59079 -5.024069) (xy 76.650419 -4.977254) (xy 76.714687 -4.937042) (xy 76.782864 -4.90389)
			(xy 76.85418 -4.878172) (xy 76.927825 -4.86018) (xy 77.002965 -4.850118) (xy 77.078749 -4.848099)
			(xy 77.154319 -4.854148) (xy 77.228817 -4.868195) (xy 77.3014 -4.890081) (xy 77.371246 -4.919558)
			(xy 77.437563 -4.956293) (xy 77.499599 -4.999868) (xy 77.556652 -5.04979) (xy 77.608076 -5.105494)
			(xy 77.653287 -5.166349) (xy 77.691774 -5.231664) (xy 77.7231 -5.3007) (xy 77.74691 -5.372675) (xy 77.762935 -5.446773)
			(xy 77.770994 -5.522154) (xy 77.771498 -5.56006) (xy 78.887577 -5.56006) (xy 78.891612 -5.484356)
			(xy 78.903671 -5.409511) (xy 78.923617 -5.33637) (xy 78.951224 -5.265765) (xy 78.98618 -5.198494)
			(xy 79.028088 -5.135319) (xy 79.076474 -5.076957) (xy 79.13079 -5.024069) (xy 79.190419 -4.977254)
			(xy 79.254687 -4.937042) (xy 79.322864 -4.90389) (xy 79.39418 -4.878172) (xy 79.467825 -4.86018)
			(xy 79.542965 -4.850118) (xy 79.618749 -4.848099) (xy 79.694319 -4.854148) (xy 79.768817 -4.868195)
			(xy 79.8414 -4.890081) (xy 79.911246 -4.919558) (xy 79.977563 -4.956293) (xy 80.039599 -4.999868)
			(xy 80.096652 -5.04979) (xy 80.148076 -5.105494) (xy 80.193287 -5.166349) (xy 80.231774 -5.231664)
			(xy 80.2631 -5.3007) (xy 80.28691 -5.372675) (xy 80.302935 -5.446773) (xy 80.310994 -5.522154) (xy 80.311498 -5.56006)
			(xy 81.427577 -5.56006) (xy 81.431612 -5.484356) (xy 81.443671 -5.409511) (xy 81.463617 -5.33637)
			(xy 81.491224 -5.265765) (xy 81.52618 -5.198494) (xy 81.568088 -5.135319) (xy 81.616474 -5.076957)
			(xy 81.67079 -5.024069) (xy 81.730419 -4.977254) (xy 81.794687 -4.937042) (xy 81.862864 -4.90389)
			(xy 81.93418 -4.878172) (xy 82.007825 -4.86018) (xy 82.082965 -4.850118) (xy 82.158749 -4.848099)
			(xy 82.234319 -4.854148) (xy 82.308817 -4.868195) (xy 82.3814 -4.890081) (xy 82.451246 -4.919558)
			(xy 82.517563 -4.956293) (xy 82.579599 -4.999868) (xy 82.585544 -5.00507) (xy 86.197697 -5.00507)
			(xy 86.201732 -4.929366) (xy 86.213791 -4.854521) (xy 86.233737 -4.78138) (xy 86.261344 -4.710775)
			(xy 86.2963 -4.643504) (xy 86.338208 -4.580329) (xy 86.386594 -4.521967) (xy 86.44091 -4.469079)
			(xy 86.500539 -4.422264) (xy 86.564807 -4.382052) (xy 86.632984 -4.3489) (xy 86.7043 -4.323182) (xy 86.777945 -4.30519)
			(xy 86.853085 -4.295128) (xy 86.928869 -4.293109) (xy 87.004439 -4.299158) (xy 87.078937 -4.313205)
			(xy 87.15152 -4.335091) (xy 87.221366 -4.364568) (xy 87.287683 -4.401303) (xy 87.349719 -4.444878)
			(xy 87.406772 -4.4948) (xy 87.458196 -4.550504) (xy 87.503407 -4.611359) (xy 87.541894 -4.676674)
			(xy 87.57322 -4.74571) (xy 87.59703 -4.817685) (xy 87.613055 -4.891783) (xy 87.621114 -4.967164)
			(xy 87.621618 -5.00507) (xy 87.621114 -5.042976) (xy 87.613055 -5.118357) (xy 87.59703 -5.192455)
			(xy 87.57322 -5.26443) (xy 87.541894 -5.333466) (xy 87.503407 -5.398781) (xy 87.458196 -5.459636)
			(xy 87.406772 -5.51534) (xy 87.349719 -5.565262) (xy 87.287683 -5.608837) (xy 87.221366 -5.645572)
			(xy 87.15152 -5.675049) (xy 87.078937 -5.696935) (xy 87.004439 -5.710982) (xy 86.928869 -5.717031)
			(xy 86.853085 -5.715012) (xy 86.777945 -5.70495) (xy 86.7043 -5.686958) (xy 86.632984 -5.66124) (xy 86.564807 -5.628088)
			(xy 86.500539 -5.587876) (xy 86.44091 -5.541061) (xy 86.386594 -5.488173) (xy 86.338208 -5.429811)
			(xy 86.2963 -5.366636) (xy 86.261344 -5.299365) (xy 86.233737 -5.22876) (xy 86.213791 -5.155619)
			(xy 86.201732 -5.080774) (xy 86.197697 -5.00507) (xy 82.585544 -5.00507) (xy 82.636652 -5.04979)
			(xy 82.688076 -5.105494) (xy 82.733287 -5.166349) (xy 82.771774 -5.231664) (xy 82.8031 -5.3007) (xy 82.82691 -5.372675)
			(xy 82.842935 -5.446773) (xy 82.850994 -5.522154) (xy 82.851498 -5.56006) (xy 82.850994 -5.597966)
			(xy 82.842935 -5.673347) (xy 82.82691 -5.747445) (xy 82.8031 -5.81942) (xy 82.771774 -5.888456) (xy 82.733287 -5.953771)
			(xy 82.688076 -6.014626) (xy 82.636652 -6.07033) (xy 82.579599 -6.120252) (xy 82.517563 -6.163827)
			(xy 82.451246 -6.200562) (xy 82.3814 -6.230039) (xy 82.308817 -6.251925) (xy 82.234319 -6.265972)
			(xy 82.158749 -6.272021) (xy 82.082965 -6.270002) (xy 82.007825 -6.25994) (xy 81.93418 -6.241948)
			(xy 81.862864 -6.21623) (xy 81.794687 -6.183078) (xy 81.730419 -6.142866) (xy 81.67079 -6.096051)
			(xy 81.616474 -6.043163) (xy 81.568088 -5.984801) (xy 81.52618 -5.921626) (xy 81.491224 -5.854355)
			(xy 81.463617 -5.78375) (xy 81.443671 -5.710609) (xy 81.431612 -5.635764) (xy 81.427577 -5.56006)
			(xy 80.311498 -5.56006) (xy 80.310994 -5.597966) (xy 80.302935 -5.673347) (xy 80.28691 -5.747445)
			(xy 80.2631 -5.81942) (xy 80.231774 -5.888456) (xy 80.193287 -5.953771) (xy 80.148076 -6.014626)
			(xy 80.096652 -6.07033) (xy 80.039599 -6.120252) (xy 79.977563 -6.163827) (xy 79.911246 -6.200562)
			(xy 79.8414 -6.230039) (xy 79.768817 -6.251925) (xy 79.694319 -6.265972) (xy 79.618749 -6.272021)
			(xy 79.542965 -6.270002) (xy 79.467825 -6.25994) (xy 79.39418 -6.241948) (xy 79.322864 -6.21623)
			(xy 79.254687 -6.183078) (xy 79.190419 -6.142866) (xy 79.13079 -6.096051) (xy 79.076474 -6.043163)
			(xy 79.028088 -5.984801) (xy 78.98618 -5.921626) (xy 78.951224 -5.854355) (xy 78.923617 -5.78375)
			(xy 78.903671 -5.710609) (xy 78.891612 -5.635764) (xy 78.887577 -5.56006) (xy 77.771498 -5.56006)
			(xy 77.770994 -5.597966) (xy 77.762935 -5.673347) (xy 77.74691 -5.747445) (xy 77.7231 -5.81942) (xy 77.691774 -5.888456)
			(xy 77.653287 -5.953771) (xy 77.608076 -6.014626) (xy 77.556652 -6.07033) (xy 77.499599 -6.120252)
			(xy 77.437563 -6.163827) (xy 77.371246 -6.200562) (xy 77.3014 -6.230039) (xy 77.228817 -6.251925)
			(xy 77.154319 -6.265972) (xy 77.078749 -6.272021) (xy 77.002965 -6.270002) (xy 76.927825 -6.25994)
			(xy 76.85418 -6.241948) (xy 76.782864 -6.21623) (xy 76.714687 -6.183078) (xy 76.650419 -6.142866)
			(xy 76.59079 -6.096051) (xy 76.536474 -6.043163) (xy 76.488088 -5.984801) (xy 76.44618 -5.921626)
			(xy 76.411224 -5.854355) (xy 76.383617 -5.78375) (xy 76.363671 -5.710609) (xy 76.351612 -5.635764)
			(xy 76.347577 -5.56006) (xy 75.231498 -5.56006) (xy 75.230994 -5.597966) (xy 75.222935 -5.673347)
			(xy 75.20691 -5.747445) (xy 75.1831 -5.81942) (xy 75.151774 -5.888456) (xy 75.113287 -5.953771) (xy 75.068076 -6.014626)
			(xy 75.016652 -6.07033) (xy 74.959599 -6.120252) (xy 74.897563 -6.163827) (xy 74.831246 -6.200562)
			(xy 74.7614 -6.230039) (xy 74.688817 -6.251925) (xy 74.614319 -6.265972) (xy 74.538749 -6.272021)
			(xy 74.462965 -6.270002) (xy 74.387825 -6.25994) (xy 74.31418 -6.241948) (xy 74.242864 -6.21623)
			(xy 74.174687 -6.183078) (xy 74.110419 -6.142866) (xy 74.05079 -6.096051) (xy 73.996474 -6.043163)
			(xy 73.948088 -5.984801) (xy 73.90618 -5.921626) (xy 73.871224 -5.854355) (xy 73.843617 -5.78375)
			(xy 73.823671 -5.710609) (xy 73.811612 -5.635764) (xy 73.807577 -5.56006) (xy 72.691498 -5.56006)
			(xy 72.690994 -5.597966) (xy 72.682935 -5.673347) (xy 72.66691 -5.747445) (xy 72.6431 -5.81942) (xy 72.611774 -5.888456)
			(xy 72.573287 -5.953771) (xy 72.528076 -6.014626) (xy 72.476652 -6.07033) (xy 72.419599 -6.120252)
			(xy 72.357563 -6.163827) (xy 72.291246 -6.200562) (xy 72.2214 -6.230039) (xy 72.148817 -6.251925)
			(xy 72.074319 -6.265972) (xy 71.998749 -6.272021) (xy 71.922965 -6.270002) (xy 71.847825 -6.25994)
			(xy 71.77418 -6.241948) (xy 71.702864 -6.21623) (xy 71.634687 -6.183078) (xy 71.570419 -6.142866)
			(xy 71.51079 -6.096051) (xy 71.456474 -6.043163) (xy 71.408088 -5.984801) (xy 71.36618 -5.921626)
			(xy 71.331224 -5.854355) (xy 71.303617 -5.78375) (xy 71.283671 -5.710609) (xy 71.271612 -5.635764)
			(xy 71.267577 -5.56006) (xy 70.151498 -5.56006) (xy 70.150994 -5.597966) (xy 70.142935 -5.673347)
			(xy 70.12691 -5.747445) (xy 70.1031 -5.81942) (xy 70.071774 -5.888456) (xy 70.033287 -5.953771) (xy 69.988076 -6.014626)
			(xy 69.936652 -6.07033) (xy 69.879599 -6.120252) (xy 69.817563 -6.163827) (xy 69.751246 -6.200562)
			(xy 69.6814 -6.230039) (xy 69.608817 -6.251925) (xy 69.534319 -6.265972) (xy 69.458749 -6.272021)
			(xy 69.382965 -6.270002) (xy 69.307825 -6.25994) (xy 69.23418 -6.241948) (xy 69.162864 -6.21623)
			(xy 69.094687 -6.183078) (xy 69.030419 -6.142866) (xy 68.97079 -6.096051) (xy 68.916474 -6.043163)
			(xy 68.868088 -5.984801) (xy 68.82618 -5.921626) (xy 68.791224 -5.854355) (xy 68.763617 -5.78375)
			(xy 68.743671 -5.710609) (xy 68.731612 -5.635764) (xy 68.727577 -5.56006) (xy 67.611498 -5.56006)
			(xy 67.610994 -5.597966) (xy 67.602935 -5.673347) (xy 67.58691 -5.747445) (xy 67.5631 -5.81942) (xy 67.531774 -5.888456)
			(xy 67.493287 -5.953771) (xy 67.448076 -6.014626) (xy 67.396652 -6.07033) (xy 67.339599 -6.120252)
			(xy 67.277563 -6.163827) (xy 67.211246 -6.200562) (xy 67.1414 -6.230039) (xy 67.068817 -6.251925)
			(xy 66.994319 -6.265972) (xy 66.918749 -6.272021) (xy 66.842965 -6.270002) (xy 66.767825 -6.25994)
			(xy 66.69418 -6.241948) (xy 66.622864 -6.21623) (xy 66.554687 -6.183078) (xy 66.490419 -6.142866)
			(xy 66.43079 -6.096051) (xy 66.376474 -6.043163) (xy 66.328088 -5.984801) (xy 66.28618 -5.921626)
			(xy 66.251224 -5.854355) (xy 66.223617 -5.78375) (xy 66.203671 -5.710609) (xy 66.191612 -5.635764)
			(xy 66.187577 -5.56006) (xy 65.071498 -5.56006) (xy 65.070994 -5.597966) (xy 65.062935 -5.673347)
			(xy 65.04691 -5.747445) (xy 65.0231 -5.81942) (xy 64.991774 -5.888456) (xy 64.953287 -5.953771) (xy 64.908076 -6.014626)
			(xy 64.856652 -6.07033) (xy 64.799599 -6.120252) (xy 64.737563 -6.163827) (xy 64.671246 -6.200562)
			(xy 64.6014 -6.230039) (xy 64.528817 -6.251925) (xy 64.454319 -6.265972) (xy 64.378749 -6.272021)
			(xy 64.302965 -6.270002) (xy 64.227825 -6.25994) (xy 64.15418 -6.241948) (xy 64.082864 -6.21623)
			(xy 64.014687 -6.183078) (xy 63.950419 -6.142866) (xy 63.89079 -6.096051) (xy 63.836474 -6.043163)
			(xy 63.788088 -5.984801) (xy 63.74618 -5.921626) (xy 63.711224 -5.854355) (xy 63.683617 -5.78375)
			(xy 63.663671 -5.710609) (xy 63.651612 -5.635764) (xy 63.647577 -5.56006) (xy 42.50107 -5.56006)
			(xy 42.515537 -5.570272) (xy 42.604599 -5.64273) (xy 42.68851 -5.721096) (xy 42.766876 -5.805007)
			(xy 42.839334 -5.894069) (xy 42.905545 -5.987869) (xy 42.9652 -6.085968) (xy 43.018022 -6.18791)
			(xy 43.055881 -6.27507) (xy 84.927697 -6.27507) (xy 84.931732 -6.199366) (xy 84.943791 -6.124521)
			(xy 84.963737 -6.05138) (xy 84.991344 -5.980775) (xy 85.0263 -5.913504) (xy 85.068208 -5.850329)
			(xy 85.116594 -5.791967) (xy 85.17091 -5.739079) (xy 85.230539 -5.692264) (xy 85.294807 -5.652052)
			(xy 85.362984 -5.6189) (xy 85.4343 -5.593182) (xy 85.507945 -5.57519) (xy 85.583085 -5.565128) (xy 85.658869 -5.563109)
			(xy 85.734439 -5.569158) (xy 85.808937 -5.583205) (xy 85.88152 -5.605091) (xy 85.951366 -5.634568)
			(xy 86.017683 -5.671303) (xy 86.079719 -5.714878) (xy 86.136772 -5.7648) (xy 86.188196 -5.820504)
			(xy 86.233407 -5.881359) (xy 86.271894 -5.946674) (xy 86.30322 -6.01571) (xy 86.32703 -6.087685)
			(xy 86.343055 -6.161783) (xy 86.351114 -6.237164) (xy 86.351618 -6.27507) (xy 86.351114 -6.312976)
			(xy 86.343055 -6.388357) (xy 86.32703 -6.462455) (xy 86.30322 -6.53443) (xy 86.271894 -6.603466)
			(xy 86.233407 -6.668781) (xy 86.188196 -6.729636) (xy 86.136772 -6.78534) (xy 86.079719 -6.835262)
			(xy 86.017683 -6.878837) (xy 85.951366 -6.915572) (xy 85.88152 -6.945049) (xy 85.808937 -6.966935)
			(xy 85.734439 -6.980982) (xy 85.658869 -6.987031) (xy 85.583085 -6.985012) (xy 85.507945 -6.97495)
			(xy 85.4343 -6.956958) (xy 85.362984 -6.93124) (xy 85.294807 -6.898088) (xy 85.230539 -6.857876)
			(xy 85.17091 -6.811061) (xy 85.116594 -6.758173) (xy 85.068208 -6.699811) (xy 85.0263 -6.636636)
			(xy 84.991344 -6.569365) (xy 84.963737 -6.49876) (xy 84.943791 -6.425619) (xy 84.931732 -6.350774)
			(xy 84.927697 -6.27507) (xy 43.055881 -6.27507) (xy 43.063764 -6.293218) (xy 43.102213 -6.401403)
			(xy 43.13319 -6.51196) (xy 43.156549 -6.624372) (xy 43.172183 -6.738117) (xy 43.180018 -6.852663)
			(xy 43.180508 -6.91007) (xy 43.180381 -6.943251) (xy 43.177842 -7.009565) (xy 43.175428 -7.042658)
			(xy 43.170272 -7.100942) (xy 43.152948 -7.216671) (xy 43.127616 -7.330914) (xy 43.094401 -7.443119)
			(xy 43.056327 -7.54507) (xy 86.197697 -7.54507) (xy 86.201732 -7.469366) (xy 86.213791 -7.394521)
			(xy 86.233737 -7.32138) (xy 86.261344 -7.250775) (xy 86.2963 -7.183504) (xy 86.338208 -7.120329)
			(xy 86.386594 -7.061967) (xy 86.44091 -7.009079) (xy 86.500539 -6.962264) (xy 86.564807 -6.922052)
			(xy 86.632984 -6.8889) (xy 86.7043 -6.863182) (xy 86.777945 -6.84519) (xy 86.853085 -6.835128) (xy 86.928869 -6.833109)
			(xy 87.004439 -6.839158) (xy 87.078937 -6.853205) (xy 87.15152 -6.875091) (xy 87.221366 -6.904568)
			(xy 87.287683 -6.941303) (xy 87.349719 -6.984878) (xy 87.406772 -7.0348) (xy 87.458196 -7.090504)
			(xy 87.503407 -7.151359) (xy 87.541894 -7.216674) (xy 87.57322 -7.28571) (xy 87.59703 -7.357685)
			(xy 87.613055 -7.431783) (xy 87.621114 -7.507164) (xy 87.621618 -7.54507) (xy 87.621114 -7.582976)
			(xy 87.613055 -7.658357) (xy 87.59703 -7.732455) (xy 87.57322 -7.80443) (xy 87.541894 -7.873466)
			(xy 87.503407 -7.938781) (xy 87.458196 -7.999636) (xy 87.406772 -8.05534) (xy 87.349719 -8.105262)
			(xy 87.287683 -8.148837) (xy 87.221366 -8.185572) (xy 87.15152 -8.215049) (xy 87.078937 -8.236935)
			(xy 87.004439 -8.250982) (xy 86.928869 -8.257031) (xy 86.853085 -8.255012) (xy 86.777945 -8.24495)
			(xy 86.7043 -8.226958) (xy 86.632984 -8.20124) (xy 86.564807 -8.168088) (xy 86.500539 -8.127876)
			(xy 86.44091 -8.081061) (xy 86.386594 -8.028173) (xy 86.338208 -7.969811) (xy 86.2963 -7.906636)
			(xy 86.261344 -7.839365) (xy 86.233737 -7.76876) (xy 86.213791 -7.695619) (xy 86.201732 -7.620774)
			(xy 86.197697 -7.54507) (xy 43.056327 -7.54507) (xy 43.053462 -7.552742) (xy 43.004999 -7.659253)
			(xy 42.949245 -7.762135) (xy 42.886471 -7.860891) (xy 42.816981 -7.955042) (xy 42.741111 -8.044132)
			(xy 42.659229 -8.127729) (xy 42.571732 -8.20543) (xy 42.500813 -8.26008) (xy 63.647577 -8.26008)
			(xy 63.651612 -8.184376) (xy 63.663671 -8.109531) (xy 63.683617 -8.03639) (xy 63.711224 -7.965785)
			(xy 63.74618 -7.898514) (xy 63.788088 -7.835339) (xy 63.836474 -7.776977) (xy 63.89079 -7.724089)
			(xy 63.950419 -7.677274) (xy 64.014687 -7.637062) (xy 64.082864 -7.60391) (xy 64.15418 -7.578192)
			(xy 64.227825 -7.5602) (xy 64.302965 -7.550138) (xy 64.378749 -7.548119) (xy 64.454319 -7.554168)
			(xy 64.528817 -7.568215) (xy 64.6014 -7.590101) (xy 64.671246 -7.619578) (xy 64.737563 -7.656313)
			(xy 64.799599 -7.699888) (xy 64.856652 -7.74981) (xy 64.908076 -7.805514) (xy 64.953287 -7.866369)
			(xy 64.991774 -7.931684) (xy 65.0231 -8.00072) (xy 65.04691 -8.072695) (xy 65.062935 -8.146793) (xy 65.070994 -8.222174)
			(xy 65.071498 -8.26008) (xy 66.187577 -8.26008) (xy 66.191612 -8.184376) (xy 66.203671 -8.109531)
			(xy 66.223617 -8.03639) (xy 66.251224 -7.965785) (xy 66.28618 -7.898514) (xy 66.328088 -7.835339)
			(xy 66.376474 -7.776977) (xy 66.43079 -7.724089) (xy 66.490419 -7.677274) (xy 66.554687 -7.637062)
			(xy 66.622864 -7.60391) (xy 66.69418 -7.578192) (xy 66.767825 -7.5602) (xy 66.842965 -7.550138) (xy 66.918749 -7.548119)
			(xy 66.994319 -7.554168) (xy 67.068817 -7.568215) (xy 67.1414 -7.590101) (xy 67.211246 -7.619578)
			(xy 67.277563 -7.656313) (xy 67.339599 -7.699888) (xy 67.396652 -7.74981) (xy 67.448076 -7.805514)
			(xy 67.493287 -7.866369) (xy 67.531774 -7.931684) (xy 67.5631 -8.00072) (xy 67.58691 -8.072695) (xy 67.602935 -8.146793)
			(xy 67.610994 -8.222174) (xy 67.611498 -8.26008) (xy 68.727577 -8.26008) (xy 68.731612 -8.184376)
			(xy 68.743671 -8.109531) (xy 68.763617 -8.03639) (xy 68.791224 -7.965785) (xy 68.82618 -7.898514)
			(xy 68.868088 -7.835339) (xy 68.916474 -7.776977) (xy 68.97079 -7.724089) (xy 69.030419 -7.677274)
			(xy 69.094687 -7.637062) (xy 69.162864 -7.60391) (xy 69.23418 -7.578192) (xy 69.307825 -7.5602) (xy 69.382965 -7.550138)
			(xy 69.458749 -7.548119) (xy 69.534319 -7.554168) (xy 69.608817 -7.568215) (xy 69.6814 -7.590101)
			(xy 69.751246 -7.619578) (xy 69.817563 -7.656313) (xy 69.879599 -7.699888) (xy 69.936652 -7.74981)
			(xy 69.988076 -7.805514) (xy 70.033287 -7.866369) (xy 70.071774 -7.931684) (xy 70.1031 -8.00072)
			(xy 70.12691 -8.072695) (xy 70.142935 -8.146793) (xy 70.150994 -8.222174) (xy 70.151498 -8.26008)
			(xy 71.267577 -8.26008) (xy 71.271612 -8.184376) (xy 71.283671 -8.109531) (xy 71.303617 -8.03639)
			(xy 71.331224 -7.965785) (xy 71.36618 -7.898514) (xy 71.408088 -7.835339) (xy 71.456474 -7.776977)
			(xy 71.51079 -7.724089) (xy 71.570419 -7.677274) (xy 71.634687 -7.637062) (xy 71.702864 -7.60391)
			(xy 71.77418 -7.578192) (xy 71.847825 -7.5602) (xy 71.922965 -7.550138) (xy 71.998749 -7.548119)
			(xy 72.074319 -7.554168) (xy 72.148817 -7.568215) (xy 72.2214 -7.590101) (xy 72.291246 -7.619578)
			(xy 72.357563 -7.656313) (xy 72.419599 -7.699888) (xy 72.476652 -7.74981) (xy 72.528076 -7.805514)
			(xy 72.573287 -7.866369) (xy 72.611774 -7.931684) (xy 72.6431 -8.00072) (xy 72.66691 -8.072695) (xy 72.682935 -8.146793)
			(xy 72.690994 -8.222174) (xy 72.691498 -8.26008) (xy 73.807577 -8.26008) (xy 73.811612 -8.184376)
			(xy 73.823671 -8.109531) (xy 73.843617 -8.03639) (xy 73.871224 -7.965785) (xy 73.90618 -7.898514)
			(xy 73.948088 -7.835339) (xy 73.996474 -7.776977) (xy 74.05079 -7.724089) (xy 74.110419 -7.677274)
			(xy 74.174687 -7.637062) (xy 74.242864 -7.60391) (xy 74.31418 -7.578192) (xy 74.387825 -7.5602) (xy 74.462965 -7.550138)
			(xy 74.538749 -7.548119) (xy 74.614319 -7.554168) (xy 74.688817 -7.568215) (xy 74.7614 -7.590101)
			(xy 74.831246 -7.619578) (xy 74.897563 -7.656313) (xy 74.959599 -7.699888) (xy 75.016652 -7.74981)
			(xy 75.068076 -7.805514) (xy 75.113287 -7.866369) (xy 75.151774 -7.931684) (xy 75.1831 -8.00072)
			(xy 75.20691 -8.072695) (xy 75.222935 -8.146793) (xy 75.230994 -8.222174) (xy 75.231498 -8.26008)
			(xy 76.347577 -8.26008) (xy 76.351612 -8.184376) (xy 76.363671 -8.109531) (xy 76.383617 -8.03639)
			(xy 76.411224 -7.965785) (xy 76.44618 -7.898514) (xy 76.488088 -7.835339) (xy 76.536474 -7.776977)
			(xy 76.59079 -7.724089) (xy 76.650419 -7.677274) (xy 76.714687 -7.637062) (xy 76.782864 -7.60391)
			(xy 76.85418 -7.578192) (xy 76.927825 -7.5602) (xy 77.002965 -7.550138) (xy 77.078749 -7.548119)
			(xy 77.154319 -7.554168) (xy 77.228817 -7.568215) (xy 77.3014 -7.590101) (xy 77.371246 -7.619578)
			(xy 77.437563 -7.656313) (xy 77.499599 -7.699888) (xy 77.556652 -7.74981) (xy 77.608076 -7.805514)
			(xy 77.653287 -7.866369) (xy 77.691774 -7.931684) (xy 77.7231 -8.00072) (xy 77.74691 -8.072695) (xy 77.762935 -8.146793)
			(xy 77.770994 -8.222174) (xy 77.771498 -8.26008) (xy 78.887577 -8.26008) (xy 78.891612 -8.184376)
			(xy 78.903671 -8.109531) (xy 78.923617 -8.03639) (xy 78.951224 -7.965785) (xy 78.98618 -7.898514)
			(xy 79.028088 -7.835339) (xy 79.076474 -7.776977) (xy 79.13079 -7.724089) (xy 79.190419 -7.677274)
			(xy 79.254687 -7.637062) (xy 79.322864 -7.60391) (xy 79.39418 -7.578192) (xy 79.467825 -7.5602) (xy 79.542965 -7.550138)
			(xy 79.618749 -7.548119) (xy 79.694319 -7.554168) (xy 79.768817 -7.568215) (xy 79.8414 -7.590101)
			(xy 79.911246 -7.619578) (xy 79.977563 -7.656313) (xy 80.039599 -7.699888) (xy 80.096652 -7.74981)
			(xy 80.148076 -7.805514) (xy 80.193287 -7.866369) (xy 80.231774 -7.931684) (xy 80.2631 -8.00072)
			(xy 80.28691 -8.072695) (xy 80.302935 -8.146793) (xy 80.310994 -8.222174) (xy 80.311498 -8.26008)
			(xy 81.427577 -8.26008) (xy 81.431612 -8.184376) (xy 81.443671 -8.109531) (xy 81.463617 -8.03639)
			(xy 81.491224 -7.965785) (xy 81.52618 -7.898514) (xy 81.568088 -7.835339) (xy 81.616474 -7.776977)
			(xy 81.67079 -7.724089) (xy 81.730419 -7.677274) (xy 81.794687 -7.637062) (xy 81.862864 -7.60391)
			(xy 81.93418 -7.578192) (xy 82.007825 -7.5602) (xy 82.082965 -7.550138) (xy 82.158749 -7.548119)
			(xy 82.234319 -7.554168) (xy 82.308817 -7.568215) (xy 82.3814 -7.590101) (xy 82.451246 -7.619578)
			(xy 82.517563 -7.656313) (xy 82.579599 -7.699888) (xy 82.636652 -7.74981) (xy 82.688076 -7.805514)
			(xy 82.733287 -7.866369) (xy 82.771774 -7.931684) (xy 82.8031 -8.00072) (xy 82.82691 -8.072695) (xy 82.842935 -8.146793)
			(xy 82.850994 -8.222174) (xy 82.851498 -8.26008) (xy 82.850994 -8.297986) (xy 82.842935 -8.373367)
			(xy 82.82691 -8.447465) (xy 82.8031 -8.51944) (xy 82.771774 -8.588476) (xy 82.733287 -8.653791) (xy 82.688076 -8.714646)
			(xy 82.636652 -8.77035) (xy 82.585544 -8.81507) (xy 84.927697 -8.81507) (xy 84.931732 -8.739366)
			(xy 84.943791 -8.664521) (xy 84.963737 -8.59138) (xy 84.991344 -8.520775) (xy 85.0263 -8.453504)
			(xy 85.068208 -8.390329) (xy 85.116594 -8.331967) (xy 85.17091 -8.279079) (xy 85.230539 -8.232264)
			(xy 85.294807 -8.192052) (xy 85.362984 -8.1589) (xy 85.4343 -8.133182) (xy 85.507945 -8.11519) (xy 85.583085 -8.105128)
			(xy 85.658869 -8.103109) (xy 85.734439 -8.109158) (xy 85.808937 -8.123205) (xy 85.88152 -8.145091)
			(xy 85.951366 -8.174568) (xy 86.017683 -8.211303) (xy 86.079719 -8.254878) (xy 86.136772 -8.3048)
			(xy 86.188196 -8.360504) (xy 86.233407 -8.421359) (xy 86.271894 -8.486674) (xy 86.30322 -8.55571)
			(xy 86.32703 -8.627685) (xy 86.343055 -8.701783) (xy 86.351114 -8.777164) (xy 86.351618 -8.81507)
			(xy 86.351114 -8.852976) (xy 86.343055 -8.928357) (xy 86.32703 -9.002455) (xy 86.30322 -9.07443)
			(xy 86.271894 -9.143466) (xy 86.233407 -9.208781) (xy 86.188196 -9.269636) (xy 86.136772 -9.32534)
			(xy 86.079719 -9.375262) (xy 86.017683 -9.418837) (xy 85.951366 -9.455572) (xy 85.88152 -9.485049)
			(xy 85.808937 -9.506935) (xy 85.734439 -9.520982) (xy 85.658869 -9.527031) (xy 85.583085 -9.525012)
			(xy 85.507945 -9.51495) (xy 85.4343 -9.496958) (xy 85.362984 -9.47124) (xy 85.294807 -9.438088) (xy 85.230539 -9.397876)
			(xy 85.17091 -9.351061) (xy 85.116594 -9.298173) (xy 85.068208 -9.239811) (xy 85.0263 -9.176636)
			(xy 84.991344 -9.109365) (xy 84.963737 -9.03876) (xy 84.943791 -8.965619) (xy 84.931732 -8.890774)
			(xy 84.927697 -8.81507) (xy 82.585544 -8.81507) (xy 82.579599 -8.820272) (xy 82.517563 -8.863847)
			(xy 82.451246 -8.900582) (xy 82.3814 -8.930059) (xy 82.308817 -8.951945) (xy 82.234319 -8.965992)
			(xy 82.158749 -8.972041) (xy 82.082965 -8.970022) (xy 82.007825 -8.95996) (xy 81.93418 -8.941968)
			(xy 81.862864 -8.91625) (xy 81.794687 -8.883098) (xy 81.730419 -8.842886) (xy 81.67079 -8.796071)
			(xy 81.616474 -8.743183) (xy 81.568088 -8.684821) (xy 81.52618 -8.621646) (xy 81.491224 -8.554375)
			(xy 81.463617 -8.48377) (xy 81.443671 -8.410629) (xy 81.431612 -8.335784) (xy 81.427577 -8.26008)
			(xy 80.311498 -8.26008) (xy 80.310994 -8.297986) (xy 80.302935 -8.373367) (xy 80.28691 -8.447465)
			(xy 80.2631 -8.51944) (xy 80.231774 -8.588476) (xy 80.193287 -8.653791) (xy 80.148076 -8.714646)
			(xy 80.096652 -8.77035) (xy 80.039599 -8.820272) (xy 79.977563 -8.863847) (xy 79.911246 -8.900582)
			(xy 79.8414 -8.930059) (xy 79.768817 -8.951945) (xy 79.694319 -8.965992) (xy 79.618749 -8.972041)
			(xy 79.542965 -8.970022) (xy 79.467825 -8.95996) (xy 79.39418 -8.941968) (xy 79.322864 -8.91625)
			(xy 79.254687 -8.883098) (xy 79.190419 -8.842886) (xy 79.13079 -8.796071) (xy 79.076474 -8.743183)
			(xy 79.028088 -8.684821) (xy 78.98618 -8.621646) (xy 78.951224 -8.554375) (xy 78.923617 -8.48377)
			(xy 78.903671 -8.410629) (xy 78.891612 -8.335784) (xy 78.887577 -8.26008) (xy 77.771498 -8.26008)
			(xy 77.770994 -8.297986) (xy 77.762935 -8.373367) (xy 77.74691 -8.447465) (xy 77.7231 -8.51944) (xy 77.691774 -8.588476)
			(xy 77.653287 -8.653791) (xy 77.608076 -8.714646) (xy 77.556652 -8.77035) (xy 77.499599 -8.820272)
			(xy 77.437563 -8.863847) (xy 77.371246 -8.900582) (xy 77.3014 -8.930059) (xy 77.228817 -8.951945)
			(xy 77.154319 -8.965992) (xy 77.078749 -8.972041) (xy 77.002965 -8.970022) (xy 76.927825 -8.95996)
			(xy 76.85418 -8.941968) (xy 76.782864 -8.91625) (xy 76.714687 -8.883098) (xy 76.650419 -8.842886)
			(xy 76.59079 -8.796071) (xy 76.536474 -8.743183) (xy 76.488088 -8.684821) (xy 76.44618 -8.621646)
			(xy 76.411224 -8.554375) (xy 76.383617 -8.48377) (xy 76.363671 -8.410629) (xy 76.351612 -8.335784)
			(xy 76.347577 -8.26008) (xy 75.231498 -8.26008) (xy 75.230994 -8.297986) (xy 75.222935 -8.373367)
			(xy 75.20691 -8.447465) (xy 75.1831 -8.51944) (xy 75.151774 -8.588476) (xy 75.113287 -8.653791) (xy 75.068076 -8.714646)
			(xy 75.016652 -8.77035) (xy 74.959599 -8.820272) (xy 74.897563 -8.863847) (xy 74.831246 -8.900582)
			(xy 74.7614 -8.930059) (xy 74.688817 -8.951945) (xy 74.614319 -8.965992) (xy 74.538749 -8.972041)
			(xy 74.462965 -8.970022) (xy 74.387825 -8.95996) (xy 74.31418 -8.941968) (xy 74.242864 -8.91625)
			(xy 74.174687 -8.883098) (xy 74.110419 -8.842886) (xy 74.05079 -8.796071) (xy 73.996474 -8.743183)
			(xy 73.948088 -8.684821) (xy 73.90618 -8.621646) (xy 73.871224 -8.554375) (xy 73.843617 -8.48377)
			(xy 73.823671 -8.410629) (xy 73.811612 -8.335784) (xy 73.807577 -8.26008) (xy 72.691498 -8.26008)
			(xy 72.690994 -8.297986) (xy 72.682935 -8.373367) (xy 72.66691 -8.447465) (xy 72.6431 -8.51944) (xy 72.611774 -8.588476)
			(xy 72.573287 -8.653791) (xy 72.528076 -8.714646) (xy 72.476652 -8.77035) (xy 72.419599 -8.820272)
			(xy 72.357563 -8.863847) (xy 72.291246 -8.900582) (xy 72.2214 -8.930059) (xy 72.148817 -8.951945)
			(xy 72.074319 -8.965992) (xy 71.998749 -8.972041) (xy 71.922965 -8.970022) (xy 71.847825 -8.95996)
			(xy 71.77418 -8.941968) (xy 71.702864 -8.91625) (xy 71.634687 -8.883098) (xy 71.570419 -8.842886)
			(xy 71.51079 -8.796071) (xy 71.456474 -8.743183) (xy 71.408088 -8.684821) (xy 71.36618 -8.621646)
			(xy 71.331224 -8.554375) (xy 71.303617 -8.48377) (xy 71.283671 -8.410629) (xy 71.271612 -8.335784)
			(xy 71.267577 -8.26008) (xy 70.151498 -8.26008) (xy 70.150994 -8.297986) (xy 70.142935 -8.373367)
			(xy 70.12691 -8.447465) (xy 70.1031 -8.51944) (xy 70.071774 -8.588476) (xy 70.033287 -8.653791) (xy 69.988076 -8.714646)
			(xy 69.936652 -8.77035) (xy 69.879599 -8.820272) (xy 69.817563 -8.863847) (xy 69.751246 -8.900582)
			(xy 69.6814 -8.930059) (xy 69.608817 -8.951945) (xy 69.534319 -8.965992) (xy 69.458749 -8.972041)
			(xy 69.382965 -8.970022) (xy 69.307825 -8.95996) (xy 69.23418 -8.941968) (xy 69.162864 -8.91625)
			(xy 69.094687 -8.883098) (xy 69.030419 -8.842886) (xy 68.97079 -8.796071) (xy 68.916474 -8.743183)
			(xy 68.868088 -8.684821) (xy 68.82618 -8.621646) (xy 68.791224 -8.554375) (xy 68.763617 -8.48377)
			(xy 68.743671 -8.410629) (xy 68.731612 -8.335784) (xy 68.727577 -8.26008) (xy 67.611498 -8.26008)
			(xy 67.610994 -8.297986) (xy 67.602935 -8.373367) (xy 67.58691 -8.447465) (xy 67.5631 -8.51944) (xy 67.531774 -8.588476)
			(xy 67.493287 -8.653791) (xy 67.448076 -8.714646) (xy 67.396652 -8.77035) (xy 67.339599 -8.820272)
			(xy 67.277563 -8.863847) (xy 67.211246 -8.900582) (xy 67.1414 -8.930059) (xy 67.068817 -8.951945)
			(xy 66.994319 -8.965992) (xy 66.918749 -8.972041) (xy 66.842965 -8.970022) (xy 66.767825 -8.95996)
			(xy 66.69418 -8.941968) (xy 66.622864 -8.91625) (xy 66.554687 -8.883098) (xy 66.490419 -8.842886)
			(xy 66.43079 -8.796071) (xy 66.376474 -8.743183) (xy 66.328088 -8.684821) (xy 66.28618 -8.621646)
			(xy 66.251224 -8.554375) (xy 66.223617 -8.48377) (xy 66.203671 -8.410629) (xy 66.191612 -8.335784)
			(xy 66.187577 -8.26008) (xy 65.071498 -8.26008) (xy 65.070994 -8.297986) (xy 65.062935 -8.373367)
			(xy 65.04691 -8.447465) (xy 65.0231 -8.51944) (xy 64.991774 -8.588476) (xy 64.953287 -8.653791) (xy 64.908076 -8.714646)
			(xy 64.856652 -8.77035) (xy 64.799599 -8.820272) (xy 64.737563 -8.863847) (xy 64.671246 -8.900582)
			(xy 64.6014 -8.930059) (xy 64.528817 -8.951945) (xy 64.454319 -8.965992) (xy 64.378749 -8.972041)
			(xy 64.302965 -8.970022) (xy 64.227825 -8.95996) (xy 64.15418 -8.941968) (xy 64.082864 -8.91625)
			(xy 64.014687 -8.883098) (xy 63.950419 -8.842886) (xy 63.89079 -8.796071) (xy 63.836474 -8.743183)
			(xy 63.788088 -8.684821) (xy 63.74618 -8.621646) (xy 63.711224 -8.554375) (xy 63.683617 -8.48377)
			(xy 63.663671 -8.410629) (xy 63.651612 -8.335784) (xy 63.647577 -8.26008) (xy 42.500813 -8.26008)
			(xy 42.479042 -8.276857) (xy 42.381609 -8.341665) (xy 42.279905 -8.39954) (xy 42.174422 -8.450202)
			(xy 42.065671 -8.493404) (xy 41.954179 -8.528939) (xy 41.840485 -8.556634) (xy 41.725141 -8.576354)
			(xy 41.608704 -8.588005) (xy 41.491739 -8.59153) (xy 41.374812 -8.586912) (xy 41.258489 -8.574173)
			(xy 41.143334 -8.553375) (xy 41.029905 -8.524618) (xy 40.91875 -8.488042) (xy 40.810407 -8.443825)
			(xy 40.705403 -8.392179) (xy 40.604244 -8.333356) (xy 40.507421 -8.26764) (xy 40.415403 -8.195349)
			(xy 40.328636 -8.116834) (xy 40.247539 -8.032474) (xy 40.172506 -7.942679) (xy 40.103899 -7.847883)
			(xy 40.042051 -7.748544) (xy 39.987262 -7.645145) (xy 39.939796 -7.538186) (xy 39.899884 -7.428185)
			(xy 39.86772 -7.315674) (xy 39.843457 -7.201199) (xy 39.827215 -7.085313) (xy 39.819072 -6.968579)
			(xy 39.818564 -6.91007) (xy 37.41166 -6.91007) (xy 37.41166 -12.33726) (xy 64.785847 -12.33726) (xy 64.789739 -12.282905)
			(xy 64.801327 -12.229658) (xy 64.820375 -12.178602) (xy 64.846496 -12.130776) (xy 64.862456 -12.108688)
			(xy 64.876065 -12.089684) (xy 64.8968 -12.0478) (xy 64.909527 -12.002829) (xy 64.913816 -11.95629)
			(xy 64.909523 -11.909752) (xy 64.896793 -11.864782) (xy 64.876055 -11.822899) (xy 64.862456 -11.803888)
			(xy 64.846496 -11.7818) (xy 64.820375 -11.733974) (xy 64.801327 -11.682918) (xy 64.789739 -11.629671)
			(xy 64.785847 -11.575316) (xy 64.789731 -11.520961) (xy 64.801311 -11.467712) (xy 64.820352 -11.416653)
			(xy 64.846466 -11.368823) (xy 64.879121 -11.325197) (xy 64.917652 -11.286663) (xy 64.961276 -11.254005)
			(xy 65.009103 -11.227888) (xy 65.060161 -11.208843) (xy 65.113409 -11.197259) (xy 65.167764 -11.193371)
			(xy 65.222119 -11.197259) (xy 65.275367 -11.208843) (xy 65.326425 -11.227888) (xy 65.374252 -11.254005)
			(xy 65.417876 -11.286663) (xy 65.456407 -11.325197) (xy 65.489062 -11.368823) (xy 65.515176 -11.416653)
			(xy 65.534217 -11.467712) (xy 65.545797 -11.520961) (xy 65.549681 -11.575316) (xy 65.545789 -11.629671)
			(xy 65.534201 -11.682918) (xy 65.515153 -11.733974) (xy 65.489032 -11.7818) (xy 65.473072 -11.803888)
			(xy 65.459489 -11.822908) (xy 65.438758 -11.86479) (xy 65.426032 -11.909756) (xy 65.421741 -11.95629)
			(xy 65.426029 -12.002825) (xy 65.438751 -12.047792) (xy 65.459479 -12.089675) (xy 65.473072 -12.108688)
			(xy 65.489032 -12.130776) (xy 65.515153 -12.178602) (xy 65.534201 -12.229658) (xy 65.545789 -12.282905)
			(xy 65.549681 -12.33726) (xy 66.700499 -12.33726) (xy 66.704391 -12.282905) (xy 66.715979 -12.229658)
			(xy 66.735027 -12.178602) (xy 66.761148 -12.130776) (xy 66.777108 -12.108688) (xy 66.790714 -12.089683)
			(xy 66.811445 -12.047798) (xy 66.824169 -12.002828) (xy 66.828458 -11.95629) (xy 66.824166 -11.909753)
			(xy 66.811438 -11.864784) (xy 66.790704 -11.8229) (xy 66.777108 -11.803888) (xy 66.761148 -11.7818)
			(xy 66.735027 -11.733974) (xy 66.715979 -11.682918) (xy 66.704391 -11.629671) (xy 66.700499 -11.575316)
			(xy 66.704383 -11.520961) (xy 66.715963 -11.467712) (xy 66.735004 -11.416653) (xy 66.761118 -11.368823)
			(xy 66.793773 -11.325197) (xy 66.832304 -11.286663) (xy 66.875928 -11.254005) (xy 66.923755 -11.227888)
			(xy 66.974813 -11.208843) (xy 67.028061 -11.197259) (xy 67.082416 -11.193371) (xy 67.136771 -11.197259)
			(xy 67.190019 -11.208843) (xy 67.241077 -11.227888) (xy 67.288904 -11.254005) (xy 67.332528 -11.286663)
			(xy 67.371059 -11.325197) (xy 67.403714 -11.368823) (xy 67.429828 -11.416653) (xy 67.448869 -11.467712)
			(xy 67.460449 -11.520961) (xy 67.464333 -11.575316) (xy 67.460441 -11.629671) (xy 67.448853 -11.682918)
			(xy 67.429805 -11.733974) (xy 67.403684 -11.7818) (xy 67.387724 -11.803888) (xy 67.374138 -11.822907)
			(xy 67.353403 -11.864788) (xy 67.340675 -11.909755) (xy 67.336382 -11.95629) (xy 67.340671 -12.002826)
			(xy 67.353396 -12.047794) (xy 67.374128 -12.089676) (xy 67.387724 -12.108688) (xy 67.403684 -12.130776)
			(xy 67.429805 -12.178602) (xy 67.448853 -12.229658) (xy 67.460441 -12.282905) (xy 67.464333 -12.33726)
			(xy 68.597371 -12.33726) (xy 68.601263 -12.282905) (xy 68.612851 -12.229658) (xy 68.631899 -12.178602)
			(xy 68.65802 -12.130776) (xy 68.67398 -12.108688) (xy 68.687588 -12.089684) (xy 68.708321 -12.047799)
			(xy 68.721046 -12.002829) (xy 68.725335 -11.95629) (xy 68.721043 -11.909752) (xy 68.708314 -11.864783)
			(xy 68.687578 -11.8229) (xy 68.67398 -11.803888) (xy 68.65802 -11.7818) (xy 68.631899 -11.733974)
			(xy 68.612851 -11.682918) (xy 68.601263 -11.629671) (xy 68.597371 -11.575316) (xy 68.601255 -11.520961)
			(xy 68.612835 -11.467712) (xy 68.631876 -11.416653) (xy 68.65799 -11.368823) (xy 68.690645 -11.325197)
			(xy 68.729176 -11.286663) (xy 68.7728 -11.254005) (xy 68.820627 -11.227888) (xy 68.871685 -11.208843)
			(xy 68.924933 -11.197259) (xy 68.979288 -11.193371) (xy 69.033643 -11.197259) (xy 69.086891 -11.208843)
			(xy 69.137949 -11.227888) (xy 69.185776 -11.254005) (xy 69.2294 -11.286663) (xy 69.267931 -11.325197)
			(xy 69.300586 -11.368823) (xy 69.3267 -11.416653) (xy 69.345741 -11.467712) (xy 69.357321 -11.520961)
			(xy 69.361205 -11.575316) (xy 69.357313 -11.629671) (xy 69.345725 -11.682918) (xy 69.326677 -11.733974)
			(xy 69.300556 -11.7818) (xy 69.284596 -11.803888) (xy 69.271012 -11.822908) (xy 69.250279 -11.864789)
			(xy 69.237552 -11.909755) (xy 69.23326 -11.95629) (xy 69.237548 -12.002826) (xy 69.250272 -12.047793)
			(xy 69.271002 -12.089676) (xy 69.284596 -12.108688) (xy 69.300556 -12.130776) (xy 69.326677 -12.178602)
			(xy 69.345725 -12.229658) (xy 69.357313 -12.282905) (xy 69.361205 -12.33726) (xy 70.675599 -12.33726)
			(xy 70.679491 -12.282905) (xy 70.691079 -12.229658) (xy 70.710127 -12.178602) (xy 70.736248 -12.130776)
			(xy 70.752208 -12.108688) (xy 70.765814 -12.089683) (xy 70.786545 -12.047798) (xy 70.799269 -12.002828)
			(xy 70.803558 -11.95629) (xy 70.799266 -11.909753) (xy 70.786538 -11.864784) (xy 70.765804 -11.8229)
			(xy 70.752208 -11.803888) (xy 70.736248 -11.7818) (xy 70.710127 -11.733974) (xy 70.691079 -11.682918)
			(xy 70.679491 -11.629671) (xy 70.675599 -11.575316) (xy 70.679483 -11.520961) (xy 70.691063 -11.467712)
			(xy 70.710104 -11.416653) (xy 70.736218 -11.368823) (xy 70.768873 -11.325197) (xy 70.807404 -11.286663)
			(xy 70.851028 -11.254005) (xy 70.898855 -11.227888) (xy 70.949913 -11.208843) (xy 71.003161 -11.197259)
			(xy 71.057516 -11.193371) (xy 71.111871 -11.197259) (xy 71.165119 -11.208843) (xy 71.216177 -11.227888)
			(xy 71.264004 -11.254005) (xy 71.307628 -11.286663) (xy 71.346159 -11.325197) (xy 71.378814 -11.368823)
			(xy 71.404928 -11.416653) (xy 71.423969 -11.467712) (xy 71.435549 -11.520961) (xy 71.439433 -11.575316)
			(xy 71.435541 -11.629671) (xy 71.423953 -11.682918) (xy 71.404905 -11.733974) (xy 71.378784 -11.7818)
			(xy 71.362824 -11.803888) (xy 71.349238 -11.822907) (xy 71.328503 -11.864788) (xy 71.315775 -11.909755)
			(xy 71.311482 -11.95629) (xy 71.315771 -12.002826) (xy 71.328496 -12.047794) (xy 71.349228 -12.089676)
			(xy 71.362824 -12.108688) (xy 71.378784 -12.130776) (xy 71.404905 -12.178602) (xy 71.423953 -12.229658)
			(xy 71.435541 -12.282905) (xy 71.439433 -12.33726) (xy 72.795991 -12.33726) (xy 72.799883 -12.282905)
			(xy 72.811471 -12.229658) (xy 72.830519 -12.178602) (xy 72.85664 -12.130776) (xy 72.8726 -12.108688)
			(xy 72.886207 -12.089684) (xy 72.906938 -12.047798) (xy 72.919663 -12.002828) (xy 72.923951 -11.95629)
			(xy 72.919659 -11.909753) (xy 72.906931 -11.864784) (xy 72.886197 -11.8229) (xy 72.8726 -11.803888)
			(xy 72.85664 -11.7818) (xy 72.830519 -11.733974) (xy 72.811471 -11.682918) (xy 72.799883 -11.629671)
			(xy 72.795991 -11.575316) (xy 72.799875 -11.520961) (xy 72.811455 -11.467712) (xy 72.830496 -11.416653)
			(xy 72.85661 -11.368823) (xy 72.889265 -11.325197) (xy 72.927796 -11.286663) (xy 72.97142 -11.254005)
			(xy 73.019247 -11.227888) (xy 73.070305 -11.208843) (xy 73.123553 -11.197259) (xy 73.177908 -11.193371)
			(xy 73.232263 -11.197259) (xy 73.285511 -11.208843) (xy 73.336569 -11.227888) (xy 73.384396 -11.254005)
			(xy 73.42802 -11.286663) (xy 73.466551 -11.325197) (xy 73.499206 -11.368823) (xy 73.52532 -11.416653)
			(xy 73.544361 -11.467712) (xy 73.555941 -11.520961) (xy 73.559825 -11.575316) (xy 73.555933 -11.629671)
			(xy 73.544345 -11.682918) (xy 73.525297 -11.733974) (xy 73.499176 -11.7818) (xy 73.483216 -11.803888)
			(xy 73.469631 -11.822907) (xy 73.448896 -11.864789) (xy 73.436168 -11.909755) (xy 73.431876 -11.95629)
			(xy 73.436165 -12.002826) (xy 73.448889 -12.047793) (xy 73.469621 -12.089676) (xy 73.483216 -12.108688)
			(xy 73.499176 -12.130776) (xy 73.525297 -12.178602) (xy 73.544345 -12.229658) (xy 73.555933 -12.282905)
			(xy 73.559825 -12.33726) (xy 73.555941 -12.391615) (xy 73.544361 -12.444864) (xy 73.52532 -12.495923)
			(xy 73.499206 -12.543753) (xy 73.466551 -12.587379) (xy 73.42802 -12.625913) (xy 73.384396 -12.658571)
			(xy 73.336569 -12.684688) (xy 73.285511 -12.703733) (xy 73.232263 -12.715317) (xy 73.177908 -12.719205)
			(xy 73.123553 -12.715317) (xy 73.070305 -12.703733) (xy 73.019247 -12.684688) (xy 72.97142 -12.658571)
			(xy 72.927796 -12.625913) (xy 72.889265 -12.587379) (xy 72.85661 -12.543753) (xy 72.830496 -12.495923)
			(xy 72.811455 -12.444864) (xy 72.799875 -12.391615) (xy 72.795991 -12.33726) (xy 71.439433 -12.33726)
			(xy 71.435549 -12.391615) (xy 71.423969 -12.444864) (xy 71.404928 -12.495923) (xy 71.378814 -12.543753)
			(xy 71.346159 -12.587379) (xy 71.307628 -12.625913) (xy 71.264004 -12.658571) (xy 71.216177 -12.684688)
			(xy 71.165119 -12.703733) (xy 71.111871 -12.715317) (xy 71.057516 -12.719205) (xy 71.003161 -12.715317)
			(xy 70.949913 -12.703733) (xy 70.898855 -12.684688) (xy 70.851028 -12.658571) (xy 70.807404 -12.625913)
			(xy 70.768873 -12.587379) (xy 70.736218 -12.543753) (xy 70.710104 -12.495923) (xy 70.691063 -12.444864)
			(xy 70.679483 -12.391615) (xy 70.675599 -12.33726) (xy 69.361205 -12.33726) (xy 69.357321 -12.391615)
			(xy 69.345741 -12.444864) (xy 69.3267 -12.495923) (xy 69.300586 -12.543753) (xy 69.267931 -12.587379)
			(xy 69.2294 -12.625913) (xy 69.185776 -12.658571) (xy 69.137949 -12.684688) (xy 69.086891 -12.703733)
			(xy 69.033643 -12.715317) (xy 68.979288 -12.719205) (xy 68.924933 -12.715317) (xy 68.871685 -12.703733)
			(xy 68.820627 -12.684688) (xy 68.7728 -12.658571) (xy 68.729176 -12.625913) (xy 68.690645 -12.587379)
			(xy 68.65799 -12.543753) (xy 68.631876 -12.495923) (xy 68.612835 -12.444864) (xy 68.601255 -12.391615)
			(xy 68.597371 -12.33726) (xy 67.464333 -12.33726) (xy 67.460449 -12.391615) (xy 67.448869 -12.444864)
			(xy 67.429828 -12.495923) (xy 67.403714 -12.543753) (xy 67.371059 -12.587379) (xy 67.332528 -12.625913)
			(xy 67.288904 -12.658571) (xy 67.241077 -12.684688) (xy 67.190019 -12.703733) (xy 67.136771 -12.715317)
			(xy 67.082416 -12.719205) (xy 67.028061 -12.715317) (xy 66.974813 -12.703733) (xy 66.923755 -12.684688)
			(xy 66.875928 -12.658571) (xy 66.832304 -12.625913) (xy 66.793773 -12.587379) (xy 66.761118 -12.543753)
			(xy 66.735004 -12.495923) (xy 66.715963 -12.444864) (xy 66.704383 -12.391615) (xy 66.700499 -12.33726)
			(xy 65.549681 -12.33726) (xy 65.545797 -12.391615) (xy 65.534217 -12.444864) (xy 65.515176 -12.495923)
			(xy 65.489062 -12.543753) (xy 65.456407 -12.587379) (xy 65.417876 -12.625913) (xy 65.374252 -12.658571)
			(xy 65.326425 -12.684688) (xy 65.275367 -12.703733) (xy 65.222119 -12.715317) (xy 65.167764 -12.719205)
			(xy 65.113409 -12.715317) (xy 65.060161 -12.703733) (xy 65.009103 -12.684688) (xy 64.961276 -12.658571)
			(xy 64.917652 -12.625913) (xy 64.879121 -12.587379) (xy 64.846466 -12.543753) (xy 64.820352 -12.495923)
			(xy 64.801311 -12.444864) (xy 64.789731 -12.391615) (xy 64.785847 -12.33726) (xy 37.41166 -12.33726)
			(xy 37.41166 -13.092172) (xy 39.562514 -13.092172) (xy 39.562514 -13.032236) (xy 39.570337 -12.972814)
			(xy 39.58585 -12.914921) (xy 39.608786 -12.859548) (xy 39.638753 -12.807642) (xy 39.67524 -12.760092)
			(xy 39.71762 -12.717712) (xy 39.76517 -12.681225) (xy 39.817076 -12.651258) (xy 39.872449 -12.628322)
			(xy 39.930342 -12.612809) (xy 39.989764 -12.604986) (xy 40.0497 -12.604986) (xy 40.109122 -12.612809)
			(xy 40.167015 -12.628322) (xy 40.222388 -12.651258) (xy 40.274294 -12.681225) (xy 40.321844 -12.717712)
			(xy 40.364224 -12.760092) (xy 40.400711 -12.807642) (xy 40.430678 -12.859548) (xy 40.453614 -12.914921)
			(xy 40.469127 -12.972814) (xy 40.47695 -13.032236) (xy 40.47744 -13.062204) (xy 40.47695 -13.092172)
			(xy 40.469127 -13.151594) (xy 40.453614 -13.209487) (xy 40.430678 -13.26486) (xy 40.400711 -13.316766)
			(xy 40.364224 -13.364316) (xy 40.321844 -13.406696) (xy 40.274294 -13.443183) (xy 40.222388 -13.47315)
			(xy 40.167015 -13.496086) (xy 40.109122 -13.511599) (xy 40.0497 -13.519422) (xy 39.989764 -13.519422)
			(xy 39.930342 -13.511599) (xy 39.872449 -13.496086) (xy 39.817076 -13.47315) (xy 39.76517 -13.443183)
			(xy 39.71762 -13.406696) (xy 39.67524 -13.364316) (xy 39.638753 -13.316766) (xy 39.608786 -13.26486)
			(xy 39.58585 -13.209487) (xy 39.570337 -13.151594) (xy 39.562514 -13.092172) (xy 37.41166 -13.092172)
			(xy 37.41166 -14.717748) (xy 64.785847 -14.717748) (xy 64.789739 -14.663393) (xy 64.801327 -14.610146)
			(xy 64.820375 -14.55909) (xy 64.846496 -14.511264) (xy 64.862456 -14.489176) (xy 64.876076 -14.47018)
			(xy 64.89681 -14.428293) (xy 64.909536 -14.383321) (xy 64.913823 -14.336781) (xy 64.909529 -14.290241)
			(xy 64.896796 -14.245271) (xy 64.876056 -14.203387) (xy 64.862456 -14.184376) (xy 64.846496 -14.162288)
			(xy 64.820375 -14.114462) (xy 64.801327 -14.063406) (xy 64.789739 -14.010159) (xy 64.785847 -13.955804)
			(xy 64.789731 -13.901449) (xy 64.801311 -13.8482) (xy 64.820352 -13.797141) (xy 64.846466 -13.749311)
			(xy 64.879121 -13.705685) (xy 64.917652 -13.667151) (xy 64.961276 -13.634493) (xy 65.009103 -13.608376)
			(xy 65.060161 -13.589331) (xy 65.113409 -13.577747) (xy 65.167764 -13.573859) (xy 65.222119 -13.577747)
			(xy 65.275367 -13.589331) (xy 65.326425 -13.608376) (xy 65.374252 -13.634493) (xy 65.417876 -13.667151)
			(xy 65.456407 -13.705685) (xy 65.489062 -13.749311) (xy 65.515176 -13.797141) (xy 65.534217 -13.8482)
			(xy 65.545797 -13.901449) (xy 65.549681 -13.955804) (xy 65.545789 -14.010159) (xy 65.534201 -14.063406)
			(xy 65.515153 -14.114462) (xy 65.489032 -14.162288) (xy 65.473072 -14.184376) (xy 65.4595 -14.203404)
			(xy 65.438768 -14.245284) (xy 65.426041 -14.290248) (xy 65.421748 -14.336781) (xy 65.426034 -14.383314)
			(xy 65.438754 -14.42828) (xy 65.45948 -14.470163) (xy 65.473072 -14.489176) (xy 65.489032 -14.511264)
			(xy 65.515153 -14.55909) (xy 65.534201 -14.610146) (xy 65.545789 -14.663393) (xy 65.549681 -14.717748)
			(xy 66.700499 -14.717748) (xy 66.704391 -14.663393) (xy 66.715979 -14.610146) (xy 66.735027 -14.55909)
			(xy 66.761148 -14.511264) (xy 66.777108 -14.489176) (xy 66.790725 -14.470179) (xy 66.811455 -14.428291)
			(xy 66.824178 -14.38332) (xy 66.828465 -14.336781) (xy 66.824171 -14.290242) (xy 66.811442 -14.245273)
			(xy 66.790705 -14.203388) (xy 66.777108 -14.184376) (xy 66.761148 -14.162288) (xy 66.735027 -14.114462)
			(xy 66.715979 -14.063406) (xy 66.704391 -14.010159) (xy 66.700499 -13.955804) (xy 66.704383 -13.901449)
			(xy 66.715963 -13.8482) (xy 66.735004 -13.797141) (xy 66.761118 -13.749311) (xy 66.793773 -13.705685)
			(xy 66.832304 -13.667151) (xy 66.875928 -13.634493) (xy 66.923755 -13.608376) (xy 66.974813 -13.589331)
			(xy 67.028061 -13.577747) (xy 67.082416 -13.573859) (xy 67.136771 -13.577747) (xy 67.190019 -13.589331)
			(xy 67.241077 -13.608376) (xy 67.288904 -13.634493) (xy 67.332528 -13.667151) (xy 67.371059 -13.705685)
			(xy 67.403714 -13.749311) (xy 67.429828 -13.797141) (xy 67.448869 -13.8482) (xy 67.460449 -13.901449)
			(xy 67.464333 -13.955804) (xy 67.460441 -14.010159) (xy 67.448853 -14.063406) (xy 67.429805 -14.114462)
			(xy 67.403684 -14.162288) (xy 67.387724 -14.184376) (xy 67.37415 -14.203403) (xy 67.353413 -14.245282)
			(xy 67.340683 -14.290247) (xy 67.33639 -14.336781) (xy 67.340676 -14.383316) (xy 67.353399 -14.428282)
			(xy 67.374129 -14.470164) (xy 67.387724 -14.489176) (xy 67.403684 -14.511264) (xy 67.429805 -14.55909)
			(xy 67.448853 -14.610146) (xy 67.460441 -14.663393) (xy 67.464333 -14.717748) (xy 68.597371 -14.717748)
			(xy 68.601263 -14.663393) (xy 68.612851 -14.610146) (xy 68.631899 -14.55909) (xy 68.65802 -14.511264)
			(xy 68.67398 -14.489176) (xy 68.687599 -14.47018) (xy 68.708331 -14.428292) (xy 68.721055 -14.383321)
			(xy 68.725342 -14.336781) (xy 68.721048 -14.290241) (xy 68.708317 -14.245272) (xy 68.687579 -14.203388)
			(xy 68.67398 -14.184376) (xy 68.65802 -14.162288) (xy 68.631899 -14.114462) (xy 68.612851 -14.063406)
			(xy 68.601263 -14.010159) (xy 68.597371 -13.955804) (xy 68.601255 -13.901449) (xy 68.612835 -13.8482)
			(xy 68.631876 -13.797141) (xy 68.65799 -13.749311) (xy 68.690645 -13.705685) (xy 68.729176 -13.667151)
			(xy 68.7728 -13.634493) (xy 68.820627 -13.608376) (xy 68.871685 -13.589331) (xy 68.924933 -13.577747)
			(xy 68.979288 -13.573859) (xy 69.033643 -13.577747) (xy 69.086891 -13.589331) (xy 69.137949 -13.608376)
			(xy 69.185776 -13.634493) (xy 69.2294 -13.667151) (xy 69.267931 -13.705685) (xy 69.300586 -13.749311)
			(xy 69.3267 -13.797141) (xy 69.345741 -13.8482) (xy 69.357321 -13.901449) (xy 69.361205 -13.955804)
			(xy 69.357313 -14.010159) (xy 69.345725 -14.063406) (xy 69.326677 -14.114462) (xy 69.300556 -14.162288)
			(xy 69.284596 -14.184376) (xy 69.271023 -14.203403) (xy 69.250289 -14.245283) (xy 69.237561 -14.290247)
			(xy 69.233267 -14.336781) (xy 69.237554 -14.383315) (xy 69.250275 -14.428281) (xy 69.271003 -14.470164)
			(xy 69.284596 -14.489176) (xy 69.300556 -14.511264) (xy 69.326677 -14.55909) (xy 69.345725 -14.610146)
			(xy 69.357313 -14.663393) (xy 69.361205 -14.717748) (xy 70.675599 -14.717748) (xy 70.679491 -14.663393)
			(xy 70.691079 -14.610146) (xy 70.710127 -14.55909) (xy 70.736248 -14.511264) (xy 70.752208 -14.489176)
			(xy 70.765825 -14.470179) (xy 70.786555 -14.428291) (xy 70.799278 -14.38332) (xy 70.803565 -14.336781)
			(xy 70.799271 -14.290242) (xy 70.786542 -14.245273) (xy 70.765805 -14.203388) (xy 70.752208 -14.184376)
			(xy 70.736248 -14.162288) (xy 70.710127 -14.114462) (xy 70.691079 -14.063406) (xy 70.679491 -14.010159)
			(xy 70.675599 -13.955804) (xy 70.679483 -13.901449) (xy 70.691063 -13.8482) (xy 70.710104 -13.797141)
			(xy 70.736218 -13.749311) (xy 70.768873 -13.705685) (xy 70.807404 -13.667151) (xy 70.851028 -13.634493)
			(xy 70.898855 -13.608376) (xy 70.949913 -13.589331) (xy 71.003161 -13.577747) (xy 71.057516 -13.573859)
			(xy 71.111871 -13.577747) (xy 71.165119 -13.589331) (xy 71.216177 -13.608376) (xy 71.264004 -13.634493)
			(xy 71.307628 -13.667151) (xy 71.346159 -13.705685) (xy 71.378814 -13.749311) (xy 71.404928 -13.797141)
			(xy 71.423969 -13.8482) (xy 71.435549 -13.901449) (xy 71.439433 -13.955804) (xy 71.435541 -14.010159)
			(xy 71.423953 -14.063406) (xy 71.404905 -14.114462) (xy 71.378784 -14.162288) (xy 71.362824 -14.184376)
			(xy 71.34925 -14.203403) (xy 71.328513 -14.245282) (xy 71.315783 -14.290247) (xy 71.31149 -14.336781)
			(xy 71.315776 -14.383316) (xy 71.328499 -14.428282) (xy 71.349229 -14.470164) (xy 71.362824 -14.489176)
			(xy 71.378784 -14.511264) (xy 71.404905 -14.55909) (xy 71.423953 -14.610146) (xy 71.435541 -14.663393)
			(xy 71.439433 -14.717748) (xy 72.795991 -14.717748) (xy 72.799883 -14.663393) (xy 72.811471 -14.610146)
			(xy 72.830519 -14.55909) (xy 72.85664 -14.511264) (xy 72.8726 -14.489176) (xy 72.886218 -14.470179)
			(xy 72.906948 -14.428292) (xy 72.919672 -14.38332) (xy 72.923958 -14.336781) (xy 72.919664 -14.290242)
			(xy 72.906935 -14.245272) (xy 72.886198 -14.203388) (xy 72.8726 -14.184376) (xy 72.85664 -14.162288)
			(xy 72.830519 -14.114462) (xy 72.811471 -14.063406) (xy 72.799883 -14.010159) (xy 72.795991 -13.955804)
			(xy 72.799875 -13.901449) (xy 72.811455 -13.8482) (xy 72.830496 -13.797141) (xy 72.85661 -13.749311)
			(xy 72.889265 -13.705685) (xy 72.927796 -13.667151) (xy 72.97142 -13.634493) (xy 73.019247 -13.608376)
			(xy 73.070305 -13.589331) (xy 73.123553 -13.577747) (xy 73.177908 -13.573859) (xy 73.232263 -13.577747)
			(xy 73.285511 -13.589331) (xy 73.336569 -13.608376) (xy 73.384396 -13.634493) (xy 73.42802 -13.667151)
			(xy 73.466551 -13.705685) (xy 73.499206 -13.749311) (xy 73.52532 -13.797141) (xy 73.544361 -13.8482)
			(xy 73.555941 -13.901449) (xy 73.559825 -13.955804) (xy 73.555933 -14.010159) (xy 73.544345 -14.063406)
			(xy 73.525297 -14.114462) (xy 73.499176 -14.162288) (xy 73.483216 -14.184376) (xy 73.469642 -14.203403)
			(xy 73.448906 -14.245282) (xy 73.436177 -14.290247) (xy 73.431883 -14.336781) (xy 73.43617 -14.383315)
			(xy 73.448892 -14.428282) (xy 73.469622 -14.470164) (xy 73.483216 -14.489176) (xy 73.499176 -14.511264)
			(xy 73.525297 -14.55909) (xy 73.544345 -14.610146) (xy 73.555933 -14.663393) (xy 73.559825 -14.717748)
			(xy 73.555941 -14.772103) (xy 73.544361 -14.825352) (xy 73.52532 -14.876411) (xy 73.499206 -14.924241)
			(xy 73.466551 -14.967867) (xy 73.42802 -15.006401) (xy 73.384396 -15.039059) (xy 73.336569 -15.065176)
			(xy 73.285511 -15.084221) (xy 73.232263 -15.095805) (xy 73.177908 -15.099693) (xy 73.123553 -15.095805)
			(xy 73.070305 -15.084221) (xy 73.019247 -15.065176) (xy 72.97142 -15.039059) (xy 72.927796 -15.006401)
			(xy 72.889265 -14.967867) (xy 72.85661 -14.924241) (xy 72.830496 -14.876411) (xy 72.811455 -14.825352)
			(xy 72.799875 -14.772103) (xy 72.795991 -14.717748) (xy 71.439433 -14.717748) (xy 71.435549 -14.772103)
			(xy 71.423969 -14.825352) (xy 71.404928 -14.876411) (xy 71.378814 -14.924241) (xy 71.346159 -14.967867)
			(xy 71.307628 -15.006401) (xy 71.264004 -15.039059) (xy 71.216177 -15.065176) (xy 71.165119 -15.084221)
			(xy 71.111871 -15.095805) (xy 71.057516 -15.099693) (xy 71.003161 -15.095805) (xy 70.949913 -15.084221)
			(xy 70.898855 -15.065176) (xy 70.851028 -15.039059) (xy 70.807404 -15.006401) (xy 70.768873 -14.967867)
			(xy 70.736218 -14.924241) (xy 70.710104 -14.876411) (xy 70.691063 -14.825352) (xy 70.679483 -14.772103)
			(xy 70.675599 -14.717748) (xy 69.361205 -14.717748) (xy 69.357321 -14.772103) (xy 69.345741 -14.825352)
			(xy 69.3267 -14.876411) (xy 69.300586 -14.924241) (xy 69.267931 -14.967867) (xy 69.2294 -15.006401)
			(xy 69.185776 -15.039059) (xy 69.137949 -15.065176) (xy 69.086891 -15.084221) (xy 69.033643 -15.095805)
			(xy 68.979288 -15.099693) (xy 68.924933 -15.095805) (xy 68.871685 -15.084221) (xy 68.820627 -15.065176)
			(xy 68.7728 -15.039059) (xy 68.729176 -15.006401) (xy 68.690645 -14.967867) (xy 68.65799 -14.924241)
			(xy 68.631876 -14.876411) (xy 68.612835 -14.825352) (xy 68.601255 -14.772103) (xy 68.597371 -14.717748)
			(xy 67.464333 -14.717748) (xy 67.460449 -14.772103) (xy 67.448869 -14.825352) (xy 67.429828 -14.876411)
			(xy 67.403714 -14.924241) (xy 67.371059 -14.967867) (xy 67.332528 -15.006401) (xy 67.288904 -15.039059)
			(xy 67.241077 -15.065176) (xy 67.190019 -15.084221) (xy 67.136771 -15.095805) (xy 67.082416 -15.099693)
			(xy 67.028061 -15.095805) (xy 66.974813 -15.084221) (xy 66.923755 -15.065176) (xy 66.875928 -15.039059)
			(xy 66.832304 -15.006401) (xy 66.793773 -14.967867) (xy 66.761118 -14.924241) (xy 66.735004 -14.876411)
			(xy 66.715963 -14.825352) (xy 66.704383 -14.772103) (xy 66.700499 -14.717748) (xy 65.549681 -14.717748)
			(xy 65.545797 -14.772103) (xy 65.534217 -14.825352) (xy 65.515176 -14.876411) (xy 65.489062 -14.924241)
			(xy 65.456407 -14.967867) (xy 65.417876 -15.006401) (xy 65.374252 -15.039059) (xy 65.326425 -15.065176)
			(xy 65.275367 -15.084221) (xy 65.222119 -15.095805) (xy 65.167764 -15.099693) (xy 65.113409 -15.095805)
			(xy 65.060161 -15.084221) (xy 65.009103 -15.065176) (xy 64.961276 -15.039059) (xy 64.917652 -15.006401)
			(xy 64.879121 -14.967867) (xy 64.846466 -14.924241) (xy 64.820352 -14.876411) (xy 64.801311 -14.825352)
			(xy 64.789731 -14.772103) (xy 64.785847 -14.717748) (xy 37.41166 -14.717748) (xy 37.41166 -17.322292)
			(xy 37.355272 -17.37868) (xy 37.347983 -17.386018) (xy 64.785847 -17.386018) (xy 64.789739 -17.331663)
			(xy 64.801327 -17.278416) (xy 64.820375 -17.22736) (xy 64.846496 -17.179534) (xy 64.862456 -17.157446)
			(xy 64.876011 -17.138406) (xy 64.896751 -17.09653) (xy 64.909484 -17.051569) (xy 64.913781 -17.005037)
			(xy 64.909497 -16.958504) (xy 64.896777 -16.913538) (xy 64.876049 -16.871657) (xy 64.862456 -16.852646)
			(xy 64.846496 -16.830558) (xy 64.820375 -16.782732) (xy 64.801327 -16.731676) (xy 64.789739 -16.678429)
			(xy 64.785847 -16.624074) (xy 64.789731 -16.569719) (xy 64.801311 -16.51647) (xy 64.820352 -16.465411)
			(xy 64.846466 -16.417581) (xy 64.879121 -16.373955) (xy 64.917652 -16.335421) (xy 64.961276 -16.302763)
			(xy 65.009103 -16.276646) (xy 65.060161 -16.257601) (xy 65.113409 -16.246017) (xy 65.167764 -16.242129)
			(xy 65.222119 -16.246017) (xy 65.275367 -16.257601) (xy 65.326425 -16.276646) (xy 65.374252 -16.302763)
			(xy 65.417876 -16.335421) (xy 65.456407 -16.373955) (xy 65.489062 -16.417581) (xy 65.515176 -16.465411)
			(xy 65.534217 -16.51647) (xy 65.545797 -16.569719) (xy 65.549681 -16.624074) (xy 65.545789 -16.678429)
			(xy 65.534201 -16.731676) (xy 65.515153 -16.782732) (xy 65.489032 -16.830558) (xy 65.473072 -16.852646)
			(xy 65.459435 -16.87163) (xy 65.438709 -16.913521) (xy 65.425989 -16.958495) (xy 65.421706 -17.005037)
			(xy 65.426003 -17.051577) (xy 65.438735 -17.096548) (xy 65.459474 -17.138433) (xy 65.473072 -17.157446)
			(xy 65.489032 -17.179534) (xy 65.515153 -17.22736) (xy 65.534201 -17.278416) (xy 65.545789 -17.331663)
			(xy 65.549681 -17.386018) (xy 66.700499 -17.386018) (xy 66.704391 -17.331663) (xy 66.715979 -17.278416)
			(xy 66.735027 -17.22736) (xy 66.761148 -17.179534) (xy 66.777108 -17.157446) (xy 66.79066 -17.138405)
			(xy 66.811396 -17.096529) (xy 66.824127 -17.051568) (xy 66.828423 -17.005037) (xy 66.82414 -16.958505)
			(xy 66.811423 -16.91354) (xy 66.790699 -16.871658) (xy 66.777108 -16.852646) (xy 66.761148 -16.830558)
			(xy 66.735027 -16.782732) (xy 66.715979 -16.731676) (xy 66.704391 -16.678429) (xy 66.700499 -16.624074)
			(xy 66.704383 -16.569719) (xy 66.715963 -16.51647) (xy 66.735004 -16.465411) (xy 66.761118 -16.417581)
			(xy 66.793773 -16.373955) (xy 66.832304 -16.335421) (xy 66.875928 -16.302763) (xy 66.923755 -16.276646)
			(xy 66.974813 -16.257601) (xy 67.028061 -16.246017) (xy 67.082416 -16.242129) (xy 67.136771 -16.246017)
			(xy 67.190019 -16.257601) (xy 67.241077 -16.276646) (xy 67.288904 -16.302763) (xy 67.332528 -16.335421)
			(xy 67.371059 -16.373955) (xy 67.403714 -16.417581) (xy 67.429828 -16.465411) (xy 67.448869 -16.51647)
			(xy 67.460449 -16.569719) (xy 67.464333 -16.624074) (xy 67.460441 -16.678429) (xy 67.448853 -16.731676)
			(xy 67.429805 -16.782732) (xy 67.403684 -16.830558) (xy 67.387724 -16.852646) (xy 67.374084 -16.871629)
			(xy 67.353354 -16.913519) (xy 67.340632 -16.958494) (xy 67.336348 -17.005037) (xy 67.340645 -17.051578)
			(xy 67.35338 -17.09655) (xy 67.374123 -17.138434) (xy 67.387724 -17.157446) (xy 67.403684 -17.179534)
			(xy 67.429805 -17.22736) (xy 67.448853 -17.278416) (xy 67.460441 -17.331663) (xy 67.464333 -17.386018)
			(xy 68.597371 -17.386018) (xy 68.601263 -17.331663) (xy 68.612851 -17.278416) (xy 68.631899 -17.22736)
			(xy 68.65802 -17.179534) (xy 68.67398 -17.157446) (xy 68.687534 -17.138405) (xy 68.708272 -17.09653)
			(xy 68.721004 -17.051568) (xy 68.7253 -17.005037) (xy 68.721017 -16.958504) (xy 68.708298 -16.913539)
			(xy 68.687572 -16.871658) (xy 68.67398 -16.852646) (xy 68.65802 -16.830558) (xy 68.631899 -16.782732)
			(xy 68.612851 -16.731676) (xy 68.601263 -16.678429) (xy 68.597371 -16.624074) (xy 68.601255 -16.569719)
			(xy 68.612835 -16.51647) (xy 68.631876 -16.465411) (xy 68.65799 -16.417581) (xy 68.690645 -16.373955)
			(xy 68.729176 -16.335421) (xy 68.7728 -16.302763) (xy 68.820627 -16.276646) (xy 68.871685 -16.257601)
			(xy 68.924933 -16.246017) (xy 68.979288 -16.242129) (xy 69.033643 -16.246017) (xy 69.086891 -16.257601)
			(xy 69.137949 -16.276646) (xy 69.185776 -16.302763) (xy 69.2294 -16.335421) (xy 69.267931 -16.373955)
			(xy 69.300586 -16.417581) (xy 69.3267 -16.465411) (xy 69.345741 -16.51647) (xy 69.357321 -16.569719)
			(xy 69.361205 -16.624074) (xy 69.357313 -16.678429) (xy 69.345725 -16.731676) (xy 69.326677 -16.782732)
			(xy 69.300556 -16.830558) (xy 69.284596 -16.852646) (xy 69.270958 -16.871629) (xy 69.250229 -16.91352)
			(xy 69.237509 -16.958495) (xy 69.233225 -17.005037) (xy 69.237522 -17.051578) (xy 69.250256 -17.096549)
			(xy 69.270996 -17.138434) (xy 69.284596 -17.157446) (xy 69.300556 -17.179534) (xy 69.326677 -17.22736)
			(xy 69.345725 -17.278416) (xy 69.357313 -17.331663) (xy 69.361205 -17.386018) (xy 70.675599 -17.386018)
			(xy 70.679491 -17.331663) (xy 70.691079 -17.278416) (xy 70.710127 -17.22736) (xy 70.736248 -17.179534)
			(xy 70.752208 -17.157446) (xy 70.76576 -17.138405) (xy 70.786496 -17.096529) (xy 70.799227 -17.051568)
			(xy 70.803523 -17.005037) (xy 70.79924 -16.958505) (xy 70.786523 -16.91354) (xy 70.765799 -16.871658)
			(xy 70.752208 -16.852646) (xy 70.736248 -16.830558) (xy 70.710127 -16.782732) (xy 70.691079 -16.731676)
			(xy 70.679491 -16.678429) (xy 70.675599 -16.624074) (xy 70.679483 -16.569719) (xy 70.691063 -16.51647)
			(xy 70.710104 -16.465411) (xy 70.736218 -16.417581) (xy 70.768873 -16.373955) (xy 70.807404 -16.335421)
			(xy 70.851028 -16.302763) (xy 70.898855 -16.276646) (xy 70.949913 -16.257601) (xy 71.003161 -16.246017)
			(xy 71.057516 -16.242129) (xy 71.111871 -16.246017) (xy 71.165119 -16.257601) (xy 71.216177 -16.276646)
			(xy 71.264004 -16.302763) (xy 71.307628 -16.335421) (xy 71.346159 -16.373955) (xy 71.378814 -16.417581)
			(xy 71.404928 -16.465411) (xy 71.423969 -16.51647) (xy 71.435549 -16.569719) (xy 71.439433 -16.624074)
			(xy 71.435541 -16.678429) (xy 71.423953 -16.731676) (xy 71.404905 -16.782732) (xy 71.378784 -16.830558)
			(xy 71.362824 -16.852646) (xy 71.349184 -16.871629) (xy 71.328454 -16.913519) (xy 71.315732 -16.958494)
			(xy 71.311448 -17.005037) (xy 71.315745 -17.051578) (xy 71.32848 -17.09655) (xy 71.349223 -17.138434)
			(xy 71.362824 -17.157446) (xy 71.378784 -17.179534) (xy 71.404905 -17.22736) (xy 71.423953 -17.278416)
			(xy 71.435541 -17.331663) (xy 71.439433 -17.386018) (xy 72.795991 -17.386018) (xy 72.799883 -17.331663)
			(xy 72.811471 -17.278416) (xy 72.830519 -17.22736) (xy 72.85664 -17.179534) (xy 72.8726 -17.157446)
			(xy 72.886153 -17.138405) (xy 72.906889 -17.096529) (xy 72.91962 -17.051568) (xy 72.923916 -17.005037)
			(xy 72.919633 -16.958505) (xy 72.906916 -16.91354) (xy 72.886191 -16.871658) (xy 72.8726 -16.852646)
			(xy 72.85664 -16.830558) (xy 72.830519 -16.782732) (xy 72.811471 -16.731676) (xy 72.799883 -16.678429)
			(xy 72.795991 -16.624074) (xy 72.799875 -16.569719) (xy 72.811455 -16.51647) (xy 72.830496 -16.465411)
			(xy 72.85661 -16.417581) (xy 72.889265 -16.373955) (xy 72.927796 -16.335421) (xy 72.97142 -16.302763)
			(xy 73.019247 -16.276646) (xy 73.070305 -16.257601) (xy 73.123553 -16.246017) (xy 73.177908 -16.242129)
			(xy 73.232263 -16.246017) (xy 73.285511 -16.257601) (xy 73.336569 -16.276646) (xy 73.384396 -16.302763)
			(xy 73.42802 -16.335421) (xy 73.466551 -16.373955) (xy 73.499206 -16.417581) (xy 73.52532 -16.465411)
			(xy 73.544361 -16.51647) (xy 73.555941 -16.569719) (xy 73.559825 -16.624074) (xy 73.555933 -16.678429)
			(xy 73.544345 -16.731676) (xy 73.525297 -16.782732) (xy 73.499176 -16.830558) (xy 73.483216 -16.852646)
			(xy 73.469577 -16.871629) (xy 73.448847 -16.913519) (xy 73.436125 -16.958494) (xy 73.431841 -17.005037)
			(xy 73.436139 -17.051578) (xy 73.448873 -17.096549) (xy 73.469616 -17.138434) (xy 73.483216 -17.157446)
			(xy 73.499176 -17.179534) (xy 73.525297 -17.22736) (xy 73.544345 -17.278416) (xy 73.555933 -17.331663)
			(xy 73.559825 -17.386018) (xy 73.555941 -17.440373) (xy 73.544361 -17.493622) (xy 73.52532 -17.544681)
			(xy 73.499206 -17.592511) (xy 73.466551 -17.636137) (xy 73.42802 -17.674671) (xy 73.384396 -17.707329)
			(xy 73.336569 -17.733446) (xy 73.285511 -17.752491) (xy 73.232263 -17.764075) (xy 73.177908 -17.767963)
			(xy 73.123553 -17.764075) (xy 73.070305 -17.752491) (xy 73.019247 -17.733446) (xy 72.97142 -17.707329)
			(xy 72.927796 -17.674671) (xy 72.889265 -17.636137) (xy 72.85661 -17.592511) (xy 72.830496 -17.544681)
			(xy 72.811455 -17.493622) (xy 72.799875 -17.440373) (xy 72.795991 -17.386018) (xy 71.439433 -17.386018)
			(xy 71.435549 -17.440373) (xy 71.423969 -17.493622) (xy 71.404928 -17.544681) (xy 71.378814 -17.592511)
			(xy 71.346159 -17.636137) (xy 71.307628 -17.674671) (xy 71.264004 -17.707329) (xy 71.216177 -17.733446)
			(xy 71.165119 -17.752491) (xy 71.111871 -17.764075) (xy 71.057516 -17.767963) (xy 71.003161 -17.764075)
			(xy 70.949913 -17.752491) (xy 70.898855 -17.733446) (xy 70.851028 -17.707329) (xy 70.807404 -17.674671)
			(xy 70.768873 -17.636137) (xy 70.736218 -17.592511) (xy 70.710104 -17.544681) (xy 70.691063 -17.493622)
			(xy 70.679483 -17.440373) (xy 70.675599 -17.386018) (xy 69.361205 -17.386018) (xy 69.357321 -17.440373)
			(xy 69.345741 -17.493622) (xy 69.3267 -17.544681) (xy 69.300586 -17.592511) (xy 69.267931 -17.636137)
			(xy 69.2294 -17.674671) (xy 69.185776 -17.707329) (xy 69.137949 -17.733446) (xy 69.086891 -17.752491)
			(xy 69.033643 -17.764075) (xy 68.979288 -17.767963) (xy 68.924933 -17.764075) (xy 68.871685 -17.752491)
			(xy 68.820627 -17.733446) (xy 68.7728 -17.707329) (xy 68.729176 -17.674671) (xy 68.690645 -17.636137)
			(xy 68.65799 -17.592511) (xy 68.631876 -17.544681) (xy 68.612835 -17.493622) (xy 68.601255 -17.440373)
			(xy 68.597371 -17.386018) (xy 67.464333 -17.386018) (xy 67.460449 -17.440373) (xy 67.448869 -17.493622)
			(xy 67.429828 -17.544681) (xy 67.403714 -17.592511) (xy 67.371059 -17.636137) (xy 67.332528 -17.674671)
			(xy 67.288904 -17.707329) (xy 67.241077 -17.733446) (xy 67.190019 -17.752491) (xy 67.136771 -17.764075)
			(xy 67.082416 -17.767963) (xy 67.028061 -17.764075) (xy 66.974813 -17.752491) (xy 66.923755 -17.733446)
			(xy 66.875928 -17.707329) (xy 66.832304 -17.674671) (xy 66.793773 -17.636137) (xy 66.761118 -17.592511)
			(xy 66.735004 -17.544681) (xy 66.715963 -17.493622) (xy 66.704383 -17.440373) (xy 66.700499 -17.386018)
			(xy 65.549681 -17.386018) (xy 65.545797 -17.440373) (xy 65.534217 -17.493622) (xy 65.515176 -17.544681)
			(xy 65.489062 -17.592511) (xy 65.456407 -17.636137) (xy 65.417876 -17.674671) (xy 65.374252 -17.707329)
			(xy 65.326425 -17.733446) (xy 65.275367 -17.752491) (xy 65.222119 -17.764075) (xy 65.167764 -17.767963)
			(xy 65.113409 -17.764075) (xy 65.060161 -17.752491) (xy 65.009103 -17.733446) (xy 64.961276 -17.707329)
			(xy 64.917652 -17.674671) (xy 64.879121 -17.636137) (xy 64.846466 -17.592511) (xy 64.820352 -17.544681)
			(xy 64.801311 -17.493622) (xy 64.789731 -17.440373) (xy 64.785847 -17.386018) (xy 37.347983 -17.386018)
			(xy 37.31768 -17.416526) (xy 37.31768 -17.742916) (xy 50.87366 -17.742916) (xy 52.525676 -17.742916)
			(xy 52.525676 -19.394424) (xy 50.87366 -19.394424) (xy 50.87366 -17.742916) (xy 37.31768 -17.742916)
			(xy 37.31768 -18.609225) (xy 47.374038 -18.609225) (xy 47.374038 -18.528115) (xy 47.381988 -18.447396)
			(xy 47.397811 -18.367845) (xy 47.421356 -18.290229) (xy 47.452395 -18.215293) (xy 47.49063 -18.143761)
			(xy 47.535692 -18.076321) (xy 47.587147 -18.013622) (xy 47.6445 -17.956269) (xy 47.707199 -17.904814)
			(xy 47.774639 -17.859752) (xy 47.846171 -17.821517) (xy 47.921107 -17.790478) (xy 47.998723 -17.766933)
			(xy 48.078274 -17.75111) (xy 48.158993 -17.74316) (xy 48.240103 -17.74316) (xy 48.320822 -17.75111)
			(xy 48.400373 -17.766933) (xy 48.477989 -17.790478) (xy 48.552925 -17.821517) (xy 48.624457 -17.859752)
			(xy 48.691897 -17.904814) (xy 48.754596 -17.956269) (xy 48.811949 -18.013622) (xy 48.863404 -18.076321)
			(xy 48.908466 -18.143761) (xy 48.946701 -18.215293) (xy 48.97774 -18.290229) (xy 49.001285 -18.367845)
			(xy 49.017108 -18.447396) (xy 49.025058 -18.528115) (xy 49.025556 -18.56867) (xy 49.025058 -18.609225)
			(xy 49.017108 -18.689944) (xy 49.001285 -18.769495) (xy 48.97774 -18.847111) (xy 48.946701 -18.922047)
			(xy 48.908466 -18.993579) (xy 48.863404 -19.061019) (xy 48.811949 -19.123718) (xy 48.754596 -19.181071)
			(xy 48.691897 -19.232526) (xy 48.624457 -19.277588) (xy 48.552925 -19.315823) (xy 48.477989 -19.346862)
			(xy 48.400373 -19.370407) (xy 48.320822 -19.38623) (xy 48.240103 -19.39418) (xy 48.158993 -19.39418)
			(xy 48.078274 -19.38623) (xy 47.998723 -19.370407) (xy 47.921107 -19.346862) (xy 47.846171 -19.315823)
			(xy 47.774639 -19.277588) (xy 47.707199 -19.232526) (xy 47.6445 -19.181071) (xy 47.587147 -19.123718)
			(xy 47.535692 -19.061019) (xy 47.49063 -18.993579) (xy 47.452395 -18.922047) (xy 47.421356 -18.847111)
			(xy 47.397811 -18.769495) (xy 47.381988 -18.689944) (xy 47.374038 -18.609225) (xy 37.31768 -18.609225)
			(xy 37.31768 -18.93189) (xy 36.499038 -19.750532) (xy 36.479734 -19.797776) (xy 36.479988 -19.823176)
			(xy 36.479814 -19.866324) (xy 36.472533 -19.952307) (xy 36.457406 -20.037262) (xy 36.434561 -20.120475)
			(xy 36.404189 -20.201244) (xy 36.366546 -20.278892) (xy 36.321949 -20.352765) (xy 36.270772 -20.422242)
			(xy 36.213446 -20.486739) (xy 36.150453 -20.545714) (xy 36.082322 -20.59867) (xy 36.009627 -20.645163)
			(xy 35.932978 -20.684801) (xy 35.853021 -20.717251) (xy 35.770427 -20.74224) (xy 35.685892 -20.759559)
			(xy 35.643058 -20.764754) (xy 35.594544 -20.770088) (xy 35.530028 -20.842224) (xy 35.530028 -21.357844)
			(xy 35.594544 -21.42998) (xy 35.643058 -21.435314) (xy 35.686175 -21.440586) (xy 35.77127 -21.458057)
			(xy 35.854391 -21.483301) (xy 35.934829 -21.516104) (xy 36.011899 -21.556186) (xy 36.084944 -21.603205)
			(xy 36.153341 -21.656761) (xy 36.216507 -21.716397) (xy 36.273904 -21.781604) (xy 36.325042 -21.851827)
			(xy 36.369485 -21.926467) (xy 36.406855 -22.004888) (xy 36.436833 -22.086422) (xy 36.459164 -22.170372)
			(xy 36.473657 -22.256025) (xy 36.480188 -22.342649) (xy 36.478702 -22.429506) (xy 36.469211 -22.515856)
			(xy 36.451797 -22.600962) (xy 36.426608 -22.6841) (xy 36.393859 -22.76456) (xy 36.374324 -22.803358)
			(xy 36.364113 -22.824059) (xy 36.350539 -22.868172) (xy 36.34515 -22.91401) (xy 36.348124 -22.960068)
			(xy 36.359362 -23.004832) (xy 36.378497 -23.046833) (xy 36.404898 -23.08469) (xy 36.437699 -23.117159)
			(xy 36.475823 -23.143174) (xy 36.518016 -23.161881) (xy 36.562892 -23.172664) (xy 36.585906 -23.174452)
			(xy 39.776654 -23.174452) (xy 39.791662 -23.172822) (xy 39.820342 -23.163422) (xy 39.846015 -23.147555)
			(xy 39.856918 -23.137114) (xy 40.150288 -22.843744) (xy 40.170811 -22.823831) (xy 40.215753 -22.788471)
			(xy 40.264557 -22.758666) (xy 40.31654 -22.734835) (xy 40.370974 -22.71731) (xy 40.398954 -22.71141)
			(xy 40.421949 -22.70635) (xy 40.465671 -22.688895) (xy 40.505437 -22.663696) (xy 40.539892 -22.631614)
			(xy 40.567859 -22.593743) (xy 40.588384 -22.551375) (xy 40.600768 -22.505955) (xy 40.604587 -22.459032)
			(xy 40.602662 -22.435566) (xy 40.600904 -22.423) (xy 40.59887 -22.397706) (xy 40.598598 -22.38502)
			(xy 40.598598 -22.381464) (xy 40.598802 -22.358256) (xy 40.604149 -22.312153) (xy 40.609266 -22.289516)
			(xy 40.614191 -22.267038) (xy 40.616781 -22.221098) (xy 40.611058 -22.175443) (xy 40.597209 -22.131564)
			(xy 40.575686 -22.090895) (xy 40.547193 -22.054766) (xy 40.512661 -22.024357) (xy 40.473219 -22.000661)
			(xy 40.430155 -21.984454) (xy 40.384877 -21.976265) (xy 40.36187 -21.975826) (xy 40.35298 -21.975826)
			(xy 40.324008 -21.974692) (xy 40.266889 -21.964746) (xy 40.211932 -21.946272) (xy 40.160404 -21.919695)
			(xy 40.11349 -21.885628) (xy 40.072272 -21.844854) (xy 40.037697 -21.798312) (xy 40.010563 -21.747075)
			(xy 39.991494 -21.692322) (xy 39.985696 -21.663914) (xy 39.981163 -21.636685) (xy 39.979062 -21.581525)
			(xy 39.98493 -21.526639) (xy 39.998644 -21.47317) (xy 40.00881 -21.447506) (xy 40.01987 -21.422249)
			(xy 40.0482 -21.374946) (xy 40.083047 -21.332216) (xy 40.123683 -21.29495) (xy 40.169263 -21.263924)
			(xy 40.218836 -21.239785) (xy 40.271367 -21.223037) (xy 40.325764 -21.214028) (xy 40.38089 -21.212946)
			(xy 40.435598 -21.219814) (xy 40.488747 -21.234488) (xy 40.539228 -21.256664) (xy 40.58599 -21.285878)
			(xy 40.628057 -21.321521) (xy 40.664553 -21.362851) (xy 40.694717 -21.409006) (xy 40.706802 -21.43379)
			(xy 40.717237 -21.457235) (xy 40.732433 -21.50625) (xy 40.740929 -21.556859) (xy 40.742569 -21.60815)
			(xy 40.737326 -21.659198) (xy 40.731694 -21.684234) (xy 40.726774 -21.706711) (xy 40.724193 -21.752646)
			(xy 40.729923 -21.798296) (xy 40.743776 -21.842169) (xy 40.765299 -21.882831) (xy 40.79379 -21.918956)
			(xy 40.828318 -21.949362) (xy 40.867755 -21.973056) (xy 40.910813 -21.989265) (xy 40.956085 -21.997459)
			(xy 40.97909 -21.997924) (xy 40.982646 -21.997924) (xy 41.007462 -21.998488) (xy 41.05664 -22.00524)
			(xy 41.08069 -22.011386) (xy 41.106603 -22.018946) (xy 41.15615 -22.040363) (xy 41.202183 -22.06855)
			(xy 41.243784 -22.102944) (xy 41.280122 -22.142859) (xy 41.31047 -22.187498) (xy 41.334222 -22.235969)
			(xy 41.350906 -22.287304) (xy 41.360186 -22.340478) (xy 41.361879 -22.394429) (xy 41.355949 -22.44808)
			(xy 41.342516 -22.50036) (xy 41.321848 -22.550224) (xy 41.294358 -22.596677) (xy 41.260594 -22.638791)
			(xy 41.221231 -22.675725) (xy 41.177054 -22.706742) (xy 41.128947 -22.731222) (xy 41.10355 -22.740366)
			(xy 41.082261 -22.749542) (xy 41.043161 -22.774438) (xy 41.009213 -22.806) (xy 40.981539 -22.843187)
			(xy 40.961055 -22.884768) (xy 40.948436 -22.929371) (xy 40.944101 -22.975521) (xy 40.948191 -23.021694)
			(xy 40.953944 -23.04415) (xy 40.963056 -23.075918) (xy 40.97351 -23.141174) (xy 40.974772 -23.174198)
			(xy 40.975014 -23.206765) (xy 40.967799 -23.27149) (xy 40.951949 -23.334659) (xy 40.927751 -23.395123)
			(xy 40.895644 -23.451785) (xy 40.856213 -23.503617) (xy 40.833548 -23.527004) (xy 40.425624 -23.934674)
			(xy 40.220138 -24.14016) (xy 29.925264 -24.14016) (xy 29.170884 -24.89454) (xy 29.170884 -29.381954)
			(xy 64.852532 -29.381954) (xy 64.852532 -29.322018) (xy 64.860355 -29.262596) (xy 64.875868 -29.204703)
			(xy 64.898804 -29.14933) (xy 64.928771 -29.097424) (xy 64.965258 -29.049874) (xy 65.007638 -29.007494)
			(xy 65.055188 -28.971007) (xy 65.107094 -28.94104) (xy 65.162467 -28.918104) (xy 65.22036 -28.902591)
			(xy 65.279782 -28.894768) (xy 65.339718 -28.894768) (xy 65.39914 -28.902591) (xy 65.457033 -28.918104)
			(xy 65.512406 -28.94104) (xy 65.564312 -28.971007) (xy 65.611862 -29.007494) (xy 65.654242 -29.049874)
			(xy 65.690729 -29.097424) (xy 65.720696 -29.14933) (xy 65.743632 -29.204703) (xy 65.759145 -29.262596)
			(xy 65.766968 -29.322018) (xy 65.767458 -29.351986) (xy 65.766968 -29.381954) (xy 65.759145 -29.441376)
			(xy 65.743632 -29.499269) (xy 65.720696 -29.554642) (xy 65.690729 -29.606548) (xy 65.654242 -29.654098)
			(xy 65.611862 -29.696478) (xy 65.564312 -29.732965) (xy 65.512406 -29.762932) (xy 65.457033 -29.785868)
			(xy 65.39914 -29.801381) (xy 65.339718 -29.809204) (xy 65.279782 -29.809204) (xy 65.22036 -29.801381)
			(xy 65.162467 -29.785868) (xy 65.107094 -29.762932) (xy 65.055188 -29.732965) (xy 65.007638 -29.696478)
			(xy 64.965258 -29.654098) (xy 64.928771 -29.606548) (xy 64.898804 -29.554642) (xy 64.875868 -29.499269)
			(xy 64.860355 -29.441376) (xy 64.852532 -29.381954) (xy 29.170884 -29.381954) (xy 29.170884 -32.612072)
			(xy 64.80732 -32.612072) (xy 64.80732 -32.552136) (xy 64.815143 -32.492714) (xy 64.830656 -32.434821)
			(xy 64.853592 -32.379448) (xy 64.883559 -32.327542) (xy 64.920046 -32.279992) (xy 64.962426 -32.237612)
			(xy 65.009976 -32.201125) (xy 65.061882 -32.171158) (xy 65.117255 -32.148222) (xy 65.175148 -32.132709)
			(xy 65.23457 -32.124886) (xy 65.294506 -32.124886) (xy 65.353928 -32.132709) (xy 65.411821 -32.148222)
			(xy 65.467194 -32.171158) (xy 65.5191 -32.201125) (xy 65.56665 -32.237612) (xy 65.60903 -32.279992)
			(xy 65.624314 -32.29991) (xy 72.998592 -32.29991) (xy 73.002596 -32.099802) (xy 73.014604 -31.900014)
			(xy 73.034596 -31.700866) (xy 73.062539 -31.502678) (xy 73.098389 -31.305767) (xy 73.14209 -31.110447)
			(xy 73.193569 -30.917033) (xy 73.252746 -30.725833) (xy 73.319526 -30.537153) (xy 73.393801 -30.351297)
			(xy 73.475452 -30.168561) (xy 73.56435 -29.989238) (xy 73.66035 -29.813616) (xy 73.763301 -29.641975)
			(xy 73.873036 -29.474591) (xy 73.989381 -29.311731) (xy 74.112148 -29.153656) (xy 74.241141 -29.00062)
			(xy 74.376154 -28.852868) (xy 74.516971 -28.710635) (xy 74.663365 -28.574151) (xy 74.815103 -28.443632)
			(xy 74.971942 -28.31929) (xy 75.133629 -28.201322) (xy 75.299908 -28.089917) (xy 75.47051 -27.985255)
			(xy 75.645163 -27.887502) (xy 75.823587 -27.796815) (xy 76.005497 -27.713339) (xy 76.190601 -27.637208)
			(xy 76.378603 -27.568544) (xy 76.569201 -27.507457) (xy 76.762091 -27.454045) (xy 76.956963 -27.408393)
			(xy 77.153506 -27.370574) (xy 77.351405 -27.34065) (xy 77.550342 -27.318666) (xy 77.75 -27.30466)
			(xy 77.950058 -27.298654) (xy 78.150197 -27.300656) (xy 78.350095 -27.310665) (xy 78.549432 -27.328663)
			(xy 78.74789 -27.354622) (xy 78.94515 -27.3885) (xy 79.140897 -27.430244) (xy 79.334817 -27.479786)
			(xy 79.5266 -27.537047) (xy 79.715938 -27.601936) (xy 79.902528 -27.674348) (xy 80.086072 -27.754167)
			(xy 80.266275 -27.841266) (xy 80.442849 -27.935504) (xy 80.615511 -28.036733) (xy 80.783985 -28.144788)
			(xy 80.948001 -28.259497) (xy 81.107296 -28.380677) (xy 81.261615 -28.508132) (xy 81.410711 -28.641661)
			(xy 81.554345 -28.781047) (xy 81.692287 -28.926069) (xy 81.824317 -29.076493) (xy 81.950223 -29.23208)
			(xy 82.069802 -29.392579) (xy 82.182865 -29.557734) (xy 82.289229 -29.727281) (xy 82.388725 -29.900947)
			(xy 82.481192 -30.078455) (xy 82.566484 -30.259521) (xy 82.644463 -30.443854) (xy 82.715004 -30.631159)
			(xy 82.777995 -30.821137) (xy 82.833334 -31.013483) (xy 82.880934 -31.207888) (xy 82.920717 -31.404043)
			(xy 82.95262 -31.601633) (xy 82.976592 -31.80034) (xy 82.992595 -31.999848) (xy 83.000603 -32.199836)
			(xy 83.001104 -32.29991) (xy 83.000603 -32.399984) (xy 82.992595 -32.599972) (xy 82.976592 -32.79948)
			(xy 82.95262 -32.998187) (xy 82.920717 -33.195777) (xy 82.880934 -33.391932) (xy 82.833334 -33.586337)
			(xy 82.777995 -33.778683) (xy 82.715004 -33.968661) (xy 82.644463 -34.155966) (xy 82.566484 -34.340299)
			(xy 82.481192 -34.521365) (xy 82.388725 -34.698873) (xy 82.289229 -34.872539) (xy 82.182865 -35.042086)
			(xy 82.069802 -35.207241) (xy 81.950223 -35.36774) (xy 81.824317 -35.523327) (xy 81.692287 -35.673751)
			(xy 81.554345 -35.818773) (xy 81.410711 -35.958159) (xy 81.261615 -36.091688) (xy 81.107296 -36.219143)
			(xy 80.948001 -36.340323) (xy 80.783985 -36.455032) (xy 80.615511 -36.563087) (xy 80.442849 -36.664316)
			(xy 80.266275 -36.758554) (xy 80.086072 -36.845653) (xy 79.902528 -36.925472) (xy 79.715938 -36.997884)
			(xy 79.5266 -37.062773) (xy 79.334817 -37.120034) (xy 79.140897 -37.169576) (xy 78.94515 -37.21132)
			(xy 78.74789 -37.245198) (xy 78.549432 -37.271157) (xy 78.350095 -37.289155) (xy 78.150197 -37.299164)
			(xy 77.950058 -37.301166) (xy 77.75 -37.29516) (xy 77.550342 -37.281154) (xy 77.351405 -37.25917)
			(xy 77.153506 -37.229246) (xy 76.956963 -37.191427) (xy 76.762091 -37.145775) (xy 76.569201 -37.092363)
			(xy 76.378603 -37.031276) (xy 76.190601 -36.962612) (xy 76.005497 -36.886481) (xy 75.823587 -36.803005)
			(xy 75.645163 -36.712318) (xy 75.47051 -36.614565) (xy 75.299908 -36.509903) (xy 75.133629 -36.398498)
			(xy 74.971942 -36.28053) (xy 74.815103 -36.156188) (xy 74.663365 -36.025669) (xy 74.516971 -35.889185)
			(xy 74.376154 -35.746952) (xy 74.241141 -35.5992) (xy 74.112148 -35.446164) (xy 73.989381 -35.288089)
			(xy 73.873036 -35.125229) (xy 73.763301 -34.957845) (xy 73.66035 -34.786204) (xy 73.56435 -34.610582)
			(xy 73.475452 -34.431259) (xy 73.393801 -34.248523) (xy 73.319526 -34.062667) (xy 73.252746 -33.873987)
			(xy 73.193569 -33.682787) (xy 73.14209 -33.489373) (xy 73.098389 -33.294053) (xy 73.062539 -33.097142)
			(xy 73.034596 -32.898954) (xy 73.014604 -32.699806) (xy 73.002596 -32.500018) (xy 72.998592 -32.29991)
			(xy 65.624314 -32.29991) (xy 65.645517 -32.327542) (xy 65.675484 -32.379448) (xy 65.69842 -32.434821)
			(xy 65.713933 -32.492714) (xy 65.721756 -32.552136) (xy 65.722246 -32.582104) (xy 65.721756 -32.612072)
			(xy 65.713933 -32.671494) (xy 65.69842 -32.729387) (xy 65.675484 -32.78476) (xy 65.645517 -32.836666)
			(xy 65.60903 -32.884216) (xy 65.56665 -32.926596) (xy 65.5191 -32.963083) (xy 65.467194 -32.99305)
			(xy 65.411821 -33.015986) (xy 65.353928 -33.031499) (xy 65.294506 -33.039322) (xy 65.23457 -33.039322)
			(xy 65.175148 -33.031499) (xy 65.117255 -33.015986) (xy 65.061882 -32.99305) (xy 65.009976 -32.963083)
			(xy 64.962426 -32.926596) (xy 64.920046 -32.884216) (xy 64.883559 -32.836666) (xy 64.853592 -32.78476)
			(xy 64.830656 -32.729387) (xy 64.815143 -32.671494) (xy 64.80732 -32.612072) (xy 29.170884 -32.612072)
			(xy 29.170884 -37.794692) (xy 51.007772 -37.794692) (xy 52.65928 -37.794692) (xy 52.65928 -39.446708)
			(xy 51.007772 -39.446708) (xy 51.007772 -37.794692) (xy 29.170884 -37.794692) (xy 29.170884 -38.661255)
			(xy 47.507896 -38.661255) (xy 47.507896 -38.580145) (xy 47.515846 -38.499426) (xy 47.531669 -38.419875)
			(xy 47.555214 -38.342259) (xy 47.586253 -38.267323) (xy 47.624488 -38.195791) (xy 47.66955 -38.128351)
			(xy 47.721005 -38.065652) (xy 47.778358 -38.008299) (xy 47.841057 -37.956844) (xy 47.908497 -37.911782)
			(xy 47.980029 -37.873547) (xy 48.054965 -37.842508) (xy 48.132581 -37.818963) (xy 48.212132 -37.80314)
			(xy 48.292851 -37.79519) (xy 48.373961 -37.79519) (xy 48.45468 -37.80314) (xy 48.534231 -37.818963)
			(xy 48.611847 -37.842508) (xy 48.686783 -37.873547) (xy 48.758315 -37.911782) (xy 48.825755 -37.956844)
			(xy 48.888454 -38.008299) (xy 48.945807 -38.065652) (xy 48.997262 -38.128351) (xy 49.042324 -38.195791)
			(xy 49.080559 -38.267323) (xy 49.111598 -38.342259) (xy 49.135143 -38.419875) (xy 49.150966 -38.499426)
			(xy 49.158916 -38.580145) (xy 49.159414 -38.6207) (xy 49.158916 -38.661255) (xy 49.150966 -38.741974)
			(xy 49.135143 -38.821525) (xy 49.111598 -38.899141) (xy 49.080559 -38.974077) (xy 49.042324 -39.045609)
			(xy 48.997262 -39.113049) (xy 48.945807 -39.175748) (xy 48.888454 -39.233101) (xy 48.825755 -39.284556)
			(xy 48.758315 -39.329618) (xy 48.686783 -39.367853) (xy 48.611847 -39.398892) (xy 48.534231 -39.422437)
			(xy 48.45468 -39.43826) (xy 48.373961 -39.44621) (xy 48.292851 -39.44621) (xy 48.212132 -39.43826)
			(xy 48.132581 -39.422437) (xy 48.054965 -39.398892) (xy 47.980029 -39.367853) (xy 47.908497 -39.329618)
			(xy 47.841057 -39.284556) (xy 47.778358 -39.233101) (xy 47.721005 -39.175748) (xy 47.66955 -39.113049)
			(xy 47.624488 -39.045609) (xy 47.586253 -38.974077) (xy 47.555214 -38.899141) (xy 47.531669 -38.821525)
			(xy 47.515846 -38.741974) (xy 47.507896 -38.661255) (xy 29.170884 -38.661255) (xy 29.170884 -39.868828)
			(xy 54.922011 -39.868828) (xy 54.925903 -39.814473) (xy 54.937491 -39.761226) (xy 54.956539 -39.71017)
			(xy 54.98266 -39.662344) (xy 54.99862 -39.640256) (xy 55.012256 -39.621271) (xy 55.032983 -39.57938)
			(xy 55.045703 -39.534406) (xy 55.049986 -39.487865) (xy 55.04569 -39.441324) (xy 55.032957 -39.396354)
			(xy 55.012219 -39.354469) (xy 54.99862 -39.335456) (xy 54.98266 -39.313368) (xy 54.956539 -39.265542)
			(xy 54.937491 -39.214486) (xy 54.925903 -39.161239) (xy 54.922011 -39.106884) (xy 54.925895 -39.052529)
			(xy 54.937475 -38.99928) (xy 54.956516 -38.948221) (xy 54.98263 -38.900391) (xy 55.015285 -38.856765)
			(xy 55.053816 -38.818231) (xy 55.09744 -38.785573) (xy 55.145267 -38.759456) (xy 55.196325 -38.740411)
			(xy 55.249573 -38.728827) (xy 55.303928 -38.724939) (xy 55.358283 -38.728827) (xy 55.411531 -38.740411)
			(xy 55.462589 -38.759456) (xy 55.510416 -38.785573) (xy 55.55404 -38.818231) (xy 55.592571 -38.856765)
			(xy 55.625226 -38.900391) (xy 55.65134 -38.948221) (xy 55.670381 -38.99928) (xy 55.681961 -39.052529)
			(xy 55.685845 -39.106884) (xy 55.681953 -39.161239) (xy 55.670365 -39.214486) (xy 55.651317 -39.265542)
			(xy 55.625196 -39.313368) (xy 55.609236 -39.335456) (xy 55.59568 -39.354495) (xy 55.574941 -39.396371)
			(xy 55.562208 -39.441333) (xy 55.557911 -39.487865) (xy 55.562195 -39.534398) (xy 55.574915 -39.579363)
			(xy 55.595643 -39.621245) (xy 55.609236 -39.640256) (xy 55.625196 -39.662344) (xy 55.651317 -39.71017)
			(xy 55.670365 -39.761226) (xy 55.681953 -39.814473) (xy 55.685845 -39.868828) (xy 57.453883 -39.868828)
			(xy 57.457775 -39.814473) (xy 57.469363 -39.761226) (xy 57.488411 -39.71017) (xy 57.514532 -39.662344)
			(xy 57.530492 -39.640256) (xy 57.544129 -39.621272) (xy 57.564858 -39.579381) (xy 57.57758 -39.534407)
			(xy 57.581864 -39.487865) (xy 57.577567 -39.441324) (xy 57.564833 -39.396353) (xy 57.544092 -39.354468)
			(xy 57.530492 -39.335456) (xy 57.514532 -39.313368) (xy 57.488411 -39.265542) (xy 57.469363 -39.214486)
			(xy 57.457775 -39.161239) (xy 57.453883 -39.106884) (xy 57.457767 -39.052529) (xy 57.469347 -38.99928)
			(xy 57.488388 -38.948221) (xy 57.514502 -38.900391) (xy 57.547157 -38.856765) (xy 57.585688 -38.818231)
			(xy 57.629312 -38.785573) (xy 57.677139 -38.759456) (xy 57.728197 -38.740411) (xy 57.781445 -38.728827)
			(xy 57.8358 -38.724939) (xy 57.890155 -38.728827) (xy 57.943403 -38.740411) (xy 57.994461 -38.759456)
			(xy 58.042288 -38.785573) (xy 58.085912 -38.818231) (xy 58.124443 -38.856765) (xy 58.157098 -38.900391)
			(xy 58.183212 -38.948221) (xy 58.202253 -38.99928) (xy 58.213833 -39.052529) (xy 58.217717 -39.106884)
			(xy 58.213825 -39.161239) (xy 58.202237 -39.214486) (xy 58.183189 -39.265542) (xy 58.157068 -39.313368)
			(xy 58.141108 -39.335456) (xy 58.127553 -39.354496) (xy 58.106816 -39.396372) (xy 58.094085 -39.441333)
			(xy 58.089789 -39.487865) (xy 58.094072 -39.534397) (xy 58.106791 -39.579362) (xy 58.127516 -39.621244)
			(xy 58.141108 -39.640256) (xy 58.157068 -39.662344) (xy 58.183189 -39.71017) (xy 58.202237 -39.761226)
			(xy 58.213825 -39.814473) (xy 58.217717 -39.868828) (xy 60.258297 -39.868828) (xy 60.262189 -39.814473)
			(xy 60.273777 -39.761226) (xy 60.292825 -39.71017) (xy 60.318946 -39.662344) (xy 60.334906 -39.640256)
			(xy 60.348542 -39.621272) (xy 60.369271 -39.579381) (xy 60.381991 -39.534407) (xy 60.386275 -39.487865)
			(xy 60.381978 -39.441324) (xy 60.369245 -39.396353) (xy 60.348505 -39.354468) (xy 60.334906 -39.335456)
			(xy 60.318946 -39.313368) (xy 60.292825 -39.265542) (xy 60.273777 -39.214486) (xy 60.262189 -39.161239)
			(xy 60.258297 -39.106884) (xy 60.262181 -39.052529) (xy 60.273761 -38.99928) (xy 60.292802 -38.948221)
			(xy 60.318916 -38.900391) (xy 60.351571 -38.856765) (xy 60.390102 -38.818231) (xy 60.433726 -38.785573)
			(xy 60.481553 -38.759456) (xy 60.532611 -38.740411) (xy 60.585859 -38.728827) (xy 60.640214 -38.724939)
			(xy 60.694569 -38.728827) (xy 60.747817 -38.740411) (xy 60.798875 -38.759456) (xy 60.846702 -38.785573)
			(xy 60.890326 -38.818231) (xy 60.928857 -38.856765) (xy 60.961512 -38.900391) (xy 60.987626 -38.948221)
			(xy 61.006667 -38.99928) (xy 61.018247 -39.052529) (xy 61.022131 -39.106884) (xy 61.018239 -39.161239)
			(xy 61.006651 -39.214486) (xy 60.987603 -39.265542) (xy 60.961482 -39.313368) (xy 60.945522 -39.335456)
			(xy 60.931966 -39.354495) (xy 60.911228 -39.396371) (xy 60.898497 -39.441333) (xy 60.8942 -39.487865)
			(xy 60.898484 -39.534398) (xy 60.911203 -39.579363) (xy 60.931929 -39.621245) (xy 60.945522 -39.640256)
			(xy 60.961482 -39.662344) (xy 60.987603 -39.71017) (xy 61.006651 -39.761226) (xy 61.018239 -39.814473)
			(xy 61.022131 -39.868828) (xy 62.631165 -39.868828) (xy 62.635057 -39.814473) (xy 62.646645 -39.761226)
			(xy 62.665693 -39.71017) (xy 62.691814 -39.662344) (xy 62.707774 -39.640256) (xy 62.721412 -39.621272)
			(xy 62.742143 -39.579382) (xy 62.754865 -39.534407) (xy 62.75915 -39.487865) (xy 62.754852 -39.441323)
			(xy 62.742117 -39.396352) (xy 62.721375 -39.354468) (xy 62.707774 -39.335456) (xy 62.691814 -39.313368)
			(xy 62.665693 -39.265542) (xy 62.646645 -39.214486) (xy 62.635057 -39.161239) (xy 62.631165 -39.106884)
			(xy 62.635049 -39.052529) (xy 62.646629 -38.99928) (xy 62.66567 -38.948221) (xy 62.691784 -38.900391)
			(xy 62.724439 -38.856765) (xy 62.76297 -38.818231) (xy 62.806594 -38.785573) (xy 62.854421 -38.759456)
			(xy 62.905479 -38.740411) (xy 62.958727 -38.728827) (xy 63.013082 -38.724939) (xy 63.067437 -38.728827)
			(xy 63.120685 -38.740411) (xy 63.171743 -38.759456) (xy 63.21957 -38.785573) (xy 63.263194 -38.818231)
			(xy 63.301725 -38.856765) (xy 63.33438 -38.900391) (xy 63.360494 -38.948221) (xy 63.379535 -38.99928)
			(xy 63.391115 -39.052529) (xy 63.394999 -39.106884) (xy 63.391107 -39.161239) (xy 63.379519 -39.214486)
			(xy 63.360471 -39.265542) (xy 63.33435 -39.313368) (xy 63.31839 -39.335456) (xy 63.304836 -39.354496)
			(xy 63.284101 -39.396372) (xy 63.27137 -39.441334) (xy 63.267074 -39.487865) (xy 63.271357 -39.534397)
			(xy 63.284075 -39.579362) (xy 63.304799 -39.621244) (xy 63.31839 -39.640256) (xy 63.33435 -39.662344)
			(xy 63.360471 -39.71017) (xy 63.379519 -39.761226) (xy 63.391107 -39.814473) (xy 63.394999 -39.868828)
			(xy 64.860777 -39.868828) (xy 64.864669 -39.814473) (xy 64.876257 -39.761226) (xy 64.895305 -39.71017)
			(xy 64.921426 -39.662344) (xy 64.937386 -39.640256) (xy 64.951023 -39.621272) (xy 64.971753 -39.579382)
			(xy 64.984475 -39.534407) (xy 64.988759 -39.487865) (xy 64.984462 -39.441324) (xy 64.971728 -39.396353)
			(xy 64.950986 -39.354468) (xy 64.937386 -39.335456) (xy 64.921426 -39.313368) (xy 64.895305 -39.265542)
			(xy 64.876257 -39.214486) (xy 64.864669 -39.161239) (xy 64.860777 -39.106884) (xy 64.864661 -39.052529)
			(xy 64.876241 -38.99928) (xy 64.895282 -38.948221) (xy 64.921396 -38.900391) (xy 64.954051 -38.856765)
			(xy 64.992582 -38.818231) (xy 65.036206 -38.785573) (xy 65.084033 -38.759456) (xy 65.135091 -38.740411)
			(xy 65.188339 -38.728827) (xy 65.242694 -38.724939) (xy 65.297049 -38.728827) (xy 65.350297 -38.740411)
			(xy 65.401355 -38.759456) (xy 65.449182 -38.785573) (xy 65.492806 -38.818231) (xy 65.531337 -38.856765)
			(xy 65.563992 -38.900391) (xy 65.590106 -38.948221) (xy 65.609147 -38.99928) (xy 65.620727 -39.052529)
			(xy 65.624611 -39.106884) (xy 65.620719 -39.161239) (xy 65.609131 -39.214486) (xy 65.590083 -39.265542)
			(xy 65.563962 -39.313368) (xy 65.548002 -39.335456) (xy 65.534447 -39.354496) (xy 65.513711 -39.396372)
			(xy 65.50098 -39.441334) (xy 65.496684 -39.487865) (xy 65.500967 -39.534397) (xy 65.513686 -39.579362)
			(xy 65.53441 -39.621244) (xy 65.548002 -39.640256) (xy 65.563962 -39.662344) (xy 65.590083 -39.71017)
			(xy 65.609131 -39.761226) (xy 65.620719 -39.814473) (xy 65.624611 -39.868828) (xy 65.620727 -39.923183)
			(xy 65.609147 -39.976432) (xy 65.590106 -40.027491) (xy 65.563992 -40.075321) (xy 65.531337 -40.118947)
			(xy 65.492806 -40.157481) (xy 65.449182 -40.190139) (xy 65.401355 -40.216256) (xy 65.350297 -40.235301)
			(xy 65.297049 -40.246885) (xy 65.242694 -40.250773) (xy 65.188339 -40.246885) (xy 65.135091 -40.235301)
			(xy 65.084033 -40.216256) (xy 65.036206 -40.190139) (xy 64.992582 -40.157481) (xy 64.954051 -40.118947)
			(xy 64.921396 -40.075321) (xy 64.895282 -40.027491) (xy 64.876241 -39.976432) (xy 64.864661 -39.923183)
			(xy 64.860777 -39.868828) (xy 63.394999 -39.868828) (xy 63.391115 -39.923183) (xy 63.379535 -39.976432)
			(xy 63.360494 -40.027491) (xy 63.33438 -40.075321) (xy 63.301725 -40.118947) (xy 63.263194 -40.157481)
			(xy 63.21957 -40.190139) (xy 63.171743 -40.216256) (xy 63.120685 -40.235301) (xy 63.067437 -40.246885)
			(xy 63.013082 -40.250773) (xy 62.958727 -40.246885) (xy 62.905479 -40.235301) (xy 62.854421 -40.216256)
			(xy 62.806594 -40.190139) (xy 62.76297 -40.157481) (xy 62.724439 -40.118947) (xy 62.691784 -40.075321)
			(xy 62.66567 -40.027491) (xy 62.646629 -39.976432) (xy 62.635049 -39.923183) (xy 62.631165 -39.868828)
			(xy 61.022131 -39.868828) (xy 61.018247 -39.923183) (xy 61.006667 -39.976432) (xy 60.987626 -40.027491)
			(xy 60.961512 -40.075321) (xy 60.928857 -40.118947) (xy 60.890326 -40.157481) (xy 60.846702 -40.190139)
			(xy 60.798875 -40.216256) (xy 60.747817 -40.235301) (xy 60.694569 -40.246885) (xy 60.640214 -40.250773)
			(xy 60.585859 -40.246885) (xy 60.532611 -40.235301) (xy 60.481553 -40.216256) (xy 60.433726 -40.190139)
			(xy 60.390102 -40.157481) (xy 60.351571 -40.118947) (xy 60.318916 -40.075321) (xy 60.292802 -40.027491)
			(xy 60.273761 -39.976432) (xy 60.262181 -39.923183) (xy 60.258297 -39.868828) (xy 58.217717 -39.868828)
			(xy 58.213833 -39.923183) (xy 58.202253 -39.976432) (xy 58.183212 -40.027491) (xy 58.157098 -40.075321)
			(xy 58.124443 -40.118947) (xy 58.085912 -40.157481) (xy 58.042288 -40.190139) (xy 57.994461 -40.216256)
			(xy 57.943403 -40.235301) (xy 57.890155 -40.246885) (xy 57.8358 -40.250773) (xy 57.781445 -40.246885)
			(xy 57.728197 -40.235301) (xy 57.677139 -40.216256) (xy 57.629312 -40.190139) (xy 57.585688 -40.157481)
			(xy 57.547157 -40.118947) (xy 57.514502 -40.075321) (xy 57.488388 -40.027491) (xy 57.469347 -39.976432)
			(xy 57.457767 -39.923183) (xy 57.453883 -39.868828) (xy 55.685845 -39.868828) (xy 55.681961 -39.923183)
			(xy 55.670381 -39.976432) (xy 55.65134 -40.027491) (xy 55.625226 -40.075321) (xy 55.592571 -40.118947)
			(xy 55.55404 -40.157481) (xy 55.510416 -40.190139) (xy 55.462589 -40.216256) (xy 55.411531 -40.235301)
			(xy 55.358283 -40.246885) (xy 55.303928 -40.250773) (xy 55.249573 -40.246885) (xy 55.196325 -40.235301)
			(xy 55.145267 -40.216256) (xy 55.09744 -40.190139) (xy 55.053816 -40.157481) (xy 55.015285 -40.118947)
			(xy 54.98263 -40.075321) (xy 54.956516 -40.027491) (xy 54.937475 -39.976432) (xy 54.925895 -39.923183)
			(xy 54.922011 -39.868828) (xy 29.170884 -39.868828) (xy 29.170884 -41.83174) (xy 54.922011 -41.83174)
			(xy 54.925903 -41.777385) (xy 54.937491 -41.724138) (xy 54.956539 -41.673082) (xy 54.98266 -41.625256)
			(xy 54.99862 -41.603168) (xy 55.012244 -41.584176) (xy 55.032973 -41.542287) (xy 55.045694 -41.497314)
			(xy 55.049979 -41.450774) (xy 55.045684 -41.404235) (xy 55.032954 -41.359265) (xy 55.012217 -41.317381)
			(xy 54.99862 -41.298368) (xy 54.98266 -41.27628) (xy 54.956539 -41.228454) (xy 54.937491 -41.177398)
			(xy 54.925903 -41.124151) (xy 54.922011 -41.069796) (xy 54.925895 -41.015441) (xy 54.937475 -40.962192)
			(xy 54.956516 -40.911133) (xy 54.98263 -40.863303) (xy 55.015285 -40.819677) (xy 55.053816 -40.781143)
			(xy 55.09744 -40.748485) (xy 55.145267 -40.722368) (xy 55.196325 -40.703323) (xy 55.249573 -40.691739)
			(xy 55.303928 -40.687851) (xy 55.358283 -40.691739) (xy 55.411531 -40.703323) (xy 55.462589 -40.722368)
			(xy 55.510416 -40.748485) (xy 55.55404 -40.781143) (xy 55.592571 -40.819677) (xy 55.625226 -40.863303)
			(xy 55.65134 -40.911133) (xy 55.670381 -40.962192) (xy 55.681961 -41.015441) (xy 55.685845 -41.069796)
			(xy 55.681953 -41.124151) (xy 55.670365 -41.177398) (xy 55.651317 -41.228454) (xy 55.625196 -41.27628)
			(xy 55.609236 -41.298368) (xy 55.595669 -41.3174) (xy 55.57493 -41.359277) (xy 55.562199 -41.404241)
			(xy 55.557904 -41.450774) (xy 55.56219 -41.497309) (xy 55.574912 -41.542275) (xy 55.595642 -41.584157)
			(xy 55.609236 -41.603168) (xy 55.625196 -41.625256) (xy 55.651317 -41.673082) (xy 55.670365 -41.724138)
			(xy 55.681953 -41.777385) (xy 55.685845 -41.83174) (xy 57.453883 -41.83174) (xy 57.457775 -41.777385)
			(xy 57.469363 -41.724138) (xy 57.488411 -41.673082) (xy 57.514532 -41.625256) (xy 57.530492 -41.603168)
			(xy 57.544118 -41.584176) (xy 57.564848 -41.542288) (xy 57.577571 -41.497315) (xy 57.581857 -41.450774)
			(xy 57.577562 -41.404234) (xy 57.56483 -41.359264) (xy 57.544091 -41.31738) (xy 57.530492 -41.298368)
			(xy 57.514532 -41.27628) (xy 57.488411 -41.228454) (xy 57.469363 -41.177398) (xy 57.457775 -41.124151)
			(xy 57.453883 -41.069796) (xy 57.457767 -41.015441) (xy 57.469347 -40.962192) (xy 57.488388 -40.911133)
			(xy 57.514502 -40.863303) (xy 57.547157 -40.819677) (xy 57.585688 -40.781143) (xy 57.629312 -40.748485)
			(xy 57.677139 -40.722368) (xy 57.728197 -40.703323) (xy 57.781445 -40.691739) (xy 57.8358 -40.687851)
			(xy 57.890155 -40.691739) (xy 57.943403 -40.703323) (xy 57.994461 -40.722368) (xy 58.042288 -40.748485)
			(xy 58.085912 -40.781143) (xy 58.124443 -40.819677) (xy 58.157098 -40.863303) (xy 58.183212 -40.911133)
			(xy 58.202253 -40.962192) (xy 58.213833 -41.015441) (xy 58.217717 -41.069796) (xy 58.213825 -41.124151)
			(xy 58.202237 -41.177398) (xy 58.183189 -41.228454) (xy 58.157068 -41.27628) (xy 58.141108 -41.298368)
			(xy 58.127542 -41.3174) (xy 58.106806 -41.359278) (xy 58.094076 -41.404242) (xy 58.089782 -41.450774)
			(xy 58.094067 -41.497308) (xy 58.106788 -41.542274) (xy 58.127515 -41.584156) (xy 58.141108 -41.603168)
			(xy 58.157068 -41.625256) (xy 58.183189 -41.673082) (xy 58.202237 -41.724138) (xy 58.213825 -41.777385)
			(xy 58.217717 -41.83174) (xy 60.258297 -41.83174) (xy 60.262189 -41.777385) (xy 60.273777 -41.724138)
			(xy 60.292825 -41.673082) (xy 60.318946 -41.625256) (xy 60.334906 -41.603168) (xy 60.348531 -41.584176)
			(xy 60.36926 -41.542287) (xy 60.381982 -41.497315) (xy 60.386268 -41.450774) (xy 60.381973 -41.404235)
			(xy 60.369242 -41.359265) (xy 60.348504 -41.31738) (xy 60.334906 -41.298368) (xy 60.318946 -41.27628)
			(xy 60.292825 -41.228454) (xy 60.273777 -41.177398) (xy 60.262189 -41.124151) (xy 60.258297 -41.069796)
			(xy 60.262181 -41.015441) (xy 60.273761 -40.962192) (xy 60.292802 -40.911133) (xy 60.318916 -40.863303)
			(xy 60.351571 -40.819677) (xy 60.390102 -40.781143) (xy 60.433726 -40.748485) (xy 60.481553 -40.722368)
			(xy 60.532611 -40.703323) (xy 60.585859 -40.691739) (xy 60.640214 -40.687851) (xy 60.694569 -40.691739)
			(xy 60.747817 -40.703323) (xy 60.798875 -40.722368) (xy 60.846702 -40.748485) (xy 60.890326 -40.781143)
			(xy 60.928857 -40.819677) (xy 60.961512 -40.863303) (xy 60.987626 -40.911133) (xy 61.006667 -40.962192)
			(xy 61.018247 -41.015441) (xy 61.022131 -41.069796) (xy 61.018239 -41.124151) (xy 61.006651 -41.177398)
			(xy 60.987603 -41.228454) (xy 60.961482 -41.27628) (xy 60.945522 -41.298368) (xy 60.931955 -41.3174)
			(xy 60.911218 -41.359278) (xy 60.898488 -41.404241) (xy 60.894193 -41.450774) (xy 60.898478 -41.497308)
			(xy 60.9112 -41.542274) (xy 60.931928 -41.584156) (xy 60.945522 -41.603168) (xy 60.961482 -41.625256)
			(xy 60.987603 -41.673082) (xy 61.006651 -41.724138) (xy 61.018239 -41.777385) (xy 61.022131 -41.83174)
			(xy 62.631165 -41.83174) (xy 62.635057 -41.777385) (xy 62.646645 -41.724138) (xy 62.665693 -41.673082)
			(xy 62.691814 -41.625256) (xy 62.707774 -41.603168) (xy 62.721401 -41.584177) (xy 62.742133 -41.542288)
			(xy 62.754856 -41.497315) (xy 62.759142 -41.450774) (xy 62.754847 -41.404234) (xy 62.742114 -41.359264)
			(xy 62.721374 -41.31738) (xy 62.707774 -41.298368) (xy 62.691814 -41.27628) (xy 62.665693 -41.228454)
			(xy 62.646645 -41.177398) (xy 62.635057 -41.124151) (xy 62.631165 -41.069796) (xy 62.635049 -41.015441)
			(xy 62.646629 -40.962192) (xy 62.66567 -40.911133) (xy 62.691784 -40.863303) (xy 62.724439 -40.819677)
			(xy 62.76297 -40.781143) (xy 62.806594 -40.748485) (xy 62.854421 -40.722368) (xy 62.905479 -40.703323)
			(xy 62.958727 -40.691739) (xy 63.013082 -40.687851) (xy 63.067437 -40.691739) (xy 63.120685 -40.703323)
			(xy 63.171743 -40.722368) (xy 63.21957 -40.748485) (xy 63.263194 -40.781143) (xy 63.301725 -40.819677)
			(xy 63.33438 -40.863303) (xy 63.360494 -40.911133) (xy 63.379535 -40.962192) (xy 63.391115 -41.015441)
			(xy 63.394999 -41.069796) (xy 63.391107 -41.124151) (xy 63.379519 -41.177398) (xy 63.360471 -41.228454)
			(xy 63.33435 -41.27628) (xy 63.31839 -41.298368) (xy 63.304825 -41.3174) (xy 63.28409 -41.359279)
			(xy 63.271362 -41.404242) (xy 63.267067 -41.450774) (xy 63.271352 -41.497308) (xy 63.284072 -41.542273)
			(xy 63.304798 -41.584156) (xy 63.31839 -41.603168) (xy 63.33435 -41.625256) (xy 63.360471 -41.673082)
			(xy 63.379519 -41.724138) (xy 63.391107 -41.777385) (xy 63.394999 -41.83174) (xy 64.860777 -41.83174)
			(xy 64.864669 -41.777385) (xy 64.876257 -41.724138) (xy 64.895305 -41.673082) (xy 64.921426 -41.625256)
			(xy 64.937386 -41.603168) (xy 64.951012 -41.584176) (xy 64.971743 -41.542288) (xy 64.984466 -41.497315)
			(xy 64.988752 -41.450774) (xy 64.984457 -41.404234) (xy 64.971725 -41.359264) (xy 64.950985 -41.31738)
			(xy 64.937386 -41.298368) (xy 64.921426 -41.27628) (xy 64.895305 -41.228454) (xy 64.876257 -41.177398)
			(xy 64.864669 -41.124151) (xy 64.860777 -41.069796) (xy 64.864661 -41.015441) (xy 64.876241 -40.962192)
			(xy 64.895282 -40.911133) (xy 64.921396 -40.863303) (xy 64.954051 -40.819677) (xy 64.992582 -40.781143)
			(xy 65.036206 -40.748485) (xy 65.084033 -40.722368) (xy 65.135091 -40.703323) (xy 65.188339 -40.691739)
			(xy 65.242694 -40.687851) (xy 65.297049 -40.691739) (xy 65.350297 -40.703323) (xy 65.401355 -40.722368)
			(xy 65.449182 -40.748485) (xy 65.492806 -40.781143) (xy 65.531337 -40.819677) (xy 65.563992 -40.863303)
			(xy 65.590106 -40.911133) (xy 65.609147 -40.962192) (xy 65.620727 -41.015441) (xy 65.624611 -41.069796)
			(xy 65.620719 -41.124151) (xy 65.609131 -41.177398) (xy 65.590083 -41.228454) (xy 65.563962 -41.27628)
			(xy 65.548002 -41.298368) (xy 65.534436 -41.3174) (xy 65.513701 -41.359278) (xy 65.500971 -41.404242)
			(xy 65.496677 -41.450774) (xy 65.500962 -41.497308) (xy 65.513682 -41.542274) (xy 65.534409 -41.584156)
			(xy 65.548002 -41.603168) (xy 65.563962 -41.625256) (xy 65.590083 -41.673082) (xy 65.609131 -41.724138)
			(xy 65.620719 -41.777385) (xy 65.624611 -41.83174) (xy 65.620727 -41.886095) (xy 65.609147 -41.939344)
			(xy 65.590106 -41.990403) (xy 65.563992 -42.038233) (xy 65.531337 -42.081859) (xy 65.492806 -42.120393)
			(xy 65.449182 -42.153051) (xy 65.401355 -42.179168) (xy 65.350297 -42.198213) (xy 65.297049 -42.209797)
			(xy 65.242694 -42.213685) (xy 65.188339 -42.209797) (xy 65.135091 -42.198213) (xy 65.084033 -42.179168)
			(xy 65.036206 -42.153051) (xy 64.992582 -42.120393) (xy 64.954051 -42.081859) (xy 64.921396 -42.038233)
			(xy 64.895282 -41.990403) (xy 64.876241 -41.939344) (xy 64.864661 -41.886095) (xy 64.860777 -41.83174)
			(xy 63.394999 -41.83174) (xy 63.391115 -41.886095) (xy 63.379535 -41.939344) (xy 63.360494 -41.990403)
			(xy 63.33438 -42.038233) (xy 63.301725 -42.081859) (xy 63.263194 -42.120393) (xy 63.21957 -42.153051)
			(xy 63.171743 -42.179168) (xy 63.120685 -42.198213) (xy 63.067437 -42.209797) (xy 63.013082 -42.213685)
			(xy 62.958727 -42.209797) (xy 62.905479 -42.198213) (xy 62.854421 -42.179168) (xy 62.806594 -42.153051)
			(xy 62.76297 -42.120393) (xy 62.724439 -42.081859) (xy 62.691784 -42.038233) (xy 62.66567 -41.990403)
			(xy 62.646629 -41.939344) (xy 62.635049 -41.886095) (xy 62.631165 -41.83174) (xy 61.022131 -41.83174)
			(xy 61.018247 -41.886095) (xy 61.006667 -41.939344) (xy 60.987626 -41.990403) (xy 60.961512 -42.038233)
			(xy 60.928857 -42.081859) (xy 60.890326 -42.120393) (xy 60.846702 -42.153051) (xy 60.798875 -42.179168)
			(xy 60.747817 -42.198213) (xy 60.694569 -42.209797) (xy 60.640214 -42.213685) (xy 60.585859 -42.209797)
			(xy 60.532611 -42.198213) (xy 60.481553 -42.179168) (xy 60.433726 -42.153051) (xy 60.390102 -42.120393)
			(xy 60.351571 -42.081859) (xy 60.318916 -42.038233) (xy 60.292802 -41.990403) (xy 60.273761 -41.939344)
			(xy 60.262181 -41.886095) (xy 60.258297 -41.83174) (xy 58.217717 -41.83174) (xy 58.213833 -41.886095)
			(xy 58.202253 -41.939344) (xy 58.183212 -41.990403) (xy 58.157098 -42.038233) (xy 58.124443 -42.081859)
			(xy 58.085912 -42.120393) (xy 58.042288 -42.153051) (xy 57.994461 -42.179168) (xy 57.943403 -42.198213)
			(xy 57.890155 -42.209797) (xy 57.8358 -42.213685) (xy 57.781445 -42.209797) (xy 57.728197 -42.198213)
			(xy 57.677139 -42.179168) (xy 57.629312 -42.153051) (xy 57.585688 -42.120393) (xy 57.547157 -42.081859)
			(xy 57.514502 -42.038233) (xy 57.488388 -41.990403) (xy 57.469347 -41.939344) (xy 57.457767 -41.886095)
			(xy 57.453883 -41.83174) (xy 55.685845 -41.83174) (xy 55.681961 -41.886095) (xy 55.670381 -41.939344)
			(xy 55.65134 -41.990403) (xy 55.625226 -42.038233) (xy 55.592571 -42.081859) (xy 55.55404 -42.120393)
			(xy 55.510416 -42.153051) (xy 55.462589 -42.179168) (xy 55.411531 -42.198213) (xy 55.358283 -42.209797)
			(xy 55.303928 -42.213685) (xy 55.249573 -42.209797) (xy 55.196325 -42.198213) (xy 55.145267 -42.179168)
			(xy 55.09744 -42.153051) (xy 55.053816 -42.120393) (xy 55.015285 -42.081859) (xy 54.98263 -42.038233)
			(xy 54.956516 -41.990403) (xy 54.937475 -41.939344) (xy 54.925895 -41.886095) (xy 54.922011 -41.83174)
			(xy 29.170884 -41.83174) (xy 29.170884 -43.975246) (xy 54.922011 -43.975246) (xy 54.925903 -43.920891)
			(xy 54.937491 -43.867644) (xy 54.956539 -43.816588) (xy 54.98266 -43.768762) (xy 54.99862 -43.746674)
			(xy 55.012239 -43.727678) (xy 55.032967 -43.68579) (xy 55.045689 -43.640818) (xy 55.049976 -43.594279)
			(xy 55.045682 -43.547741) (xy 55.032953 -43.502771) (xy 55.012217 -43.460887) (xy 54.99862 -43.441874)
			(xy 54.98266 -43.419786) (xy 54.956539 -43.37196) (xy 54.937491 -43.320904) (xy 54.925903 -43.267657)
			(xy 54.922011 -43.213302) (xy 54.925895 -43.158947) (xy 54.937475 -43.105698) (xy 54.956516 -43.054639)
			(xy 54.98263 -43.006809) (xy 55.015285 -42.963183) (xy 55.053816 -42.924649) (xy 55.09744 -42.891991)
			(xy 55.145267 -42.865874) (xy 55.196325 -42.846829) (xy 55.249573 -42.835245) (xy 55.303928 -42.831357)
			(xy 55.358283 -42.835245) (xy 55.411531 -42.846829) (xy 55.462589 -42.865874) (xy 55.510416 -42.891991)
			(xy 55.55404 -42.924649) (xy 55.592571 -42.963183) (xy 55.625226 -43.006809) (xy 55.65134 -43.054639)
			(xy 55.670381 -43.105698) (xy 55.681961 -43.158947) (xy 55.685845 -43.213302) (xy 55.681953 -43.267657)
			(xy 55.670365 -43.320904) (xy 55.651317 -43.37196) (xy 55.625196 -43.419786) (xy 55.609236 -43.441874)
			(xy 55.595663 -43.460902) (xy 55.574925 -43.50278) (xy 55.562195 -43.547745) (xy 55.5579 -43.594279)
			(xy 55.562187 -43.640814) (xy 55.57491 -43.685781) (xy 55.595641 -43.727663) (xy 55.609236 -43.746674)
			(xy 55.625196 -43.768762) (xy 55.651317 -43.816588) (xy 55.670365 -43.867644) (xy 55.681953 -43.920891)
			(xy 55.685845 -43.975246) (xy 57.453883 -43.975246) (xy 57.457775 -43.920891) (xy 57.469363 -43.867644)
			(xy 57.488411 -43.816588) (xy 57.514532 -43.768762) (xy 57.530492 -43.746674) (xy 57.544112 -43.727679)
			(xy 57.564843 -43.685791) (xy 57.577566 -43.640819) (xy 57.581853 -43.594279) (xy 57.577559 -43.54774)
			(xy 57.564828 -43.50277) (xy 57.54409 -43.460886) (xy 57.530492 -43.441874) (xy 57.514532 -43.419786)
			(xy 57.488411 -43.37196) (xy 57.469363 -43.320904) (xy 57.457775 -43.267657) (xy 57.453883 -43.213302)
			(xy 57.457767 -43.158947) (xy 57.469347 -43.105698) (xy 57.488388 -43.054639) (xy 57.514502 -43.006809)
			(xy 57.547157 -42.963183) (xy 57.585688 -42.924649) (xy 57.629312 -42.891991) (xy 57.677139 -42.865874)
			(xy 57.728197 -42.846829) (xy 57.781445 -42.835245) (xy 57.8358 -42.831357) (xy 57.890155 -42.835245)
			(xy 57.943403 -42.846829) (xy 57.994461 -42.865874) (xy 58.042288 -42.891991) (xy 58.085912 -42.924649)
			(xy 58.124443 -42.963183) (xy 58.157098 -43.006809) (xy 58.183212 -43.054639) (xy 58.202253 -43.105698)
			(xy 58.213833 -43.158947) (xy 58.217717 -43.213302) (xy 58.213825 -43.267657) (xy 58.202237 -43.320904)
			(xy 58.183189 -43.37196) (xy 58.157068 -43.419786) (xy 58.141108 -43.441874) (xy 58.127536 -43.460902)
			(xy 58.106801 -43.502781) (xy 58.094072 -43.547746) (xy 58.089778 -43.594279) (xy 58.094064 -43.640813)
			(xy 58.106786 -43.68578) (xy 58.127514 -43.727662) (xy 58.141108 -43.746674) (xy 58.157068 -43.768762)
			(xy 58.183189 -43.816588) (xy 58.202237 -43.867644) (xy 58.213825 -43.920891) (xy 58.217717 -43.975246)
			(xy 60.258297 -43.975246) (xy 60.262189 -43.920891) (xy 60.273777 -43.867644) (xy 60.292825 -43.816588)
			(xy 60.318946 -43.768762) (xy 60.334906 -43.746674) (xy 60.348525 -43.727678) (xy 60.369255 -43.68579)
			(xy 60.381978 -43.640819) (xy 60.386264 -43.594279) (xy 60.38197 -43.54774) (xy 60.36924 -43.502771)
			(xy 60.348504 -43.460886) (xy 60.334906 -43.441874) (xy 60.318946 -43.419786) (xy 60.292825 -43.37196)
			(xy 60.273777 -43.320904) (xy 60.262189 -43.267657) (xy 60.258297 -43.213302) (xy 60.262181 -43.158947)
			(xy 60.273761 -43.105698) (xy 60.292802 -43.054639) (xy 60.318916 -43.006809) (xy 60.351571 -42.963183)
			(xy 60.390102 -42.924649) (xy 60.433726 -42.891991) (xy 60.481553 -42.865874) (xy 60.532611 -42.846829)
			(xy 60.585859 -42.835245) (xy 60.640214 -42.831357) (xy 60.694569 -42.835245) (xy 60.747817 -42.846829)
			(xy 60.798875 -42.865874) (xy 60.846702 -42.891991) (xy 60.890326 -42.924649) (xy 60.928857 -42.963183)
			(xy 60.961512 -43.006809) (xy 60.987626 -43.054639) (xy 61.006667 -43.105698) (xy 61.018247 -43.158947)
			(xy 61.022131 -43.213302) (xy 61.018239 -43.267657) (xy 61.006651 -43.320904) (xy 60.987603 -43.37196)
			(xy 60.961482 -43.419786) (xy 60.945522 -43.441874) (xy 60.93195 -43.460902) (xy 60.911213 -43.502781)
			(xy 60.898483 -43.547745) (xy 60.894189 -43.594279) (xy 60.898476 -43.640814) (xy 60.911198 -43.68578)
			(xy 60.931928 -43.727662) (xy 60.945522 -43.746674) (xy 60.961482 -43.768762) (xy 60.987603 -43.816588)
			(xy 61.006651 -43.867644) (xy 61.018239 -43.920891) (xy 61.022131 -43.975246) (xy 62.631165 -43.975246)
			(xy 62.635057 -43.920891) (xy 62.646645 -43.867644) (xy 62.665693 -43.816588) (xy 62.691814 -43.768762)
			(xy 62.707774 -43.746674) (xy 62.721395 -43.727679) (xy 62.742127 -43.685792) (xy 62.754852 -43.64082)
			(xy 62.759139 -43.594279) (xy 62.754844 -43.547739) (xy 62.742112 -43.50277) (xy 62.721373 -43.460886)
			(xy 62.707774 -43.441874) (xy 62.691814 -43.419786) (xy 62.665693 -43.37196) (xy 62.646645 -43.320904)
			(xy 62.635057 -43.267657) (xy 62.631165 -43.213302) (xy 62.635049 -43.158947) (xy 62.646629 -43.105698)
			(xy 62.66567 -43.054639) (xy 62.691784 -43.006809) (xy 62.724439 -42.963183) (xy 62.76297 -42.924649)
			(xy 62.806594 -42.891991) (xy 62.854421 -42.865874) (xy 62.905479 -42.846829) (xy 62.958727 -42.835245)
			(xy 63.013082 -42.831357) (xy 63.067437 -42.835245) (xy 63.120685 -42.846829) (xy 63.171743 -42.865874)
			(xy 63.21957 -42.891991) (xy 63.263194 -42.924649) (xy 63.301725 -42.963183) (xy 63.33438 -43.006809)
			(xy 63.360494 -43.054639) (xy 63.379535 -43.105698) (xy 63.391115 -43.158947) (xy 63.394999 -43.213302)
			(xy 63.391107 -43.267657) (xy 63.379519 -43.320904) (xy 63.360471 -43.37196) (xy 63.33435 -43.419786)
			(xy 63.31839 -43.441874) (xy 63.304819 -43.460903) (xy 63.284085 -43.502782) (xy 63.271357 -43.547746)
			(xy 63.267064 -43.594279) (xy 63.271349 -43.640813) (xy 63.28407 -43.685779) (xy 63.304797 -43.727662)
			(xy 63.31839 -43.746674) (xy 63.33435 -43.768762) (xy 63.360471 -43.816588) (xy 63.379519 -43.867644)
			(xy 63.391107 -43.920891) (xy 63.394999 -43.975246) (xy 64.860777 -43.975246) (xy 64.864669 -43.920891)
			(xy 64.876257 -43.867644) (xy 64.895305 -43.816588) (xy 64.921426 -43.768762) (xy 64.937386 -43.746674)
			(xy 64.951006 -43.727679) (xy 64.971738 -43.685791) (xy 64.984462 -43.640819) (xy 64.988748 -43.594279)
			(xy 64.984454 -43.54774) (xy 64.971723 -43.50277) (xy 64.950985 -43.460886) (xy 64.937386 -43.441874)
			(xy 64.921426 -43.419786) (xy 64.895305 -43.37196) (xy 64.876257 -43.320904) (xy 64.864669 -43.267657)
			(xy 64.860777 -43.213302) (xy 64.864661 -43.158947) (xy 64.876241 -43.105698) (xy 64.895282 -43.054639)
			(xy 64.921396 -43.006809) (xy 64.954051 -42.963183) (xy 64.992582 -42.924649) (xy 65.036206 -42.891991)
			(xy 65.084033 -42.865874) (xy 65.135091 -42.846829) (xy 65.188339 -42.835245) (xy 65.242694 -42.831357)
			(xy 65.297049 -42.835245) (xy 65.350297 -42.846829) (xy 65.401355 -42.865874) (xy 65.449182 -42.891991)
			(xy 65.492806 -42.924649) (xy 65.531337 -42.963183) (xy 65.563992 -43.006809) (xy 65.590106 -43.054639)
			(xy 65.609147 -43.105698) (xy 65.620727 -43.158947) (xy 65.624611 -43.213302) (xy 65.620719 -43.267657)
			(xy 65.609131 -43.320904) (xy 65.590083 -43.37196) (xy 65.563962 -43.419786) (xy 65.548002 -43.441874)
			(xy 65.534431 -43.460902) (xy 65.513696 -43.502782) (xy 65.500967 -43.547746) (xy 65.496673 -43.594279)
			(xy 65.500959 -43.640813) (xy 65.513681 -43.68578) (xy 65.534409 -43.727662) (xy 65.548002 -43.746674)
			(xy 65.563962 -43.768762) (xy 65.590083 -43.816588) (xy 65.609131 -43.867644) (xy 65.620719 -43.920891)
			(xy 65.624611 -43.975246) (xy 65.620727 -44.029601) (xy 65.609147 -44.08285) (xy 65.590106 -44.133909)
			(xy 65.563992 -44.181739) (xy 65.531337 -44.225365) (xy 65.492806 -44.263899) (xy 65.449182 -44.296557)
			(xy 65.401355 -44.322674) (xy 65.350297 -44.341719) (xy 65.297049 -44.353303) (xy 65.242694 -44.357191)
			(xy 65.188339 -44.353303) (xy 65.135091 -44.341719) (xy 65.084033 -44.322674) (xy 65.036206 -44.296557)
			(xy 64.992582 -44.263899) (xy 64.954051 -44.225365) (xy 64.921396 -44.181739) (xy 64.895282 -44.133909)
			(xy 64.876241 -44.08285) (xy 64.864661 -44.029601) (xy 64.860777 -43.975246) (xy 63.394999 -43.975246)
			(xy 63.391115 -44.029601) (xy 63.379535 -44.08285) (xy 63.360494 -44.133909) (xy 63.33438 -44.181739)
			(xy 63.301725 -44.225365) (xy 63.263194 -44.263899) (xy 63.21957 -44.296557) (xy 63.171743 -44.322674)
			(xy 63.120685 -44.341719) (xy 63.067437 -44.353303) (xy 63.013082 -44.357191) (xy 62.958727 -44.353303)
			(xy 62.905479 -44.341719) (xy 62.854421 -44.322674) (xy 62.806594 -44.296557) (xy 62.76297 -44.263899)
			(xy 62.724439 -44.225365) (xy 62.691784 -44.181739) (xy 62.66567 -44.133909) (xy 62.646629 -44.08285)
			(xy 62.635049 -44.029601) (xy 62.631165 -43.975246) (xy 61.022131 -43.975246) (xy 61.018247 -44.029601)
			(xy 61.006667 -44.08285) (xy 60.987626 -44.133909) (xy 60.961512 -44.181739) (xy 60.928857 -44.225365)
			(xy 60.890326 -44.263899) (xy 60.846702 -44.296557) (xy 60.798875 -44.322674) (xy 60.747817 -44.341719)
			(xy 60.694569 -44.353303) (xy 60.640214 -44.357191) (xy 60.585859 -44.353303) (xy 60.532611 -44.341719)
			(xy 60.481553 -44.322674) (xy 60.433726 -44.296557) (xy 60.390102 -44.263899) (xy 60.351571 -44.225365)
			(xy 60.318916 -44.181739) (xy 60.292802 -44.133909) (xy 60.273761 -44.08285) (xy 60.262181 -44.029601)
			(xy 60.258297 -43.975246) (xy 58.217717 -43.975246) (xy 58.213833 -44.029601) (xy 58.202253 -44.08285)
			(xy 58.183212 -44.133909) (xy 58.157098 -44.181739) (xy 58.124443 -44.225365) (xy 58.085912 -44.263899)
			(xy 58.042288 -44.296557) (xy 57.994461 -44.322674) (xy 57.943403 -44.341719) (xy 57.890155 -44.353303)
			(xy 57.8358 -44.357191) (xy 57.781445 -44.353303) (xy 57.728197 -44.341719) (xy 57.677139 -44.322674)
			(xy 57.629312 -44.296557) (xy 57.585688 -44.263899) (xy 57.547157 -44.225365) (xy 57.514502 -44.181739)
			(xy 57.488388 -44.133909) (xy 57.469347 -44.08285) (xy 57.457767 -44.029601) (xy 57.453883 -43.975246)
			(xy 55.685845 -43.975246) (xy 55.681961 -44.029601) (xy 55.670381 -44.08285) (xy 55.65134 -44.133909)
			(xy 55.625226 -44.181739) (xy 55.592571 -44.225365) (xy 55.55404 -44.263899) (xy 55.510416 -44.296557)
			(xy 55.462589 -44.322674) (xy 55.411531 -44.341719) (xy 55.358283 -44.353303) (xy 55.303928 -44.357191)
			(xy 55.249573 -44.353303) (xy 55.196325 -44.341719) (xy 55.145267 -44.322674) (xy 55.09744 -44.296557)
			(xy 55.053816 -44.263899) (xy 55.015285 -44.225365) (xy 54.98263 -44.181739) (xy 54.956516 -44.133909)
			(xy 54.937475 -44.08285) (xy 54.925895 -44.029601) (xy 54.922011 -43.975246) (xy 29.170884 -43.975246)
			(xy 29.170884 -51.36007) (xy 39.818564 -51.36007) (xy 39.819054 -51.302663) (xy 39.826889 -51.188117)
			(xy 39.842523 -51.074372) (xy 39.865882 -50.96196) (xy 39.896859 -50.851403) (xy 39.935308 -50.743218)
			(xy 39.98105 -50.63791) (xy 40.033872 -50.535968) (xy 40.093527 -50.437869) (xy 40.159738 -50.344069)
			(xy 40.232196 -50.255007) (xy 40.310562 -50.171096) (xy 40.394473 -50.09273) (xy 40.483535 -50.020272)
			(xy 40.577335 -49.954061) (xy 40.675434 -49.894406) (xy 40.777376 -49.841584) (xy 40.882684 -49.795842)
			(xy 40.990869 -49.757393) (xy 41.101426 -49.726416) (xy 41.213838 -49.703057) (xy 41.327583 -49.687423)
			(xy 41.442129 -49.679588) (xy 41.556943 -49.679588) (xy 41.671489 -49.687423) (xy 41.785234 -49.703057)
			(xy 41.897646 -49.726416) (xy 42.008203 -49.757393) (xy 42.116388 -49.795842) (xy 42.221696 -49.841584)
			(xy 42.323638 -49.894406) (xy 42.421737 -49.954061) (xy 42.50107 -50.01006) (xy 63.647577 -50.01006)
			(xy 63.651612 -49.934356) (xy 63.663671 -49.859511) (xy 63.683617 -49.78637) (xy 63.711224 -49.715765)
			(xy 63.74618 -49.648494) (xy 63.788088 -49.585319) (xy 63.836474 -49.526957) (xy 63.89079 -49.474069)
			(xy 63.950419 -49.427254) (xy 64.014687 -49.387042) (xy 64.082864 -49.35389) (xy 64.15418 -49.328172)
			(xy 64.227825 -49.31018) (xy 64.302965 -49.300118) (xy 64.378749 -49.298099) (xy 64.454319 -49.304148)
			(xy 64.528817 -49.318195) (xy 64.6014 -49.340081) (xy 64.671246 -49.369558) (xy 64.737563 -49.406293)
			(xy 64.799599 -49.449868) (xy 64.856652 -49.49979) (xy 64.908076 -49.555494) (xy 64.953287 -49.616349)
			(xy 64.991774 -49.681664) (xy 65.0231 -49.7507) (xy 65.04691 -49.822675) (xy 65.062935 -49.896773)
			(xy 65.070994 -49.972154) (xy 65.071498 -50.01006) (xy 66.187577 -50.01006) (xy 66.191612 -49.934356)
			(xy 66.203671 -49.859511) (xy 66.223617 -49.78637) (xy 66.251224 -49.715765) (xy 66.28618 -49.648494)
			(xy 66.328088 -49.585319) (xy 66.376474 -49.526957) (xy 66.43079 -49.474069) (xy 66.490419 -49.427254)
			(xy 66.554687 -49.387042) (xy 66.622864 -49.35389) (xy 66.69418 -49.328172) (xy 66.767825 -49.31018)
			(xy 66.842965 -49.300118) (xy 66.918749 -49.298099) (xy 66.994319 -49.304148) (xy 67.068817 -49.318195)
			(xy 67.1414 -49.340081) (xy 67.211246 -49.369558) (xy 67.277563 -49.406293) (xy 67.339599 -49.449868)
			(xy 67.396652 -49.49979) (xy 67.448076 -49.555494) (xy 67.493287 -49.616349) (xy 67.531774 -49.681664)
			(xy 67.5631 -49.7507) (xy 67.58691 -49.822675) (xy 67.602935 -49.896773) (xy 67.610994 -49.972154)
			(xy 67.611498 -50.01006) (xy 68.727577 -50.01006) (xy 68.731612 -49.934356) (xy 68.743671 -49.859511)
			(xy 68.763617 -49.78637) (xy 68.791224 -49.715765) (xy 68.82618 -49.648494) (xy 68.868088 -49.585319)
			(xy 68.916474 -49.526957) (xy 68.97079 -49.474069) (xy 69.030419 -49.427254) (xy 69.094687 -49.387042)
			(xy 69.162864 -49.35389) (xy 69.23418 -49.328172) (xy 69.307825 -49.31018) (xy 69.382965 -49.300118)
			(xy 69.458749 -49.298099) (xy 69.534319 -49.304148) (xy 69.608817 -49.318195) (xy 69.6814 -49.340081)
			(xy 69.751246 -49.369558) (xy 69.817563 -49.406293) (xy 69.879599 -49.449868) (xy 69.936652 -49.49979)
			(xy 69.988076 -49.555494) (xy 70.033287 -49.616349) (xy 70.071774 -49.681664) (xy 70.1031 -49.7507)
			(xy 70.12691 -49.822675) (xy 70.142935 -49.896773) (xy 70.150994 -49.972154) (xy 70.151498 -50.01006)
			(xy 71.267577 -50.01006) (xy 71.271612 -49.934356) (xy 71.283671 -49.859511) (xy 71.303617 -49.78637)
			(xy 71.331224 -49.715765) (xy 71.36618 -49.648494) (xy 71.408088 -49.585319) (xy 71.456474 -49.526957)
			(xy 71.51079 -49.474069) (xy 71.570419 -49.427254) (xy 71.634687 -49.387042) (xy 71.702864 -49.35389)
			(xy 71.77418 -49.328172) (xy 71.847825 -49.31018) (xy 71.922965 -49.300118) (xy 71.998749 -49.298099)
			(xy 72.074319 -49.304148) (xy 72.148817 -49.318195) (xy 72.2214 -49.340081) (xy 72.291246 -49.369558)
			(xy 72.357563 -49.406293) (xy 72.419599 -49.449868) (xy 72.476652 -49.49979) (xy 72.528076 -49.555494)
			(xy 72.573287 -49.616349) (xy 72.611774 -49.681664) (xy 72.6431 -49.7507) (xy 72.66691 -49.822675)
			(xy 72.682935 -49.896773) (xy 72.690994 -49.972154) (xy 72.691498 -50.01006) (xy 73.807577 -50.01006)
			(xy 73.811612 -49.934356) (xy 73.823671 -49.859511) (xy 73.843617 -49.78637) (xy 73.871224 -49.715765)
			(xy 73.90618 -49.648494) (xy 73.948088 -49.585319) (xy 73.996474 -49.526957) (xy 74.05079 -49.474069)
			(xy 74.110419 -49.427254) (xy 74.174687 -49.387042) (xy 74.242864 -49.35389) (xy 74.31418 -49.328172)
			(xy 74.387825 -49.31018) (xy 74.462965 -49.300118) (xy 74.538749 -49.298099) (xy 74.614319 -49.304148)
			(xy 74.688817 -49.318195) (xy 74.7614 -49.340081) (xy 74.831246 -49.369558) (xy 74.897563 -49.406293)
			(xy 74.959599 -49.449868) (xy 75.016652 -49.49979) (xy 75.068076 -49.555494) (xy 75.113287 -49.616349)
			(xy 75.151774 -49.681664) (xy 75.1831 -49.7507) (xy 75.20691 -49.822675) (xy 75.222935 -49.896773)
			(xy 75.230994 -49.972154) (xy 75.231498 -50.01006) (xy 76.347577 -50.01006) (xy 76.351612 -49.934356)
			(xy 76.363671 -49.859511) (xy 76.383617 -49.78637) (xy 76.411224 -49.715765) (xy 76.44618 -49.648494)
			(xy 76.488088 -49.585319) (xy 76.536474 -49.526957) (xy 76.59079 -49.474069) (xy 76.650419 -49.427254)
			(xy 76.714687 -49.387042) (xy 76.782864 -49.35389) (xy 76.85418 -49.328172) (xy 76.927825 -49.31018)
			(xy 77.002965 -49.300118) (xy 77.078749 -49.298099) (xy 77.154319 -49.304148) (xy 77.228817 -49.318195)
			(xy 77.3014 -49.340081) (xy 77.371246 -49.369558) (xy 77.437563 -49.406293) (xy 77.499599 -49.449868)
			(xy 77.556652 -49.49979) (xy 77.608076 -49.555494) (xy 77.653287 -49.616349) (xy 77.691774 -49.681664)
			(xy 77.7231 -49.7507) (xy 77.74691 -49.822675) (xy 77.762935 -49.896773) (xy 77.770994 -49.972154)
			(xy 77.771498 -50.01006) (xy 78.887577 -50.01006) (xy 78.891612 -49.934356) (xy 78.903671 -49.859511)
			(xy 78.923617 -49.78637) (xy 78.951224 -49.715765) (xy 78.98618 -49.648494) (xy 79.028088 -49.585319)
			(xy 79.076474 -49.526957) (xy 79.13079 -49.474069) (xy 79.190419 -49.427254) (xy 79.254687 -49.387042)
			(xy 79.322864 -49.35389) (xy 79.39418 -49.328172) (xy 79.467825 -49.31018) (xy 79.542965 -49.300118)
			(xy 79.618749 -49.298099) (xy 79.694319 -49.304148) (xy 79.768817 -49.318195) (xy 79.8414 -49.340081)
			(xy 79.911246 -49.369558) (xy 79.977563 -49.406293) (xy 80.039599 -49.449868) (xy 80.096652 -49.49979)
			(xy 80.148076 -49.555494) (xy 80.193287 -49.616349) (xy 80.231774 -49.681664) (xy 80.2631 -49.7507)
			(xy 80.28691 -49.822675) (xy 80.302935 -49.896773) (xy 80.310994 -49.972154) (xy 80.311498 -50.01006)
			(xy 81.427577 -50.01006) (xy 81.431612 -49.934356) (xy 81.443671 -49.859511) (xy 81.463617 -49.78637)
			(xy 81.491224 -49.715765) (xy 81.52618 -49.648494) (xy 81.568088 -49.585319) (xy 81.616474 -49.526957)
			(xy 81.67079 -49.474069) (xy 81.730419 -49.427254) (xy 81.794687 -49.387042) (xy 81.862864 -49.35389)
			(xy 81.93418 -49.328172) (xy 82.007825 -49.31018) (xy 82.082965 -49.300118) (xy 82.158749 -49.298099)
			(xy 82.234319 -49.304148) (xy 82.308817 -49.318195) (xy 82.3814 -49.340081) (xy 82.451246 -49.369558)
			(xy 82.517563 -49.406293) (xy 82.579599 -49.449868) (xy 82.585544 -49.45507) (xy 86.197697 -49.45507)
			(xy 86.201732 -49.379366) (xy 86.213791 -49.304521) (xy 86.233737 -49.23138) (xy 86.261344 -49.160775)
			(xy 86.2963 -49.093504) (xy 86.338208 -49.030329) (xy 86.386594 -48.971967) (xy 86.44091 -48.919079)
			(xy 86.500539 -48.872264) (xy 86.564807 -48.832052) (xy 86.632984 -48.7989) (xy 86.7043 -48.773182)
			(xy 86.777945 -48.75519) (xy 86.853085 -48.745128) (xy 86.928869 -48.743109) (xy 87.004439 -48.749158)
			(xy 87.078937 -48.763205) (xy 87.15152 -48.785091) (xy 87.221366 -48.814568) (xy 87.287683 -48.851303)
			(xy 87.349719 -48.894878) (xy 87.406772 -48.9448) (xy 87.458196 -49.000504) (xy 87.503407 -49.061359)
			(xy 87.541894 -49.126674) (xy 87.57322 -49.19571) (xy 87.59703 -49.267685) (xy 87.613055 -49.341783)
			(xy 87.621114 -49.417164) (xy 87.621618 -49.45507) (xy 87.621114 -49.492976) (xy 87.613055 -49.568357)
			(xy 87.59703 -49.642455) (xy 87.57322 -49.71443) (xy 87.541894 -49.783466) (xy 87.503407 -49.848781)
			(xy 87.458196 -49.909636) (xy 87.406772 -49.96534) (xy 87.349719 -50.015262) (xy 87.287683 -50.058837)
			(xy 87.221366 -50.095572) (xy 87.15152 -50.125049) (xy 87.078937 -50.146935) (xy 87.004439 -50.160982)
			(xy 86.928869 -50.167031) (xy 86.853085 -50.165012) (xy 86.777945 -50.15495) (xy 86.7043 -50.136958)
			(xy 86.632984 -50.11124) (xy 86.564807 -50.078088) (xy 86.500539 -50.037876) (xy 86.44091 -49.991061)
			(xy 86.386594 -49.938173) (xy 86.338208 -49.879811) (xy 86.2963 -49.816636) (xy 86.261344 -49.749365)
			(xy 86.233737 -49.67876) (xy 86.213791 -49.605619) (xy 86.201732 -49.530774) (xy 86.197697 -49.45507)
			(xy 82.585544 -49.45507) (xy 82.636652 -49.49979) (xy 82.688076 -49.555494) (xy 82.733287 -49.616349)
			(xy 82.771774 -49.681664) (xy 82.8031 -49.7507) (xy 82.82691 -49.822675) (xy 82.842935 -49.896773)
			(xy 82.850994 -49.972154) (xy 82.851498 -50.01006) (xy 82.850994 -50.047966) (xy 82.842935 -50.123347)
			(xy 82.82691 -50.197445) (xy 82.8031 -50.26942) (xy 82.771774 -50.338456) (xy 82.733287 -50.403771)
			(xy 82.688076 -50.464626) (xy 82.636652 -50.52033) (xy 82.579599 -50.570252) (xy 82.517563 -50.613827)
			(xy 82.451246 -50.650562) (xy 82.3814 -50.680039) (xy 82.308817 -50.701925) (xy 82.234319 -50.715972)
			(xy 82.158749 -50.722021) (xy 82.082965 -50.720002) (xy 82.007825 -50.70994) (xy 81.93418 -50.691948)
			(xy 81.862864 -50.66623) (xy 81.794687 -50.633078) (xy 81.730419 -50.592866) (xy 81.67079 -50.546051)
			(xy 81.616474 -50.493163) (xy 81.568088 -50.434801) (xy 81.52618 -50.371626) (xy 81.491224 -50.304355)
			(xy 81.463617 -50.23375) (xy 81.443671 -50.160609) (xy 81.431612 -50.085764) (xy 81.427577 -50.01006)
			(xy 80.311498 -50.01006) (xy 80.310994 -50.047966) (xy 80.302935 -50.123347) (xy 80.28691 -50.197445)
			(xy 80.2631 -50.26942) (xy 80.231774 -50.338456) (xy 80.193287 -50.403771) (xy 80.148076 -50.464626)
			(xy 80.096652 -50.52033) (xy 80.039599 -50.570252) (xy 79.977563 -50.613827) (xy 79.911246 -50.650562)
			(xy 79.8414 -50.680039) (xy 79.768817 -50.701925) (xy 79.694319 -50.715972) (xy 79.618749 -50.722021)
			(xy 79.542965 -50.720002) (xy 79.467825 -50.70994) (xy 79.39418 -50.691948) (xy 79.322864 -50.66623)
			(xy 79.254687 -50.633078) (xy 79.190419 -50.592866) (xy 79.13079 -50.546051) (xy 79.076474 -50.493163)
			(xy 79.028088 -50.434801) (xy 78.98618 -50.371626) (xy 78.951224 -50.304355) (xy 78.923617 -50.23375)
			(xy 78.903671 -50.160609) (xy 78.891612 -50.085764) (xy 78.887577 -50.01006) (xy 77.771498 -50.01006)
			(xy 77.770994 -50.047966) (xy 77.762935 -50.123347) (xy 77.74691 -50.197445) (xy 77.7231 -50.26942)
			(xy 77.691774 -50.338456) (xy 77.653287 -50.403771) (xy 77.608076 -50.464626) (xy 77.556652 -50.52033)
			(xy 77.499599 -50.570252) (xy 77.437563 -50.613827) (xy 77.371246 -50.650562) (xy 77.3014 -50.680039)
			(xy 77.228817 -50.701925) (xy 77.154319 -50.715972) (xy 77.078749 -50.722021) (xy 77.002965 -50.720002)
			(xy 76.927825 -50.70994) (xy 76.85418 -50.691948) (xy 76.782864 -50.66623) (xy 76.714687 -50.633078)
			(xy 76.650419 -50.592866) (xy 76.59079 -50.546051) (xy 76.536474 -50.493163) (xy 76.488088 -50.434801)
			(xy 76.44618 -50.371626) (xy 76.411224 -50.304355) (xy 76.383617 -50.23375) (xy 76.363671 -50.160609)
			(xy 76.351612 -50.085764) (xy 76.347577 -50.01006) (xy 75.231498 -50.01006) (xy 75.230994 -50.047966)
			(xy 75.222935 -50.123347) (xy 75.20691 -50.197445) (xy 75.1831 -50.26942) (xy 75.151774 -50.338456)
			(xy 75.113287 -50.403771) (xy 75.068076 -50.464626) (xy 75.016652 -50.52033) (xy 74.959599 -50.570252)
			(xy 74.897563 -50.613827) (xy 74.831246 -50.650562) (xy 74.7614 -50.680039) (xy 74.688817 -50.701925)
			(xy 74.614319 -50.715972) (xy 74.538749 -50.722021) (xy 74.462965 -50.720002) (xy 74.387825 -50.70994)
			(xy 74.31418 -50.691948) (xy 74.242864 -50.66623) (xy 74.174687 -50.633078) (xy 74.110419 -50.592866)
			(xy 74.05079 -50.546051) (xy 73.996474 -50.493163) (xy 73.948088 -50.434801) (xy 73.90618 -50.371626)
			(xy 73.871224 -50.304355) (xy 73.843617 -50.23375) (xy 73.823671 -50.160609) (xy 73.811612 -50.085764)
			(xy 73.807577 -50.01006) (xy 72.691498 -50.01006) (xy 72.690994 -50.047966) (xy 72.682935 -50.123347)
			(xy 72.66691 -50.197445) (xy 72.6431 -50.26942) (xy 72.611774 -50.338456) (xy 72.573287 -50.403771)
			(xy 72.528076 -50.464626) (xy 72.476652 -50.52033) (xy 72.419599 -50.570252) (xy 72.357563 -50.613827)
			(xy 72.291246 -50.650562) (xy 72.2214 -50.680039) (xy 72.148817 -50.701925) (xy 72.074319 -50.715972)
			(xy 71.998749 -50.722021) (xy 71.922965 -50.720002) (xy 71.847825 -50.70994) (xy 71.77418 -50.691948)
			(xy 71.702864 -50.66623) (xy 71.634687 -50.633078) (xy 71.570419 -50.592866) (xy 71.51079 -50.546051)
			(xy 71.456474 -50.493163) (xy 71.408088 -50.434801) (xy 71.36618 -50.371626) (xy 71.331224 -50.304355)
			(xy 71.303617 -50.23375) (xy 71.283671 -50.160609) (xy 71.271612 -50.085764) (xy 71.267577 -50.01006)
			(xy 70.151498 -50.01006) (xy 70.150994 -50.047966) (xy 70.142935 -50.123347) (xy 70.12691 -50.197445)
			(xy 70.1031 -50.26942) (xy 70.071774 -50.338456) (xy 70.033287 -50.403771) (xy 69.988076 -50.464626)
			(xy 69.936652 -50.52033) (xy 69.879599 -50.570252) (xy 69.817563 -50.613827) (xy 69.751246 -50.650562)
			(xy 69.6814 -50.680039) (xy 69.608817 -50.701925) (xy 69.534319 -50.715972) (xy 69.458749 -50.722021)
			(xy 69.382965 -50.720002) (xy 69.307825 -50.70994) (xy 69.23418 -50.691948) (xy 69.162864 -50.66623)
			(xy 69.094687 -50.633078) (xy 69.030419 -50.592866) (xy 68.97079 -50.546051) (xy 68.916474 -50.493163)
			(xy 68.868088 -50.434801) (xy 68.82618 -50.371626) (xy 68.791224 -50.304355) (xy 68.763617 -50.23375)
			(xy 68.743671 -50.160609) (xy 68.731612 -50.085764) (xy 68.727577 -50.01006) (xy 67.611498 -50.01006)
			(xy 67.610994 -50.047966) (xy 67.602935 -50.123347) (xy 67.58691 -50.197445) (xy 67.5631 -50.26942)
			(xy 67.531774 -50.338456) (xy 67.493287 -50.403771) (xy 67.448076 -50.464626) (xy 67.396652 -50.52033)
			(xy 67.339599 -50.570252) (xy 67.277563 -50.613827) (xy 67.211246 -50.650562) (xy 67.1414 -50.680039)
			(xy 67.068817 -50.701925) (xy 66.994319 -50.715972) (xy 66.918749 -50.722021) (xy 66.842965 -50.720002)
			(xy 66.767825 -50.70994) (xy 66.69418 -50.691948) (xy 66.622864 -50.66623) (xy 66.554687 -50.633078)
			(xy 66.490419 -50.592866) (xy 66.43079 -50.546051) (xy 66.376474 -50.493163) (xy 66.328088 -50.434801)
			(xy 66.28618 -50.371626) (xy 66.251224 -50.304355) (xy 66.223617 -50.23375) (xy 66.203671 -50.160609)
			(xy 66.191612 -50.085764) (xy 66.187577 -50.01006) (xy 65.071498 -50.01006) (xy 65.070994 -50.047966)
			(xy 65.062935 -50.123347) (xy 65.04691 -50.197445) (xy 65.0231 -50.26942) (xy 64.991774 -50.338456)
			(xy 64.953287 -50.403771) (xy 64.908076 -50.464626) (xy 64.856652 -50.52033) (xy 64.799599 -50.570252)
			(xy 64.737563 -50.613827) (xy 64.671246 -50.650562) (xy 64.6014 -50.680039) (xy 64.528817 -50.701925)
			(xy 64.454319 -50.715972) (xy 64.378749 -50.722021) (xy 64.302965 -50.720002) (xy 64.227825 -50.70994)
			(xy 64.15418 -50.691948) (xy 64.082864 -50.66623) (xy 64.014687 -50.633078) (xy 63.950419 -50.592866)
			(xy 63.89079 -50.546051) (xy 63.836474 -50.493163) (xy 63.788088 -50.434801) (xy 63.74618 -50.371626)
			(xy 63.711224 -50.304355) (xy 63.683617 -50.23375) (xy 63.663671 -50.160609) (xy 63.651612 -50.085764)
			(xy 63.647577 -50.01006) (xy 42.50107 -50.01006) (xy 42.515537 -50.020272) (xy 42.604599 -50.09273)
			(xy 42.68851 -50.171096) (xy 42.766876 -50.255007) (xy 42.839334 -50.344069) (xy 42.905545 -50.437869)
			(xy 42.9652 -50.535968) (xy 43.018022 -50.63791) (xy 43.055881 -50.72507) (xy 84.927697 -50.72507)
			(xy 84.931732 -50.649366) (xy 84.943791 -50.574521) (xy 84.963737 -50.50138) (xy 84.991344 -50.430775)
			(xy 85.0263 -50.363504) (xy 85.068208 -50.300329) (xy 85.116594 -50.241967) (xy 85.17091 -50.189079)
			(xy 85.230539 -50.142264) (xy 85.294807 -50.102052) (xy 85.362984 -50.0689) (xy 85.4343 -50.043182)
			(xy 85.507945 -50.02519) (xy 85.583085 -50.015128) (xy 85.658869 -50.013109) (xy 85.734439 -50.019158)
			(xy 85.808937 -50.033205) (xy 85.88152 -50.055091) (xy 85.951366 -50.084568) (xy 86.017683 -50.121303)
			(xy 86.079719 -50.164878) (xy 86.136772 -50.2148) (xy 86.188196 -50.270504) (xy 86.233407 -50.331359)
			(xy 86.271894 -50.396674) (xy 86.30322 -50.46571) (xy 86.32703 -50.537685) (xy 86.343055 -50.611783)
			(xy 86.351114 -50.687164) (xy 86.351618 -50.72507) (xy 86.351114 -50.762976) (xy 86.343055 -50.838357)
			(xy 86.32703 -50.912455) (xy 86.30322 -50.98443) (xy 86.271894 -51.053466) (xy 86.233407 -51.118781)
			(xy 86.188196 -51.179636) (xy 86.136772 -51.23534) (xy 86.079719 -51.285262) (xy 86.017683 -51.328837)
			(xy 85.951366 -51.365572) (xy 85.88152 -51.395049) (xy 85.808937 -51.416935) (xy 85.734439 -51.430982)
			(xy 85.658869 -51.437031) (xy 85.583085 -51.435012) (xy 85.507945 -51.42495) (xy 85.4343 -51.406958)
			(xy 85.362984 -51.38124) (xy 85.294807 -51.348088) (xy 85.230539 -51.307876) (xy 85.17091 -51.261061)
			(xy 85.116594 -51.208173) (xy 85.068208 -51.149811) (xy 85.0263 -51.086636) (xy 84.991344 -51.019365)
			(xy 84.963737 -50.94876) (xy 84.943791 -50.875619) (xy 84.931732 -50.800774) (xy 84.927697 -50.72507)
			(xy 43.055881 -50.72507) (xy 43.063764 -50.743218) (xy 43.102213 -50.851403) (xy 43.13319 -50.96196)
			(xy 43.156549 -51.074372) (xy 43.172183 -51.188117) (xy 43.180018 -51.302663) (xy 43.180508 -51.36007)
			(xy 43.180381 -51.393251) (xy 43.177842 -51.459565) (xy 43.175428 -51.492658) (xy 43.170272 -51.550942)
			(xy 43.152948 -51.666671) (xy 43.127616 -51.780914) (xy 43.094401 -51.893119) (xy 43.056327 -51.99507)
			(xy 86.197697 -51.99507) (xy 86.201732 -51.919366) (xy 86.213791 -51.844521) (xy 86.233737 -51.77138)
			(xy 86.261344 -51.700775) (xy 86.2963 -51.633504) (xy 86.338208 -51.570329) (xy 86.386594 -51.511967)
			(xy 86.44091 -51.459079) (xy 86.500539 -51.412264) (xy 86.564807 -51.372052) (xy 86.632984 -51.3389)
			(xy 86.7043 -51.313182) (xy 86.777945 -51.29519) (xy 86.853085 -51.285128) (xy 86.928869 -51.283109)
			(xy 87.004439 -51.289158) (xy 87.078937 -51.303205) (xy 87.15152 -51.325091) (xy 87.221366 -51.354568)
			(xy 87.287683 -51.391303) (xy 87.349719 -51.434878) (xy 87.406772 -51.4848) (xy 87.458196 -51.540504)
			(xy 87.503407 -51.601359) (xy 87.541894 -51.666674) (xy 87.57322 -51.73571) (xy 87.59703 -51.807685)
			(xy 87.613055 -51.881783) (xy 87.621114 -51.957164) (xy 87.621618 -51.99507) (xy 87.621114 -52.032976)
			(xy 87.613055 -52.108357) (xy 87.59703 -52.182455) (xy 87.57322 -52.25443) (xy 87.541894 -52.323466)
			(xy 87.503407 -52.388781) (xy 87.458196 -52.449636) (xy 87.406772 -52.50534) (xy 87.349719 -52.555262)
			(xy 87.287683 -52.598837) (xy 87.221366 -52.635572) (xy 87.15152 -52.665049) (xy 87.078937 -52.686935)
			(xy 87.004439 -52.700982) (xy 86.928869 -52.707031) (xy 86.853085 -52.705012) (xy 86.777945 -52.69495)
			(xy 86.7043 -52.676958) (xy 86.632984 -52.65124) (xy 86.564807 -52.618088) (xy 86.500539 -52.577876)
			(xy 86.44091 -52.531061) (xy 86.386594 -52.478173) (xy 86.338208 -52.419811) (xy 86.2963 -52.356636)
			(xy 86.261344 -52.289365) (xy 86.233737 -52.21876) (xy 86.213791 -52.145619) (xy 86.201732 -52.070774)
			(xy 86.197697 -51.99507) (xy 43.056327 -51.99507) (xy 43.053462 -52.002742) (xy 43.004999 -52.109253)
			(xy 42.949245 -52.212135) (xy 42.886471 -52.310891) (xy 42.816981 -52.405042) (xy 42.741111 -52.494132)
			(xy 42.659229 -52.577729) (xy 42.571732 -52.65543) (xy 42.500813 -52.71008) (xy 63.647577 -52.71008)
			(xy 63.651612 -52.634376) (xy 63.663671 -52.559531) (xy 63.683617 -52.48639) (xy 63.711224 -52.415785)
			(xy 63.74618 -52.348514) (xy 63.788088 -52.285339) (xy 63.836474 -52.226977) (xy 63.89079 -52.174089)
			(xy 63.950419 -52.127274) (xy 64.014687 -52.087062) (xy 64.082864 -52.05391) (xy 64.15418 -52.028192)
			(xy 64.227825 -52.0102) (xy 64.302965 -52.000138) (xy 64.378749 -51.998119) (xy 64.454319 -52.004168)
			(xy 64.528817 -52.018215) (xy 64.6014 -52.040101) (xy 64.671246 -52.069578) (xy 64.737563 -52.106313)
			(xy 64.799599 -52.149888) (xy 64.856652 -52.19981) (xy 64.908076 -52.255514) (xy 64.953287 -52.316369)
			(xy 64.991774 -52.381684) (xy 65.0231 -52.45072) (xy 65.04691 -52.522695) (xy 65.062935 -52.596793)
			(xy 65.070994 -52.672174) (xy 65.071498 -52.71008) (xy 66.187577 -52.71008) (xy 66.191612 -52.634376)
			(xy 66.203671 -52.559531) (xy 66.223617 -52.48639) (xy 66.251224 -52.415785) (xy 66.28618 -52.348514)
			(xy 66.328088 -52.285339) (xy 66.376474 -52.226977) (xy 66.43079 -52.174089) (xy 66.490419 -52.127274)
			(xy 66.554687 -52.087062) (xy 66.622864 -52.05391) (xy 66.69418 -52.028192) (xy 66.767825 -52.0102)
			(xy 66.842965 -52.000138) (xy 66.918749 -51.998119) (xy 66.994319 -52.004168) (xy 67.068817 -52.018215)
			(xy 67.1414 -52.040101) (xy 67.211246 -52.069578) (xy 67.277563 -52.106313) (xy 67.339599 -52.149888)
			(xy 67.396652 -52.19981) (xy 67.448076 -52.255514) (xy 67.493287 -52.316369) (xy 67.531774 -52.381684)
			(xy 67.5631 -52.45072) (xy 67.58691 -52.522695) (xy 67.602935 -52.596793) (xy 67.610994 -52.672174)
			(xy 67.611498 -52.71008) (xy 68.727577 -52.71008) (xy 68.731612 -52.634376) (xy 68.743671 -52.559531)
			(xy 68.763617 -52.48639) (xy 68.791224 -52.415785) (xy 68.82618 -52.348514) (xy 68.868088 -52.285339)
			(xy 68.916474 -52.226977) (xy 68.97079 -52.174089) (xy 69.030419 -52.127274) (xy 69.094687 -52.087062)
			(xy 69.162864 -52.05391) (xy 69.23418 -52.028192) (xy 69.307825 -52.0102) (xy 69.382965 -52.000138)
			(xy 69.458749 -51.998119) (xy 69.534319 -52.004168) (xy 69.608817 -52.018215) (xy 69.6814 -52.040101)
			(xy 69.751246 -52.069578) (xy 69.817563 -52.106313) (xy 69.879599 -52.149888) (xy 69.936652 -52.19981)
			(xy 69.988076 -52.255514) (xy 70.033287 -52.316369) (xy 70.071774 -52.381684) (xy 70.1031 -52.45072)
			(xy 70.12691 -52.522695) (xy 70.142935 -52.596793) (xy 70.150994 -52.672174) (xy 70.151498 -52.71008)
			(xy 71.267577 -52.71008) (xy 71.271612 -52.634376) (xy 71.283671 -52.559531) (xy 71.303617 -52.48639)
			(xy 71.331224 -52.415785) (xy 71.36618 -52.348514) (xy 71.408088 -52.285339) (xy 71.456474 -52.226977)
			(xy 71.51079 -52.174089) (xy 71.570419 -52.127274) (xy 71.634687 -52.087062) (xy 71.702864 -52.05391)
			(xy 71.77418 -52.028192) (xy 71.847825 -52.0102) (xy 71.922965 -52.000138) (xy 71.998749 -51.998119)
			(xy 72.074319 -52.004168) (xy 72.148817 -52.018215) (xy 72.2214 -52.040101) (xy 72.291246 -52.069578)
			(xy 72.357563 -52.106313) (xy 72.419599 -52.149888) (xy 72.476652 -52.19981) (xy 72.528076 -52.255514)
			(xy 72.573287 -52.316369) (xy 72.611774 -52.381684) (xy 72.6431 -52.45072) (xy 72.66691 -52.522695)
			(xy 72.682935 -52.596793) (xy 72.690994 -52.672174) (xy 72.691498 -52.71008) (xy 73.807577 -52.71008)
			(xy 73.811612 -52.634376) (xy 73.823671 -52.559531) (xy 73.843617 -52.48639) (xy 73.871224 -52.415785)
			(xy 73.90618 -52.348514) (xy 73.948088 -52.285339) (xy 73.996474 -52.226977) (xy 74.05079 -52.174089)
			(xy 74.110419 -52.127274) (xy 74.174687 -52.087062) (xy 74.242864 -52.05391) (xy 74.31418 -52.028192)
			(xy 74.387825 -52.0102) (xy 74.462965 -52.000138) (xy 74.538749 -51.998119) (xy 74.614319 -52.004168)
			(xy 74.688817 -52.018215) (xy 74.7614 -52.040101) (xy 74.831246 -52.069578) (xy 74.897563 -52.106313)
			(xy 74.959599 -52.149888) (xy 75.016652 -52.19981) (xy 75.068076 -52.255514) (xy 75.113287 -52.316369)
			(xy 75.151774 -52.381684) (xy 75.1831 -52.45072) (xy 75.20691 -52.522695) (xy 75.222935 -52.596793)
			(xy 75.230994 -52.672174) (xy 75.231498 -52.71008) (xy 76.347577 -52.71008) (xy 76.351612 -52.634376)
			(xy 76.363671 -52.559531) (xy 76.383617 -52.48639) (xy 76.411224 -52.415785) (xy 76.44618 -52.348514)
			(xy 76.488088 -52.285339) (xy 76.536474 -52.226977) (xy 76.59079 -52.174089) (xy 76.650419 -52.127274)
			(xy 76.714687 -52.087062) (xy 76.782864 -52.05391) (xy 76.85418 -52.028192) (xy 76.927825 -52.0102)
			(xy 77.002965 -52.000138) (xy 77.078749 -51.998119) (xy 77.154319 -52.004168) (xy 77.228817 -52.018215)
			(xy 77.3014 -52.040101) (xy 77.371246 -52.069578) (xy 77.437563 -52.106313) (xy 77.499599 -52.149888)
			(xy 77.556652 -52.19981) (xy 77.608076 -52.255514) (xy 77.653287 -52.316369) (xy 77.691774 -52.381684)
			(xy 77.7231 -52.45072) (xy 77.74691 -52.522695) (xy 77.762935 -52.596793) (xy 77.770994 -52.672174)
			(xy 77.771498 -52.71008) (xy 78.887577 -52.71008) (xy 78.891612 -52.634376) (xy 78.903671 -52.559531)
			(xy 78.923617 -52.48639) (xy 78.951224 -52.415785) (xy 78.98618 -52.348514) (xy 79.028088 -52.285339)
			(xy 79.076474 -52.226977) (xy 79.13079 -52.174089) (xy 79.190419 -52.127274) (xy 79.254687 -52.087062)
			(xy 79.322864 -52.05391) (xy 79.39418 -52.028192) (xy 79.467825 -52.0102) (xy 79.542965 -52.000138)
			(xy 79.618749 -51.998119) (xy 79.694319 -52.004168) (xy 79.768817 -52.018215) (xy 79.8414 -52.040101)
			(xy 79.911246 -52.069578) (xy 79.977563 -52.106313) (xy 80.039599 -52.149888) (xy 80.096652 -52.19981)
			(xy 80.148076 -52.255514) (xy 80.193287 -52.316369) (xy 80.231774 -52.381684) (xy 80.2631 -52.45072)
			(xy 80.28691 -52.522695) (xy 80.302935 -52.596793) (xy 80.310994 -52.672174) (xy 80.311498 -52.71008)
			(xy 81.427577 -52.71008) (xy 81.431612 -52.634376) (xy 81.443671 -52.559531) (xy 81.463617 -52.48639)
			(xy 81.491224 -52.415785) (xy 81.52618 -52.348514) (xy 81.568088 -52.285339) (xy 81.616474 -52.226977)
			(xy 81.67079 -52.174089) (xy 81.730419 -52.127274) (xy 81.794687 -52.087062) (xy 81.862864 -52.05391)
			(xy 81.93418 -52.028192) (xy 82.007825 -52.0102) (xy 82.082965 -52.000138) (xy 82.158749 -51.998119)
			(xy 82.234319 -52.004168) (xy 82.308817 -52.018215) (xy 82.3814 -52.040101) (xy 82.451246 -52.069578)
			(xy 82.517563 -52.106313) (xy 82.579599 -52.149888) (xy 82.636652 -52.19981) (xy 82.688076 -52.255514)
			(xy 82.733287 -52.316369) (xy 82.771774 -52.381684) (xy 82.8031 -52.45072) (xy 82.82691 -52.522695)
			(xy 82.842935 -52.596793) (xy 82.850994 -52.672174) (xy 82.851498 -52.71008) (xy 82.850994 -52.747986)
			(xy 82.842935 -52.823367) (xy 82.82691 -52.897465) (xy 82.8031 -52.96944) (xy 82.771774 -53.038476)
			(xy 82.733287 -53.103791) (xy 82.688076 -53.164646) (xy 82.636652 -53.22035) (xy 82.585544 -53.26507)
			(xy 84.927697 -53.26507) (xy 84.931732 -53.189366) (xy 84.943791 -53.114521) (xy 84.963737 -53.04138)
			(xy 84.991344 -52.970775) (xy 85.0263 -52.903504) (xy 85.068208 -52.840329) (xy 85.116594 -52.781967)
			(xy 85.17091 -52.729079) (xy 85.230539 -52.682264) (xy 85.294807 -52.642052) (xy 85.362984 -52.6089)
			(xy 85.4343 -52.583182) (xy 85.507945 -52.56519) (xy 85.583085 -52.555128) (xy 85.658869 -52.553109)
			(xy 85.734439 -52.559158) (xy 85.808937 -52.573205) (xy 85.88152 -52.595091) (xy 85.951366 -52.624568)
			(xy 86.017683 -52.661303) (xy 86.079719 -52.704878) (xy 86.136772 -52.7548) (xy 86.188196 -52.810504)
			(xy 86.233407 -52.871359) (xy 86.271894 -52.936674) (xy 86.30322 -53.00571) (xy 86.32703 -53.077685)
			(xy 86.343055 -53.151783) (xy 86.351114 -53.227164) (xy 86.351618 -53.26507) (xy 86.351114 -53.302976)
			(xy 86.343055 -53.378357) (xy 86.32703 -53.452455) (xy 86.30322 -53.52443) (xy 86.271894 -53.593466)
			(xy 86.233407 -53.658781) (xy 86.188196 -53.719636) (xy 86.136772 -53.77534) (xy 86.079719 -53.825262)
			(xy 86.017683 -53.868837) (xy 85.951366 -53.905572) (xy 85.88152 -53.935049) (xy 85.808937 -53.956935)
			(xy 85.734439 -53.970982) (xy 85.658869 -53.977031) (xy 85.583085 -53.975012) (xy 85.507945 -53.96495)
			(xy 85.4343 -53.946958) (xy 85.362984 -53.92124) (xy 85.294807 -53.888088) (xy 85.230539 -53.847876)
			(xy 85.17091 -53.801061) (xy 85.116594 -53.748173) (xy 85.068208 -53.689811) (xy 85.0263 -53.626636)
			(xy 84.991344 -53.559365) (xy 84.963737 -53.48876) (xy 84.943791 -53.415619) (xy 84.931732 -53.340774)
			(xy 84.927697 -53.26507) (xy 82.585544 -53.26507) (xy 82.579599 -53.270272) (xy 82.517563 -53.313847)
			(xy 82.451246 -53.350582) (xy 82.3814 -53.380059) (xy 82.308817 -53.401945) (xy 82.234319 -53.415992)
			(xy 82.158749 -53.422041) (xy 82.082965 -53.420022) (xy 82.007825 -53.40996) (xy 81.93418 -53.391968)
			(xy 81.862864 -53.36625) (xy 81.794687 -53.333098) (xy 81.730419 -53.292886) (xy 81.67079 -53.246071)
			(xy 81.616474 -53.193183) (xy 81.568088 -53.134821) (xy 81.52618 -53.071646) (xy 81.491224 -53.004375)
			(xy 81.463617 -52.93377) (xy 81.443671 -52.860629) (xy 81.431612 -52.785784) (xy 81.427577 -52.71008)
			(xy 80.311498 -52.71008) (xy 80.310994 -52.747986) (xy 80.302935 -52.823367) (xy 80.28691 -52.897465)
			(xy 80.2631 -52.96944) (xy 80.231774 -53.038476) (xy 80.193287 -53.103791) (xy 80.148076 -53.164646)
			(xy 80.096652 -53.22035) (xy 80.039599 -53.270272) (xy 79.977563 -53.313847) (xy 79.911246 -53.350582)
			(xy 79.8414 -53.380059) (xy 79.768817 -53.401945) (xy 79.694319 -53.415992) (xy 79.618749 -53.422041)
			(xy 79.542965 -53.420022) (xy 79.467825 -53.40996) (xy 79.39418 -53.391968) (xy 79.322864 -53.36625)
			(xy 79.254687 -53.333098) (xy 79.190419 -53.292886) (xy 79.13079 -53.246071) (xy 79.076474 -53.193183)
			(xy 79.028088 -53.134821) (xy 78.98618 -53.071646) (xy 78.951224 -53.004375) (xy 78.923617 -52.93377)
			(xy 78.903671 -52.860629) (xy 78.891612 -52.785784) (xy 78.887577 -52.71008) (xy 77.771498 -52.71008)
			(xy 77.770994 -52.747986) (xy 77.762935 -52.823367) (xy 77.74691 -52.897465) (xy 77.7231 -52.96944)
			(xy 77.691774 -53.038476) (xy 77.653287 -53.103791) (xy 77.608076 -53.164646) (xy 77.556652 -53.22035)
			(xy 77.499599 -53.270272) (xy 77.437563 -53.313847) (xy 77.371246 -53.350582) (xy 77.3014 -53.380059)
			(xy 77.228817 -53.401945) (xy 77.154319 -53.415992) (xy 77.078749 -53.422041) (xy 77.002965 -53.420022)
			(xy 76.927825 -53.40996) (xy 76.85418 -53.391968) (xy 76.782864 -53.36625) (xy 76.714687 -53.333098)
			(xy 76.650419 -53.292886) (xy 76.59079 -53.246071) (xy 76.536474 -53.193183) (xy 76.488088 -53.134821)
			(xy 76.44618 -53.071646) (xy 76.411224 -53.004375) (xy 76.383617 -52.93377) (xy 76.363671 -52.860629)
			(xy 76.351612 -52.785784) (xy 76.347577 -52.71008) (xy 75.231498 -52.71008) (xy 75.230994 -52.747986)
			(xy 75.222935 -52.823367) (xy 75.20691 -52.897465) (xy 75.1831 -52.96944) (xy 75.151774 -53.038476)
			(xy 75.113287 -53.103791) (xy 75.068076 -53.164646) (xy 75.016652 -53.22035) (xy 74.959599 -53.270272)
			(xy 74.897563 -53.313847) (xy 74.831246 -53.350582) (xy 74.7614 -53.380059) (xy 74.688817 -53.401945)
			(xy 74.614319 -53.415992) (xy 74.538749 -53.422041) (xy 74.462965 -53.420022) (xy 74.387825 -53.40996)
			(xy 74.31418 -53.391968) (xy 74.242864 -53.36625) (xy 74.174687 -53.333098) (xy 74.110419 -53.292886)
			(xy 74.05079 -53.246071) (xy 73.996474 -53.193183) (xy 73.948088 -53.134821) (xy 73.90618 -53.071646)
			(xy 73.871224 -53.004375) (xy 73.843617 -52.93377) (xy 73.823671 -52.860629) (xy 73.811612 -52.785784)
			(xy 73.807577 -52.71008) (xy 72.691498 -52.71008) (xy 72.690994 -52.747986) (xy 72.682935 -52.823367)
			(xy 72.66691 -52.897465) (xy 72.6431 -52.96944) (xy 72.611774 -53.038476) (xy 72.573287 -53.103791)
			(xy 72.528076 -53.164646) (xy 72.476652 -53.22035) (xy 72.419599 -53.270272) (xy 72.357563 -53.313847)
			(xy 72.291246 -53.350582) (xy 72.2214 -53.380059) (xy 72.148817 -53.401945) (xy 72.074319 -53.415992)
			(xy 71.998749 -53.422041) (xy 71.922965 -53.420022) (xy 71.847825 -53.40996) (xy 71.77418 -53.391968)
			(xy 71.702864 -53.36625) (xy 71.634687 -53.333098) (xy 71.570419 -53.292886) (xy 71.51079 -53.246071)
			(xy 71.456474 -53.193183) (xy 71.408088 -53.134821) (xy 71.36618 -53.071646) (xy 71.331224 -53.004375)
			(xy 71.303617 -52.93377) (xy 71.283671 -52.860629) (xy 71.271612 -52.785784) (xy 71.267577 -52.71008)
			(xy 70.151498 -52.71008) (xy 70.150994 -52.747986) (xy 70.142935 -52.823367) (xy 70.12691 -52.897465)
			(xy 70.1031 -52.96944) (xy 70.071774 -53.038476) (xy 70.033287 -53.103791) (xy 69.988076 -53.164646)
			(xy 69.936652 -53.22035) (xy 69.879599 -53.270272) (xy 69.817563 -53.313847) (xy 69.751246 -53.350582)
			(xy 69.6814 -53.380059) (xy 69.608817 -53.401945) (xy 69.534319 -53.415992) (xy 69.458749 -53.422041)
			(xy 69.382965 -53.420022) (xy 69.307825 -53.40996) (xy 69.23418 -53.391968) (xy 69.162864 -53.36625)
			(xy 69.094687 -53.333098) (xy 69.030419 -53.292886) (xy 68.97079 -53.246071) (xy 68.916474 -53.193183)
			(xy 68.868088 -53.134821) (xy 68.82618 -53.071646) (xy 68.791224 -53.004375) (xy 68.763617 -52.93377)
			(xy 68.743671 -52.860629) (xy 68.731612 -52.785784) (xy 68.727577 -52.71008) (xy 67.611498 -52.71008)
			(xy 67.610994 -52.747986) (xy 67.602935 -52.823367) (xy 67.58691 -52.897465) (xy 67.5631 -52.96944)
			(xy 67.531774 -53.038476) (xy 67.493287 -53.103791) (xy 67.448076 -53.164646) (xy 67.396652 -53.22035)
			(xy 67.339599 -53.270272) (xy 67.277563 -53.313847) (xy 67.211246 -53.350582) (xy 67.1414 -53.380059)
			(xy 67.068817 -53.401945) (xy 66.994319 -53.415992) (xy 66.918749 -53.422041) (xy 66.842965 -53.420022)
			(xy 66.767825 -53.40996) (xy 66.69418 -53.391968) (xy 66.622864 -53.36625) (xy 66.554687 -53.333098)
			(xy 66.490419 -53.292886) (xy 66.43079 -53.246071) (xy 66.376474 -53.193183) (xy 66.328088 -53.134821)
			(xy 66.28618 -53.071646) (xy 66.251224 -53.004375) (xy 66.223617 -52.93377) (xy 66.203671 -52.860629)
			(xy 66.191612 -52.785784) (xy 66.187577 -52.71008) (xy 65.071498 -52.71008) (xy 65.070994 -52.747986)
			(xy 65.062935 -52.823367) (xy 65.04691 -52.897465) (xy 65.0231 -52.96944) (xy 64.991774 -53.038476)
			(xy 64.953287 -53.103791) (xy 64.908076 -53.164646) (xy 64.856652 -53.22035) (xy 64.799599 -53.270272)
			(xy 64.737563 -53.313847) (xy 64.671246 -53.350582) (xy 64.6014 -53.380059) (xy 64.528817 -53.401945)
			(xy 64.454319 -53.415992) (xy 64.378749 -53.422041) (xy 64.302965 -53.420022) (xy 64.227825 -53.40996)
			(xy 64.15418 -53.391968) (xy 64.082864 -53.36625) (xy 64.014687 -53.333098) (xy 63.950419 -53.292886)
			(xy 63.89079 -53.246071) (xy 63.836474 -53.193183) (xy 63.788088 -53.134821) (xy 63.74618 -53.071646)
			(xy 63.711224 -53.004375) (xy 63.683617 -52.93377) (xy 63.663671 -52.860629) (xy 63.651612 -52.785784)
			(xy 63.647577 -52.71008) (xy 42.500813 -52.71008) (xy 42.479042 -52.726857) (xy 42.381609 -52.791665)
			(xy 42.279905 -52.84954) (xy 42.174422 -52.900202) (xy 42.065671 -52.943404) (xy 41.954179 -52.978939)
			(xy 41.840485 -53.006634) (xy 41.725141 -53.026354) (xy 41.608704 -53.038005) (xy 41.491739 -53.04153)
			(xy 41.374812 -53.036912) (xy 41.258489 -53.024173) (xy 41.143334 -53.003375) (xy 41.029905 -52.974618)
			(xy 40.91875 -52.938042) (xy 40.810407 -52.893825) (xy 40.705403 -52.842179) (xy 40.604244 -52.783356)
			(xy 40.507421 -52.71764) (xy 40.415403 -52.645349) (xy 40.328636 -52.566834) (xy 40.247539 -52.482474)
			(xy 40.172506 -52.392679) (xy 40.103899 -52.297883) (xy 40.042051 -52.198544) (xy 39.987262 -52.095145)
			(xy 39.939796 -51.988186) (xy 39.899884 -51.878185) (xy 39.86772 -51.765674) (xy 39.843457 -51.651199)
			(xy 39.827215 -51.535313) (xy 39.819072 -51.418579) (xy 39.818564 -51.36007) (xy 29.170884 -51.36007)
			(xy 29.170884 -55.433484) (xy 29.519874 -55.433484) (xy 29.519874 -55.346584) (xy 29.527892 -55.260055)
			(xy 29.54386 -55.174635) (xy 29.567641 -55.091053) (xy 29.599033 -55.010021) (xy 29.637767 -54.932232)
			(xy 29.683514 -54.858348) (xy 29.735883 -54.789001) (xy 29.794427 -54.724781) (xy 29.858647 -54.666237)
			(xy 29.927994 -54.613868) (xy 30.001878 -54.568121) (xy 30.079667 -54.529387) (xy 30.160699 -54.497995)
			(xy 30.244281 -54.474214) (xy 30.329701 -54.458246) (xy 30.41623 -54.450228) (xy 30.50313 -54.450228)
			(xy 30.589659 -54.458246) (xy 30.675079 -54.474214) (xy 30.758661 -54.497995) (xy 30.839693 -54.529387)
			(xy 30.917482 -54.568121) (xy 30.991366 -54.613868) (xy 31.060713 -54.666237) (xy 31.124933 -54.724781)
			(xy 31.183477 -54.789001) (xy 31.235846 -54.858348) (xy 31.281593 -54.932232) (xy 31.320327 -55.010021)
			(xy 31.351719 -55.091053) (xy 31.3755 -55.174635) (xy 31.391468 -55.260055) (xy 31.399486 -55.346584)
			(xy 31.399988 -55.390034) (xy 31.399486 -55.433484) (xy 34.599874 -55.433484) (xy 34.599874 -55.346584)
			(xy 34.607892 -55.260055) (xy 34.62386 -55.174635) (xy 34.647641 -55.091053) (xy 34.679033 -55.010021)
			(xy 34.717767 -54.932232) (xy 34.763514 -54.858348) (xy 34.815883 -54.789001) (xy 34.874427 -54.724781)
			(xy 34.938647 -54.666237) (xy 35.007994 -54.613868) (xy 35.081878 -54.568121) (xy 35.159667 -54.529387)
			(xy 35.240699 -54.497995) (xy 35.324281 -54.474214) (xy 35.409701 -54.458246) (xy 35.49623 -54.450228)
			(xy 35.58313 -54.450228) (xy 35.669659 -54.458246) (xy 35.755079 -54.474214) (xy 35.838661 -54.497995)
			(xy 35.919693 -54.529387) (xy 35.997482 -54.568121) (xy 36.071366 -54.613868) (xy 36.140713 -54.666237)
			(xy 36.204933 -54.724781) (xy 36.263477 -54.789001) (xy 36.315846 -54.858348) (xy 36.361593 -54.932232)
			(xy 36.400327 -55.010021) (xy 36.431719 -55.091053) (xy 36.4555 -55.174635) (xy 36.471468 -55.260055)
			(xy 36.479486 -55.346584) (xy 36.479988 -55.390034) (xy 36.479486 -55.433484) (xy 36.471468 -55.520013)
			(xy 36.4555 -55.605433) (xy 36.431719 -55.689015) (xy 36.400327 -55.770047) (xy 36.361593 -55.847836)
			(xy 36.315846 -55.92172) (xy 36.263477 -55.991067) (xy 36.204933 -56.055287) (xy 36.140713 -56.113831)
			(xy 36.071366 -56.1662) (xy 35.997482 -56.211947) (xy 35.919693 -56.250681) (xy 35.838661 -56.282073)
			(xy 35.766073 -56.302726) (xy 63.833865 -56.302726) (xy 63.837749 -56.24837) (xy 63.849329 -56.19512)
			(xy 63.86837 -56.144059) (xy 63.894484 -56.096229) (xy 63.927139 -56.052602) (xy 63.965671 -56.014066)
			(xy 64.009295 -55.981406) (xy 64.057122 -55.955287) (xy 64.108181 -55.936241) (xy 64.16143 -55.924655)
			(xy 64.215786 -55.920765) (xy 64.270142 -55.924651) (xy 64.323392 -55.936233) (xy 64.374452 -55.955275)
			(xy 64.422281 -55.981391) (xy 64.444372 -55.997348) (xy 64.463384 -56.010944) (xy 64.505267 -56.031676)
			(xy 64.550235 -56.044402) (xy 64.596772 -56.048692) (xy 64.643309 -56.044402) (xy 64.688277 -56.031676)
			(xy 64.73016 -56.010944) (xy 64.749172 -55.997348) (xy 64.771302 -55.981445) (xy 64.819127 -55.955326)
			(xy 64.870182 -55.936279) (xy 64.923429 -55.924692) (xy 64.977782 -55.920802) (xy 65.032136 -55.924687)
			(xy 65.085384 -55.936269) (xy 65.136441 -55.955311) (xy 65.184268 -55.981426) (xy 65.227892 -56.014082)
			(xy 65.266424 -56.052615) (xy 65.299079 -56.096239) (xy 65.325193 -56.144067) (xy 65.344234 -56.195125)
			(xy 65.355814 -56.248372) (xy 65.359698 -56.302726) (xy 66.063458 -56.302726) (xy 66.067342 -56.248368)
			(xy 66.078923 -56.195116) (xy 66.097964 -56.144055) (xy 66.124079 -56.096223) (xy 66.156736 -56.052595)
			(xy 66.195269 -56.014058) (xy 66.238894 -55.981398) (xy 66.286724 -55.955278) (xy 66.337784 -55.936232)
			(xy 66.391035 -55.924647) (xy 66.445393 -55.920758) (xy 66.49975 -55.924645) (xy 66.553002 -55.936228)
			(xy 66.604062 -55.955272) (xy 66.651893 -55.98139) (xy 66.673984 -55.997348) (xy 66.692996 -56.010944)
			(xy 66.734879 -56.031676) (xy 66.779847 -56.044402) (xy 66.826384 -56.048692) (xy 66.872921 -56.044402)
			(xy 66.917889 -56.031676) (xy 66.959772 -56.010944) (xy 66.978784 -55.997348) (xy 67.000914 -55.981446)
			(xy 67.048738 -55.955328) (xy 67.099792 -55.936283) (xy 67.153037 -55.924698) (xy 67.207389 -55.920809)
			(xy 67.261741 -55.924695) (xy 67.314987 -55.936277) (xy 67.366043 -55.95532) (xy 67.413868 -55.981434)
			(xy 67.45749 -56.01409) (xy 67.49602 -56.052622) (xy 67.528674 -56.096245) (xy 67.554787 -56.144072)
			(xy 67.573827 -56.195128) (xy 67.585407 -56.248374) (xy 67.589291 -56.302726) (xy 67.5854 -56.357078)
			(xy 67.573812 -56.410323) (xy 67.554765 -56.461376) (xy 67.528645 -56.509199) (xy 67.495986 -56.552818)
			(xy 67.45745 -56.591344) (xy 67.413824 -56.623994) (xy 67.365995 -56.650102) (xy 67.314937 -56.669138)
			(xy 67.261689 -56.680712) (xy 67.207336 -56.684591) (xy 67.152985 -56.680694) (xy 67.099741 -56.669102)
			(xy 67.04869 -56.65005) (xy 67.000869 -56.623925) (xy 66.978784 -56.607964) (xy 66.959772 -56.594368)
			(xy 66.917889 -56.573636) (xy 66.872921 -56.56091) (xy 66.826384 -56.55662) (xy 66.779847 -56.56091)
			(xy 66.734879 -56.573636) (xy 66.692996 -56.594368) (xy 66.673984 -56.607964) (xy 66.651937 -56.623982)
			(xy 66.60411 -56.650106) (xy 66.553052 -56.669157) (xy 66.499803 -56.680748) (xy 66.445445 -56.684642)
			(xy 66.391087 -56.680761) (xy 66.337835 -56.669183) (xy 66.286772 -56.650143) (xy 66.238939 -56.624031)
			(xy 66.195309 -56.591377) (xy 66.15677 -56.552845) (xy 66.124108 -56.509222) (xy 66.097986 -56.461393)
			(xy 66.078938 -56.410334) (xy 66.067349 -56.357084) (xy 66.063458 -56.302726) (xy 65.359698 -56.302726)
			(xy 65.355807 -56.35708) (xy 65.344219 -56.410326) (xy 65.325171 -56.461381) (xy 65.29905 -56.509205)
			(xy 65.266389 -56.552825) (xy 65.227852 -56.591352) (xy 65.184224 -56.624003) (xy 65.136393 -56.650111)
			(xy 65.085333 -56.669146) (xy 65.032084 -56.68072) (xy 64.97773 -56.684598) (xy 64.923377 -56.6807)
			(xy 64.870132 -56.669106) (xy 64.819079 -56.650052) (xy 64.771258 -56.623926) (xy 64.749172 -56.607964)
			(xy 64.73016 -56.594368) (xy 64.688277 -56.573636) (xy 64.643309 -56.56091) (xy 64.596772 -56.55662)
			(xy 64.550235 -56.56091) (xy 64.505267 -56.573636) (xy 64.463384 -56.594368) (xy 64.444372 -56.607964)
			(xy 64.422326 -56.623981) (xy 64.3745 -56.650103) (xy 64.323443 -56.669152) (xy 64.270194 -56.680742)
			(xy 64.215839 -56.684635) (xy 64.161482 -56.680753) (xy 64.108231 -56.669174) (xy 64.057171 -56.650135)
			(xy 64.009339 -56.624023) (xy 63.965711 -56.591369) (xy 63.927174 -56.552838) (xy 63.894513 -56.509216)
			(xy 63.868392 -56.461389) (xy 63.849344 -56.410331) (xy 63.837756 -56.357082) (xy 63.833865 -56.302726)
			(xy 35.766073 -56.302726) (xy 35.755079 -56.305854) (xy 35.669659 -56.321822) (xy 35.58313 -56.32984)
			(xy 35.49623 -56.32984) (xy 35.409701 -56.321822) (xy 35.324281 -56.305854) (xy 35.240699 -56.282073)
			(xy 35.159667 -56.250681) (xy 35.081878 -56.211947) (xy 35.007994 -56.1662) (xy 34.938647 -56.113831)
			(xy 34.874427 -56.055287) (xy 34.815883 -55.991067) (xy 34.763514 -55.92172) (xy 34.717767 -55.847836)
			(xy 34.679033 -55.770047) (xy 34.647641 -55.689015) (xy 34.62386 -55.605433) (xy 34.607892 -55.520013)
			(xy 34.599874 -55.433484) (xy 31.399486 -55.433484) (xy 31.391468 -55.520013) (xy 31.3755 -55.605433)
			(xy 31.351719 -55.689015) (xy 31.320327 -55.770047) (xy 31.281593 -55.847836) (xy 31.235846 -55.92172)
			(xy 31.183477 -55.991067) (xy 31.124933 -56.055287) (xy 31.060713 -56.113831) (xy 30.991366 -56.1662)
			(xy 30.917482 -56.211947) (xy 30.839693 -56.250681) (xy 30.758661 -56.282073) (xy 30.675079 -56.305854)
			(xy 30.589659 -56.321822) (xy 30.50313 -56.32984) (xy 30.41623 -56.32984) (xy 30.329701 -56.321822)
			(xy 30.244281 -56.305854) (xy 30.160699 -56.282073) (xy 30.079667 -56.250681) (xy 30.001878 -56.211947)
			(xy 29.927994 -56.1662) (xy 29.858647 -56.113831) (xy 29.794427 -56.055287) (xy 29.735883 -55.991067)
			(xy 29.683514 -55.92172) (xy 29.637767 -55.847836) (xy 29.599033 -55.770047) (xy 29.567641 -55.689015)
			(xy 29.54386 -55.605433) (xy 29.527892 -55.520013) (xy 29.519874 -55.433484) (xy 29.170884 -55.433484)
			(xy 29.170884 -57.973484) (xy 29.519874 -57.973484) (xy 29.519874 -57.886584) (xy 29.527892 -57.800055)
			(xy 29.54386 -57.714635) (xy 29.567641 -57.631053) (xy 29.599033 -57.550021) (xy 29.637767 -57.472232)
			(xy 29.683514 -57.398348) (xy 29.735883 -57.329001) (xy 29.794427 -57.264781) (xy 29.858647 -57.206237)
			(xy 29.927994 -57.153868) (xy 30.001878 -57.108121) (xy 30.079667 -57.069387) (xy 30.160699 -57.037995)
			(xy 30.244281 -57.014214) (xy 30.329701 -56.998246) (xy 30.41623 -56.990228) (xy 30.50313 -56.990228)
			(xy 30.589659 -56.998246) (xy 30.675079 -57.014214) (xy 30.758661 -57.037995) (xy 30.839693 -57.069387)
			(xy 30.917482 -57.108121) (xy 30.991366 -57.153868) (xy 31.060713 -57.206237) (xy 31.124933 -57.264781)
			(xy 31.183477 -57.329001) (xy 31.235846 -57.398348) (xy 31.281593 -57.472232) (xy 31.320327 -57.550021)
			(xy 31.351719 -57.631053) (xy 31.3755 -57.714635) (xy 31.391468 -57.800055) (xy 31.399486 -57.886584)
			(xy 31.399988 -57.930034) (xy 31.399486 -57.973484) (xy 34.599874 -57.973484) (xy 34.599874 -57.886584)
			(xy 34.607892 -57.800055) (xy 34.62386 -57.714635) (xy 34.647641 -57.631053) (xy 34.679033 -57.550021)
			(xy 34.717767 -57.472232) (xy 34.763514 -57.398348) (xy 34.815883 -57.329001) (xy 34.874427 -57.264781)
			(xy 34.938647 -57.206237) (xy 35.007994 -57.153868) (xy 35.081878 -57.108121) (xy 35.159667 -57.069387)
			(xy 35.240699 -57.037995) (xy 35.324281 -57.014214) (xy 35.409701 -56.998246) (xy 35.49623 -56.990228)
			(xy 35.58313 -56.990228) (xy 35.669659 -56.998246) (xy 35.755079 -57.014214) (xy 35.838661 -57.037995)
			(xy 35.919693 -57.069387) (xy 35.997482 -57.108121) (xy 36.071366 -57.153868) (xy 36.140713 -57.206237)
			(xy 36.204933 -57.264781) (xy 36.263477 -57.329001) (xy 36.315846 -57.398348) (xy 36.334598 -57.428634)
			(xy 80.91727 -57.428634) (xy 80.91727 -57.368698) (xy 80.925093 -57.309276) (xy 80.940606 -57.251383)
			(xy 80.963542 -57.19601) (xy 80.993509 -57.144104) (xy 81.029996 -57.096554) (xy 81.072376 -57.054174)
			(xy 81.119926 -57.017687) (xy 81.171832 -56.98772) (xy 81.227205 -56.964784) (xy 81.285098 -56.949271)
			(xy 81.34452 -56.941448) (xy 81.404456 -56.941448) (xy 81.463878 -56.949271) (xy 81.521771 -56.964784)
			(xy 81.577144 -56.98772) (xy 81.62905 -57.017687) (xy 81.6766 -57.054174) (xy 81.71898 -57.096554)
			(xy 81.755467 -57.144104) (xy 81.785434 -57.19601) (xy 81.80837 -57.251383) (xy 81.823883 -57.309276)
			(xy 81.831706 -57.368698) (xy 81.832196 -57.398666) (xy 81.831706 -57.428634) (xy 81.823883 -57.488056)
			(xy 81.80837 -57.545949) (xy 81.785434 -57.601322) (xy 81.755467 -57.653228) (xy 81.71898 -57.700778)
			(xy 81.6766 -57.743158) (xy 81.62905 -57.779645) (xy 81.577144 -57.809612) (xy 81.521771 -57.832548)
			(xy 81.463878 -57.848061) (xy 81.404456 -57.855884) (xy 81.34452 -57.855884) (xy 81.285098 -57.848061)
			(xy 81.227205 -57.832548) (xy 81.171832 -57.809612) (xy 81.119926 -57.779645) (xy 81.072376 -57.743158)
			(xy 81.029996 -57.700778) (xy 80.993509 -57.653228) (xy 80.963542 -57.601322) (xy 80.940606 -57.545949)
			(xy 80.925093 -57.488056) (xy 80.91727 -57.428634) (xy 36.334598 -57.428634) (xy 36.361593 -57.472232)
			(xy 36.400327 -57.550021) (xy 36.431719 -57.631053) (xy 36.4555 -57.714635) (xy 36.471468 -57.800055)
			(xy 36.479486 -57.886584) (xy 36.479988 -57.930034) (xy 36.479486 -57.973484) (xy 36.471468 -58.060013)
			(xy 36.4555 -58.145433) (xy 36.431719 -58.229015) (xy 36.400327 -58.310047) (xy 36.361593 -58.387836)
			(xy 36.315846 -58.46172) (xy 36.263477 -58.531067) (xy 36.204933 -58.595287) (xy 36.140713 -58.653831)
			(xy 36.071366 -58.7062) (xy 35.997482 -58.751947) (xy 35.919693 -58.790681) (xy 35.838661 -58.822073)
			(xy 35.755079 -58.845854) (xy 35.669659 -58.861822) (xy 35.58313 -58.86984) (xy 35.49623 -58.86984)
			(xy 35.409701 -58.861822) (xy 35.324281 -58.845854) (xy 35.240699 -58.822073) (xy 35.159667 -58.790681)
			(xy 35.081878 -58.751947) (xy 35.007994 -58.7062) (xy 34.938647 -58.653831) (xy 34.874427 -58.595287)
			(xy 34.815883 -58.531067) (xy 34.763514 -58.46172) (xy 34.717767 -58.387836) (xy 34.679033 -58.310047)
			(xy 34.647641 -58.229015) (xy 34.62386 -58.145433) (xy 34.607892 -58.060013) (xy 34.599874 -57.973484)
			(xy 31.399486 -57.973484) (xy 31.391468 -58.060013) (xy 31.3755 -58.145433) (xy 31.351719 -58.229015)
			(xy 31.320327 -58.310047) (xy 31.281593 -58.387836) (xy 31.235846 -58.46172) (xy 31.183477 -58.531067)
			(xy 31.124933 -58.595287) (xy 31.060713 -58.653831) (xy 30.991366 -58.7062) (xy 30.917482 -58.751947)
			(xy 30.839693 -58.790681) (xy 30.758661 -58.822073) (xy 30.675079 -58.845854) (xy 30.589659 -58.861822)
			(xy 30.50313 -58.86984) (xy 30.41623 -58.86984) (xy 30.329701 -58.861822) (xy 30.244281 -58.845854)
			(xy 30.160699 -58.822073) (xy 30.079667 -58.790681) (xy 30.001878 -58.751947) (xy 29.927994 -58.7062)
			(xy 29.858647 -58.653831) (xy 29.794427 -58.595287) (xy 29.735883 -58.531067) (xy 29.683514 -58.46172)
			(xy 29.637767 -58.387836) (xy 29.599033 -58.310047) (xy 29.567641 -58.229015) (xy 29.54386 -58.145433)
			(xy 29.527892 -58.060013) (xy 29.519874 -57.973484) (xy 29.170884 -57.973484) (xy 29.170884 -58.97352)
			(xy 63.833873 -58.97352) (xy 63.837758 -58.919165) (xy 63.849339 -58.865916) (xy 63.86838 -58.814857)
			(xy 63.894494 -58.767028) (xy 63.927149 -58.723402) (xy 63.965681 -58.684868) (xy 64.009304 -58.652209)
			(xy 64.057131 -58.626092) (xy 64.108189 -58.607047) (xy 64.161437 -58.595462) (xy 64.215792 -58.591573)
			(xy 64.270147 -58.595459) (xy 64.323395 -58.607042) (xy 64.374454 -58.626085) (xy 64.422282 -58.6522)
			(xy 64.444372 -58.668158) (xy 64.463384 -58.681754) (xy 64.505267 -58.702486) (xy 64.550235 -58.715212)
			(xy 64.596772 -58.719502) (xy 64.643309 -58.715212) (xy 64.688277 -58.702486) (xy 64.73016 -58.681754)
			(xy 64.749172 -58.668158) (xy 64.771293 -58.652242) (xy 64.819118 -58.626121) (xy 64.870174 -58.607073)
			(xy 64.923422 -58.595485) (xy 64.977776 -58.591594) (xy 65.032132 -58.595478) (xy 65.08538 -58.607059)
			(xy 65.136439 -58.626101) (xy 65.184268 -58.652216) (xy 65.227893 -58.684872) (xy 65.266426 -58.723405)
			(xy 65.299082 -58.76703) (xy 65.325197 -58.814858) (xy 65.34424 -58.865917) (xy 65.355821 -58.919165)
			(xy 65.359706 -58.97352) (xy 66.063466 -58.97352) (xy 66.067351 -58.919164) (xy 66.078932 -58.865913)
			(xy 66.097974 -58.814853) (xy 66.124089 -58.767022) (xy 66.156746 -58.723395) (xy 66.195279 -58.68486)
			(xy 66.238904 -58.652201) (xy 66.286733 -58.626083) (xy 66.337792 -58.607038) (xy 66.391042 -58.595454)
			(xy 66.445399 -58.591566) (xy 66.499755 -58.595453) (xy 66.553005 -58.607037) (xy 66.604065 -58.626082)
			(xy 66.651894 -58.652199) (xy 66.673984 -58.668158) (xy 66.692996 -58.681754) (xy 66.734879 -58.702486)
			(xy 66.779847 -58.715212) (xy 66.826384 -58.719502) (xy 66.872921 -58.715212) (xy 66.917889 -58.702486)
			(xy 66.959772 -58.681754) (xy 66.978784 -58.668158) (xy 67.000904 -58.652243) (xy 67.048729 -58.626124)
			(xy 67.099784 -58.607077) (xy 67.15303 -58.595491) (xy 67.207383 -58.591601) (xy 67.261737 -58.595486)
			(xy 67.314984 -58.607068) (xy 67.366041 -58.62611) (xy 67.413867 -58.652224) (xy 67.457491 -58.68488)
			(xy 67.496022 -58.723412) (xy 67.528678 -58.767036) (xy 67.554792 -58.814863) (xy 67.573833 -58.86592)
			(xy 67.583909 -58.912248) (xy 80.337134 -58.912248) (xy 80.337134 -58.852312) (xy 80.344957 -58.79289)
			(xy 80.36047 -58.734997) (xy 80.383406 -58.679624) (xy 80.413373 -58.627718) (xy 80.44986 -58.580168)
			(xy 80.49224 -58.537788) (xy 80.53979 -58.501301) (xy 80.591696 -58.471334) (xy 80.647069 -58.448398)
			(xy 80.704962 -58.432885) (xy 80.764384 -58.425062) (xy 80.82432 -58.425062) (xy 80.883742 -58.432885)
			(xy 80.941635 -58.448398) (xy 80.997008 -58.471334) (xy 81.048914 -58.501301) (xy 81.096464 -58.537788)
			(xy 81.138844 -58.580168) (xy 81.175331 -58.627718) (xy 81.205298 -58.679624) (xy 81.228234 -58.734997)
			(xy 81.243747 -58.79289) (xy 81.251435 -58.851288) (xy 82.018868 -58.851288) (xy 82.018868 -58.791352)
			(xy 82.026691 -58.73193) (xy 82.042204 -58.674037) (xy 82.06514 -58.618664) (xy 82.095107 -58.566758)
			(xy 82.131594 -58.519208) (xy 82.173974 -58.476828) (xy 82.221524 -58.440341) (xy 82.27343 -58.410374)
			(xy 82.328803 -58.387438) (xy 82.386696 -58.371925) (xy 82.446118 -58.364102) (xy 82.506054 -58.364102)
			(xy 82.565476 -58.371925) (xy 82.623369 -58.387438) (xy 82.678742 -58.410374) (xy 82.730648 -58.440341)
			(xy 82.778198 -58.476828) (xy 82.820578 -58.519208) (xy 82.857065 -58.566758) (xy 82.887032 -58.618664)
			(xy 82.909968 -58.674037) (xy 82.925481 -58.73193) (xy 82.933304 -58.791352) (xy 82.933794 -58.82132)
			(xy 82.933304 -58.851288) (xy 82.925481 -58.91071) (xy 82.911388 -58.963302) (xy 83.628466 -58.963302)
			(xy 83.628466 -58.903366) (xy 83.636289 -58.843944) (xy 83.651802 -58.786051) (xy 83.674738 -58.730678)
			(xy 83.704705 -58.678772) (xy 83.741192 -58.631222) (xy 83.783572 -58.588842) (xy 83.831122 -58.552355)
			(xy 83.883028 -58.522388) (xy 83.938401 -58.499452) (xy 83.996294 -58.483939) (xy 84.055716 -58.476116)
			(xy 84.115652 -58.476116) (xy 84.175074 -58.483939) (xy 84.232967 -58.499452) (xy 84.28834 -58.522388)
			(xy 84.340246 -58.552355) (xy 84.387796 -58.588842) (xy 84.430176 -58.631222) (xy 84.466663 -58.678772)
			(xy 84.49663 -58.730678) (xy 84.519566 -58.786051) (xy 84.535079 -58.843944) (xy 84.542902 -58.903366)
			(xy 84.543392 -58.933334) (xy 84.542902 -58.963302) (xy 84.535079 -59.022724) (xy 84.519566 -59.080617)
			(xy 84.49663 -59.13599) (xy 84.466663 -59.187896) (xy 84.430176 -59.235446) (xy 84.387796 -59.277826)
			(xy 84.340246 -59.314313) (xy 84.28834 -59.34428) (xy 84.232967 -59.367216) (xy 84.175074 -59.382729)
			(xy 84.115652 -59.390552) (xy 84.055716 -59.390552) (xy 83.996294 -59.382729) (xy 83.938401 -59.367216)
			(xy 83.883028 -59.34428) (xy 83.831122 -59.314313) (xy 83.783572 -59.277826) (xy 83.741192 -59.235446)
			(xy 83.704705 -59.187896) (xy 83.674738 -59.13599) (xy 83.651802 -59.080617) (xy 83.636289 -59.022724)
			(xy 83.628466 -58.963302) (xy 82.911388 -58.963302) (xy 82.909968 -58.968603) (xy 82.887032 -59.023976)
			(xy 82.857065 -59.075882) (xy 82.820578 -59.123432) (xy 82.778198 -59.165812) (xy 82.730648 -59.202299)
			(xy 82.678742 -59.232266) (xy 82.623369 -59.255202) (xy 82.565476 -59.270715) (xy 82.506054 -59.278538)
			(xy 82.446118 -59.278538) (xy 82.386696 -59.270715) (xy 82.328803 -59.255202) (xy 82.27343 -59.232266)
			(xy 82.221524 -59.202299) (xy 82.173974 -59.165812) (xy 82.131594 -59.123432) (xy 82.095107 -59.075882)
			(xy 82.06514 -59.023976) (xy 82.042204 -58.968603) (xy 82.026691 -58.91071) (xy 82.018868 -58.851288)
			(xy 81.251435 -58.851288) (xy 81.25157 -58.852312) (xy 81.25206 -58.88228) (xy 81.25157 -58.912248)
			(xy 81.243747 -58.97167) (xy 81.228234 -59.029563) (xy 81.205298 -59.084936) (xy 81.175331 -59.136842)
			(xy 81.138844 -59.184392) (xy 81.096464 -59.226772) (xy 81.048914 -59.263259) (xy 80.997008 -59.293226)
			(xy 80.941635 -59.316162) (xy 80.883742 -59.331675) (xy 80.82432 -59.339498) (xy 80.764384 -59.339498)
			(xy 80.704962 -59.331675) (xy 80.647069 -59.316162) (xy 80.591696 -59.293226) (xy 80.53979 -59.263259)
			(xy 80.49224 -59.226772) (xy 80.44986 -59.184392) (xy 80.413373 -59.136842) (xy 80.383406 -59.084936)
			(xy 80.36047 -59.029563) (xy 80.344957 -58.97167) (xy 80.337134 -58.912248) (xy 67.583909 -58.912248)
			(xy 67.585414 -58.919167) (xy 67.589299 -58.97352) (xy 67.585408 -59.027873) (xy 67.573822 -59.081119)
			(xy 67.554775 -59.132174) (xy 67.528655 -59.179999) (xy 67.495996 -59.223619) (xy 67.45746 -59.262147)
			(xy 67.413833 -59.294798) (xy 67.366003 -59.320907) (xy 67.314945 -59.339944) (xy 67.261696 -59.351519)
			(xy 67.207342 -59.355399) (xy 67.15299 -59.351503) (xy 67.099745 -59.339911) (xy 67.048692 -59.320859)
			(xy 67.00087 -59.294735) (xy 66.978784 -59.278774) (xy 66.959772 -59.265178) (xy 66.917889 -59.244446)
			(xy 66.872921 -59.23172) (xy 66.826384 -59.22743) (xy 66.779847 -59.23172) (xy 66.734879 -59.244446)
			(xy 66.692996 -59.265178) (xy 66.673984 -59.278774) (xy 66.651928 -59.294778) (xy 66.604102 -59.320901)
			(xy 66.553044 -59.339951) (xy 66.499796 -59.351541) (xy 66.445439 -59.355434) (xy 66.391082 -59.351552)
			(xy 66.337831 -59.339973) (xy 66.28677 -59.320934) (xy 66.238938 -59.294821) (xy 66.19531 -59.262167)
			(xy 66.156772 -59.223636) (xy 66.124111 -59.180012) (xy 66.097991 -59.132184) (xy 66.078944 -59.081126)
			(xy 66.067357 -59.027877) (xy 66.063466 -58.97352) (xy 65.359706 -58.97352) (xy 65.355815 -59.027875)
			(xy 65.344228 -59.081123) (xy 65.325181 -59.132179) (xy 65.29906 -59.180005) (xy 65.266399 -59.223626)
			(xy 65.227862 -59.262154) (xy 65.184233 -59.294806) (xy 65.136402 -59.320916) (xy 65.085341 -59.339952)
			(xy 65.032091 -59.351527) (xy 64.977736 -59.355406) (xy 64.923381 -59.351509) (xy 64.870135 -59.339916)
			(xy 64.819081 -59.320862) (xy 64.771258 -59.294736) (xy 64.749172 -59.278774) (xy 64.73016 -59.265178)
			(xy 64.688277 -59.244446) (xy 64.643309 -59.23172) (xy 64.596772 -59.22743) (xy 64.550235 -59.23172)
			(xy 64.505267 -59.244446) (xy 64.463384 -59.265178) (xy 64.444372 -59.278774) (xy 64.422316 -59.294777)
			(xy 64.374491 -59.320898) (xy 64.323435 -59.339946) (xy 64.270187 -59.351535) (xy 64.215833 -59.355427)
			(xy 64.161477 -59.351544) (xy 64.108228 -59.339965) (xy 64.057168 -59.320925) (xy 64.009338 -59.294813)
			(xy 63.965711 -59.262159) (xy 63.927176 -59.223629) (xy 63.894516 -59.180006) (xy 63.868397 -59.13218)
			(xy 63.84935 -59.081123) (xy 63.837764 -59.027875) (xy 63.833873 -58.97352) (xy 29.170884 -58.97352)
			(xy 29.170884 -60.513484) (xy 29.519874 -60.513484) (xy 29.519874 -60.426584) (xy 29.527892 -60.340055)
			(xy 29.54386 -60.254635) (xy 29.567641 -60.171053) (xy 29.599033 -60.090021) (xy 29.637767 -60.012232)
			(xy 29.683514 -59.938348) (xy 29.735883 -59.869001) (xy 29.794427 -59.804781) (xy 29.858647 -59.746237)
			(xy 29.927994 -59.693868) (xy 30.001878 -59.648121) (xy 30.079667 -59.609387) (xy 30.160699 -59.577995)
			(xy 30.244281 -59.554214) (xy 30.329701 -59.538246) (xy 30.41623 -59.530228) (xy 30.50313 -59.530228)
			(xy 30.589659 -59.538246) (xy 30.675079 -59.554214) (xy 30.758661 -59.577995) (xy 30.839693 -59.609387)
			(xy 30.917482 -59.648121) (xy 30.991366 -59.693868) (xy 31.060713 -59.746237) (xy 31.124933 -59.804781)
			(xy 31.183477 -59.869001) (xy 31.235846 -59.938348) (xy 31.281593 -60.012232) (xy 31.320327 -60.090021)
			(xy 31.351719 -60.171053) (xy 31.3755 -60.254635) (xy 31.391468 -60.340055) (xy 31.399486 -60.426584)
			(xy 31.399988 -60.470034) (xy 31.399486 -60.513484) (xy 34.599874 -60.513484) (xy 34.599874 -60.426584)
			(xy 34.607892 -60.340055) (xy 34.62386 -60.254635) (xy 34.647641 -60.171053) (xy 34.679033 -60.090021)
			(xy 34.717767 -60.012232) (xy 34.763514 -59.938348) (xy 34.815883 -59.869001) (xy 34.874427 -59.804781)
			(xy 34.938647 -59.746237) (xy 35.007994 -59.693868) (xy 35.081878 -59.648121) (xy 35.159667 -59.609387)
			(xy 35.240699 -59.577995) (xy 35.324281 -59.554214) (xy 35.409701 -59.538246) (xy 35.49623 -59.530228)
			(xy 35.58313 -59.530228) (xy 35.669659 -59.538246) (xy 35.755079 -59.554214) (xy 35.838661 -59.577995)
			(xy 35.919693 -59.609387) (xy 35.997482 -59.648121) (xy 36.071366 -59.693868) (xy 36.140713 -59.746237)
			(xy 36.204933 -59.804781) (xy 36.263477 -59.869001) (xy 36.315846 -59.938348) (xy 36.361593 -60.012232)
			(xy 36.400327 -60.090021) (xy 36.431719 -60.171053) (xy 36.4555 -60.254635) (xy 36.471468 -60.340055)
			(xy 36.479486 -60.426584) (xy 36.479988 -60.470034) (xy 36.479486 -60.513484) (xy 36.478593 -60.523116)
			(xy 79.530938 -60.523116) (xy 79.530938 -60.46318) (xy 79.538761 -60.403758) (xy 79.554274 -60.345865)
			(xy 79.57721 -60.290492) (xy 79.607177 -60.238586) (xy 79.643664 -60.191036) (xy 79.686044 -60.148656)
			(xy 79.733594 -60.112169) (xy 79.7855 -60.082202) (xy 79.840873 -60.059266) (xy 79.898766 -60.043753)
			(xy 79.958188 -60.03593) (xy 80.018124 -60.03593) (xy 80.077546 -60.043753) (xy 80.135439 -60.059266)
			(xy 80.190812 -60.082202) (xy 80.242718 -60.112169) (xy 80.290268 -60.148656) (xy 80.332648 -60.191036)
			(xy 80.369135 -60.238586) (xy 80.399102 -60.290492) (xy 80.422038 -60.345865) (xy 80.437551 -60.403758)
			(xy 80.445374 -60.46318) (xy 80.445864 -60.493148) (xy 80.445478 -60.516766) (xy 81.305128 -60.516766)
			(xy 81.305128 -60.45683) (xy 81.312951 -60.397408) (xy 81.328464 -60.339515) (xy 81.3514 -60.284142)
			(xy 81.381367 -60.232236) (xy 81.417854 -60.184686) (xy 81.460234 -60.142306) (xy 81.507784 -60.105819)
			(xy 81.55969 -60.075852) (xy 81.615063 -60.052916) (xy 81.672956 -60.037403) (xy 81.732378 -60.02958)
			(xy 81.792314 -60.02958) (xy 81.851736 -60.037403) (xy 81.909629 -60.052916) (xy 81.965002 -60.075852)
			(xy 82.016908 -60.105819) (xy 82.064458 -60.142306) (xy 82.106838 -60.184686) (xy 82.143325 -60.232236)
			(xy 82.173292 -60.284142) (xy 82.196228 -60.339515) (xy 82.211741 -60.397408) (xy 82.219564 -60.45683)
			(xy 82.220054 -60.486798) (xy 82.219564 -60.516766) (xy 82.211741 -60.576188) (xy 82.196228 -60.634081)
			(xy 82.173292 -60.689454) (xy 82.143325 -60.74136) (xy 82.106838 -60.78891) (xy 82.064458 -60.83129)
			(xy 82.016908 -60.867777) (xy 81.965002 -60.897744) (xy 81.909629 -60.92068) (xy 81.851736 -60.936193)
			(xy 81.792314 -60.944016) (xy 81.732378 -60.944016) (xy 81.672956 -60.936193) (xy 81.615063 -60.92068)
			(xy 81.55969 -60.897744) (xy 81.507784 -60.867777) (xy 81.460234 -60.83129) (xy 81.417854 -60.78891)
			(xy 81.381367 -60.74136) (xy 81.3514 -60.689454) (xy 81.328464 -60.634081) (xy 81.312951 -60.576188)
			(xy 81.305128 -60.516766) (xy 80.445478 -60.516766) (xy 80.445374 -60.523116) (xy 80.437551 -60.582538)
			(xy 80.422038 -60.640431) (xy 80.399102 -60.695804) (xy 80.369135 -60.74771) (xy 80.332648 -60.79526)
			(xy 80.290268 -60.83764) (xy 80.242718 -60.874127) (xy 80.190812 -60.904094) (xy 80.135439 -60.92703)
			(xy 80.077546 -60.942543) (xy 80.018124 -60.950366) (xy 79.958188 -60.950366) (xy 79.898766 -60.942543)
			(xy 79.840873 -60.92703) (xy 79.7855 -60.904094) (xy 79.733594 -60.874127) (xy 79.686044 -60.83764)
			(xy 79.643664 -60.79526) (xy 79.607177 -60.74771) (xy 79.57721 -60.695804) (xy 79.554274 -60.640431)
			(xy 79.538761 -60.582538) (xy 79.530938 -60.523116) (xy 36.478593 -60.523116) (xy 36.471468 -60.600013)
			(xy 36.4555 -60.685433) (xy 36.431719 -60.769015) (xy 36.400327 -60.850047) (xy 36.361593 -60.927836)
			(xy 36.315846 -61.00172) (xy 36.263477 -61.071067) (xy 36.204933 -61.135287) (xy 36.140713 -61.193831)
			(xy 36.071366 -61.2462) (xy 36.070869 -61.246508) (xy 77.3346 -61.246508) (xy 77.3346 -61.186572)
			(xy 77.342423 -61.12715) (xy 77.357936 -61.069257) (xy 77.380872 -61.013884) (xy 77.410839 -60.961978)
			(xy 77.447326 -60.914428) (xy 77.489706 -60.872048) (xy 77.537256 -60.835561) (xy 77.589162 -60.805594)
			(xy 77.644535 -60.782658) (xy 77.702428 -60.767145) (xy 77.76185 -60.759322) (xy 77.821786 -60.759322)
			(xy 77.881208 -60.767145) (xy 77.939101 -60.782658) (xy 77.994474 -60.805594) (xy 78.04638 -60.835561)
			(xy 78.09393 -60.872048) (xy 78.13631 -60.914428) (xy 78.172797 -60.961978) (xy 78.202764 -61.013884)
			(xy 78.2257 -61.069257) (xy 78.241213 -61.12715) (xy 78.249036 -61.186572) (xy 78.249526 -61.21654)
			(xy 78.249036 -61.246508) (xy 78.241213 -61.30593) (xy 78.2257 -61.363823) (xy 78.202764 -61.419196)
			(xy 78.172797 -61.471102) (xy 78.13631 -61.518652) (xy 78.09393 -61.561032) (xy 78.04638 -61.597519)
			(xy 77.994474 -61.627486) (xy 77.939101 -61.650422) (xy 77.881208 -61.665935) (xy 77.821786 -61.673758)
			(xy 77.76185 -61.673758) (xy 77.702428 -61.665935) (xy 77.644535 -61.650422) (xy 77.589162 -61.627486)
			(xy 77.537256 -61.597519) (xy 77.489706 -61.561032) (xy 77.447326 -61.518652) (xy 77.410839 -61.471102)
			(xy 77.380872 -61.419196) (xy 77.357936 -61.363823) (xy 77.342423 -61.30593) (xy 77.3346 -61.246508)
			(xy 36.070869 -61.246508) (xy 35.997482 -61.291947) (xy 35.919693 -61.330681) (xy 35.838661 -61.362073)
			(xy 35.755079 -61.385854) (xy 35.669659 -61.401822) (xy 35.58313 -61.40984) (xy 35.49623 -61.40984)
			(xy 35.409701 -61.401822) (xy 35.324281 -61.385854) (xy 35.240699 -61.362073) (xy 35.159667 -61.330681)
			(xy 35.081878 -61.291947) (xy 35.007994 -61.2462) (xy 34.938647 -61.193831) (xy 34.874427 -61.135287)
			(xy 34.815883 -61.071067) (xy 34.763514 -61.00172) (xy 34.717767 -60.927836) (xy 34.679033 -60.850047)
			(xy 34.647641 -60.769015) (xy 34.62386 -60.685433) (xy 34.607892 -60.600013) (xy 34.599874 -60.513484)
			(xy 31.399486 -60.513484) (xy 31.391468 -60.600013) (xy 31.3755 -60.685433) (xy 31.351719 -60.769015)
			(xy 31.320327 -60.850047) (xy 31.281593 -60.927836) (xy 31.235846 -61.00172) (xy 31.183477 -61.071067)
			(xy 31.124933 -61.135287) (xy 31.060713 -61.193831) (xy 30.991366 -61.2462) (xy 30.917482 -61.291947)
			(xy 30.839693 -61.330681) (xy 30.758661 -61.362073) (xy 30.675079 -61.385854) (xy 30.589659 -61.401822)
			(xy 30.50313 -61.40984) (xy 30.41623 -61.40984) (xy 30.329701 -61.401822) (xy 30.244281 -61.385854)
			(xy 30.160699 -61.362073) (xy 30.079667 -61.330681) (xy 30.001878 -61.291947) (xy 29.927994 -61.2462)
			(xy 29.858647 -61.193831) (xy 29.794427 -61.135287) (xy 29.735883 -61.071067) (xy 29.683514 -61.00172)
			(xy 29.637767 -60.927836) (xy 29.599033 -60.850047) (xy 29.567641 -60.769015) (xy 29.54386 -60.685433)
			(xy 29.527892 -60.600013) (xy 29.519874 -60.513484) (xy 29.170884 -60.513484) (xy 29.170884 -61.641678)
			(xy 63.833929 -61.641678) (xy 63.837819 -61.587332) (xy 63.849404 -61.534092) (xy 63.868448 -61.483042)
			(xy 63.894564 -61.435223) (xy 63.927219 -61.391607) (xy 63.965749 -61.353083) (xy 64.00937 -61.320434)
			(xy 64.057193 -61.294325) (xy 64.108245 -61.275289) (xy 64.161486 -61.263711) (xy 64.215834 -61.259829)
			(xy 64.27018 -61.263721) (xy 64.32342 -61.275308) (xy 64.374469 -61.294353) (xy 64.422287 -61.32047)
			(xy 64.444372 -61.336428) (xy 64.463384 -61.350024) (xy 64.505267 -61.370756) (xy 64.550235 -61.383482)
			(xy 64.596772 -61.387772) (xy 64.643309 -61.383482) (xy 64.688277 -61.370756) (xy 64.73016 -61.350024)
			(xy 64.749172 -61.336428) (xy 64.771227 -61.320417) (xy 64.819057 -61.294287) (xy 64.870118 -61.275231)
			(xy 64.923372 -61.263636) (xy 64.977734 -61.259738) (xy 65.032098 -61.263617) (xy 65.085356 -61.275194)
			(xy 65.136424 -61.294233) (xy 65.184263 -61.320346) (xy 65.227898 -61.353002) (xy 65.26644 -61.391537)
			(xy 65.299107 -61.435164) (xy 65.325231 -61.482997) (xy 65.344282 -61.53406) (xy 65.355871 -61.587316)
			(xy 65.359762 -61.641678) (xy 66.063522 -61.641678) (xy 66.067412 -61.58733) (xy 66.078998 -61.534088)
			(xy 66.098043 -61.483038) (xy 66.124159 -61.435217) (xy 66.156816 -61.3916) (xy 66.195347 -61.353075)
			(xy 66.238969 -61.320425) (xy 66.286794 -61.294317) (xy 66.337848 -61.27528) (xy 66.391092 -61.263703)
			(xy 66.445441 -61.259822) (xy 66.499789 -61.263715) (xy 66.55303 -61.275303) (xy 66.604079 -61.29435)
			(xy 66.651899 -61.320469) (xy 66.673984 -61.336428) (xy 66.692996 -61.350024) (xy 66.734879 -61.370756)
			(xy 66.779847 -61.383482) (xy 66.826384 -61.387772) (xy 66.872921 -61.383482) (xy 66.917889 -61.370756)
			(xy 66.959772 -61.350024) (xy 66.978784 -61.336428) (xy 67.000839 -61.320418) (xy 67.048668 -61.29429)
			(xy 67.099728 -61.275235) (xy 67.152981 -61.263642) (xy 67.207341 -61.259745) (xy 67.261703 -61.263625)
			(xy 67.314959 -61.275202) (xy 67.366026 -61.294241) (xy 67.413862 -61.320355) (xy 67.457496 -61.35301)
			(xy 67.496037 -61.391544) (xy 67.528702 -61.43517) (xy 67.554825 -61.483001) (xy 67.573875 -61.534064)
			(xy 67.585464 -61.587317) (xy 67.589355 -61.641678) (xy 67.58547 -61.69604) (xy 67.573887 -61.749295)
			(xy 67.554843 -61.800359) (xy 67.528725 -61.848194) (xy 67.496065 -61.891824) (xy 67.457528 -61.930361)
			(xy 67.413899 -61.963022) (xy 67.366065 -61.989141) (xy 67.315001 -62.008186) (xy 67.261746 -62.019769)
			(xy 67.207384 -62.023655) (xy 67.153023 -62.019764) (xy 67.099769 -62.008177) (xy 67.048707 -61.989128)
			(xy 67.000875 -61.963005) (xy 66.978784 -61.947044) (xy 66.959772 -61.933448) (xy 66.917889 -61.912716)
			(xy 66.872921 -61.89999) (xy 66.826384 -61.8957) (xy 66.779847 -61.89999) (xy 66.734879 -61.912716)
			(xy 66.692996 -61.933448) (xy 66.673984 -61.947044) (xy 66.651862 -61.962954) (xy 66.60404 -61.989068)
			(xy 66.552988 -62.008109) (xy 66.499746 -62.019691) (xy 66.445397 -62.023578) (xy 66.391049 -62.019691)
			(xy 66.337807 -62.008108) (xy 66.286755 -61.989065) (xy 66.238933 -61.962951) (xy 66.195314 -61.930297)
			(xy 66.156787 -61.891767) (xy 66.124136 -61.848147) (xy 66.098025 -61.800323) (xy 66.078986 -61.74927)
			(xy 66.067406 -61.696027) (xy 66.063522 -61.641678) (xy 65.359762 -61.641678) (xy 65.355877 -61.696041)
			(xy 65.344294 -61.749298) (xy 65.325249 -61.800364) (xy 65.29913 -61.8482) (xy 65.266469 -61.891831)
			(xy 65.22793 -61.930369) (xy 65.184299 -61.96303) (xy 65.136463 -61.989149) (xy 65.085397 -62.008194)
			(xy 65.032141 -62.019777) (xy 64.977778 -62.023662) (xy 64.923415 -62.019771) (xy 64.87016 -62.008181)
			(xy 64.819096 -61.989131) (xy 64.771263 -61.963006) (xy 64.749172 -61.947044) (xy 64.73016 -61.933448)
			(xy 64.688277 -61.912716) (xy 64.643309 -61.89999) (xy 64.596772 -61.8957) (xy 64.550235 -61.89999)
			(xy 64.505267 -61.912716) (xy 64.463384 -61.933448) (xy 64.444372 -61.947044) (xy 64.422251 -61.962953)
			(xy 64.374429 -61.989065) (xy 64.323378 -62.008105) (xy 64.270138 -62.019685) (xy 64.215791 -62.023571)
			(xy 64.161444 -62.019683) (xy 64.108203 -62.008099) (xy 64.057153 -61.989057) (xy 64.009333 -61.962943)
			(xy 63.965716 -61.930289) (xy 63.927191 -61.89176) (xy 63.89454 -61.848141) (xy 63.86843 -61.800318)
			(xy 63.849392 -61.749267) (xy 63.837813 -61.696026) (xy 63.833929 -61.641678) (xy 29.170884 -61.641678)
			(xy 29.170884 -62.056264) (xy 51.025044 -62.056264) (xy 52.676552 -62.056264) (xy 52.676552 -63.24117)
			(xy 77.78926 -63.24117) (xy 77.78926 -63.181234) (xy 77.797083 -63.121812) (xy 77.812596 -63.063919)
			(xy 77.835532 -63.008546) (xy 77.865499 -62.95664) (xy 77.901986 -62.90909) (xy 77.944366 -62.86671)
			(xy 77.991916 -62.830223) (xy 78.043822 -62.800256) (xy 78.099195 -62.77732) (xy 78.157088 -62.761807)
			(xy 78.21651 -62.753984) (xy 78.276446 -62.753984) (xy 78.335868 -62.761807) (xy 78.393761 -62.77732)
			(xy 78.449134 -62.800256) (xy 78.50104 -62.830223) (xy 78.54859 -62.86671) (xy 78.59097 -62.90909)
			(xy 78.627457 -62.95664) (xy 78.657424 -63.008546) (xy 78.68036 -63.063919) (xy 78.695873 -63.121812)
			(xy 78.703696 -63.181234) (xy 78.704186 -63.211202) (xy 78.703696 -63.24117) (xy 78.695873 -63.300592)
			(xy 78.68036 -63.358485) (xy 78.657424 -63.413858) (xy 78.627457 -63.465764) (xy 78.59097 -63.513314)
			(xy 78.54859 -63.555694) (xy 78.54736 -63.556638) (xy 81.066876 -63.556638) (xy 81.066876 -63.496702)
			(xy 81.074699 -63.43728) (xy 81.090212 -63.379387) (xy 81.113148 -63.324014) (xy 81.143115 -63.272108)
			(xy 81.179602 -63.224558) (xy 81.221982 -63.182178) (xy 81.269532 -63.145691) (xy 81.321438 -63.115724)
			(xy 81.376811 -63.092788) (xy 81.434704 -63.077275) (xy 81.494126 -63.069452) (xy 81.554062 -63.069452)
			(xy 81.613484 -63.077275) (xy 81.671377 -63.092788) (xy 81.72675 -63.115724) (xy 81.778656 -63.145691)
			(xy 81.826206 -63.182178) (xy 81.868586 -63.224558) (xy 81.905073 -63.272108) (xy 81.93504 -63.324014)
			(xy 81.957976 -63.379387) (xy 81.973489 -63.43728) (xy 81.981312 -63.496702) (xy 81.981802 -63.52667)
			(xy 81.981312 -63.556638) (xy 81.973489 -63.61606) (xy 81.957976 -63.673953) (xy 81.93504 -63.729326)
			(xy 81.905073 -63.781232) (xy 81.868586 -63.828782) (xy 81.826206 -63.871162) (xy 81.778656 -63.907649)
			(xy 81.72675 -63.937616) (xy 81.671377 -63.960552) (xy 81.613484 -63.976065) (xy 81.554062 -63.983888)
			(xy 81.494126 -63.983888) (xy 81.434704 -63.976065) (xy 81.376811 -63.960552) (xy 81.321438 -63.937616)
			(xy 81.269532 -63.907649) (xy 81.221982 -63.871162) (xy 81.179602 -63.828782) (xy 81.143115 -63.781232)
			(xy 81.113148 -63.729326) (xy 81.090212 -63.673953) (xy 81.074699 -63.61606) (xy 81.066876 -63.556638)
			(xy 78.54736 -63.556638) (xy 78.50104 -63.592181) (xy 78.449134 -63.622148) (xy 78.393761 -63.645084)
			(xy 78.335868 -63.660597) (xy 78.276446 -63.66842) (xy 78.21651 -63.66842) (xy 78.157088 -63.660597)
			(xy 78.099195 -63.645084) (xy 78.043822 -63.622148) (xy 77.991916 -63.592181) (xy 77.944366 -63.555694)
			(xy 77.901986 -63.513314) (xy 77.865499 -63.465764) (xy 77.835532 -63.413858) (xy 77.812596 -63.358485)
			(xy 77.797083 -63.300592) (xy 77.78926 -63.24117) (xy 52.676552 -63.24117) (xy 52.676552 -63.70828)
			(xy 51.025044 -63.70828) (xy 51.025044 -62.056264) (xy 29.170884 -62.056264) (xy 29.170884 -63.053484)
			(xy 29.519874 -63.053484) (xy 29.519874 -62.966584) (xy 29.527892 -62.880055) (xy 29.54386 -62.794635)
			(xy 29.567641 -62.711053) (xy 29.599033 -62.630021) (xy 29.637767 -62.552232) (xy 29.683514 -62.478348)
			(xy 29.735883 -62.409001) (xy 29.794427 -62.344781) (xy 29.858647 -62.286237) (xy 29.927994 -62.233868)
			(xy 30.001878 -62.188121) (xy 30.079667 -62.149387) (xy 30.160699 -62.117995) (xy 30.244281 -62.094214)
			(xy 30.329701 -62.078246) (xy 30.41623 -62.070228) (xy 30.50313 -62.070228) (xy 30.589659 -62.078246)
			(xy 30.675079 -62.094214) (xy 30.758661 -62.117995) (xy 30.839693 -62.149387) (xy 30.917482 -62.188121)
			(xy 30.991366 -62.233868) (xy 31.060713 -62.286237) (xy 31.124933 -62.344781) (xy 31.183477 -62.409001)
			(xy 31.235846 -62.478348) (xy 31.281593 -62.552232) (xy 31.320327 -62.630021) (xy 31.351719 -62.711053)
			(xy 31.3755 -62.794635) (xy 31.391468 -62.880055) (xy 31.399486 -62.966584) (xy 31.399988 -63.010034)
			(xy 31.399486 -63.053484) (xy 34.599874 -63.053484) (xy 34.599874 -62.966584) (xy 34.607892 -62.880055)
			(xy 34.62386 -62.794635) (xy 34.647641 -62.711053) (xy 34.679033 -62.630021) (xy 34.717767 -62.552232)
			(xy 34.763514 -62.478348) (xy 34.815883 -62.409001) (xy 34.874427 -62.344781) (xy 34.938647 -62.286237)
			(xy 35.007994 -62.233868) (xy 35.081878 -62.188121) (xy 35.159667 -62.149387) (xy 35.240699 -62.117995)
			(xy 35.324281 -62.094214) (xy 35.409701 -62.078246) (xy 35.49623 -62.070228) (xy 35.58313 -62.070228)
			(xy 35.669659 -62.078246) (xy 35.755079 -62.094214) (xy 35.838661 -62.117995) (xy 35.919693 -62.149387)
			(xy 35.997482 -62.188121) (xy 36.071366 -62.233868) (xy 36.140713 -62.286237) (xy 36.204933 -62.344781)
			(xy 36.263477 -62.409001) (xy 36.315846 -62.478348) (xy 36.361593 -62.552232) (xy 36.400327 -62.630021)
			(xy 36.431719 -62.711053) (xy 36.4555 -62.794635) (xy 36.471468 -62.880055) (xy 36.475431 -62.922827)
			(xy 47.525168 -62.922827) (xy 47.525168 -62.841717) (xy 47.533118 -62.760998) (xy 47.548941 -62.681447)
			(xy 47.572486 -62.603831) (xy 47.603525 -62.528895) (xy 47.64176 -62.457363) (xy 47.686822 -62.389923)
			(xy 47.738277 -62.327224) (xy 47.79563 -62.269871) (xy 47.858329 -62.218416) (xy 47.925769 -62.173354)
			(xy 47.997301 -62.135119) (xy 48.072237 -62.10408) (xy 48.149853 -62.080535) (xy 48.229404 -62.064712)
			(xy 48.310123 -62.056762) (xy 48.391233 -62.056762) (xy 48.471952 -62.064712) (xy 48.551503 -62.080535)
			(xy 48.629119 -62.10408) (xy 48.704055 -62.135119) (xy 48.775587 -62.173354) (xy 48.843027 -62.218416)
			(xy 48.905726 -62.269871) (xy 48.963079 -62.327224) (xy 49.014534 -62.389923) (xy 49.059596 -62.457363)
			(xy 49.097831 -62.528895) (xy 49.12887 -62.603831) (xy 49.152415 -62.681447) (xy 49.168238 -62.760998)
			(xy 49.176188 -62.841717) (xy 49.176686 -62.882272) (xy 49.176188 -62.922827) (xy 49.168238 -63.003546)
			(xy 49.152415 -63.083097) (xy 49.12887 -63.160713) (xy 49.097831 -63.235649) (xy 49.059596 -63.307181)
			(xy 49.014534 -63.374621) (xy 48.963079 -63.43732) (xy 48.905726 -63.494673) (xy 48.843027 -63.546128)
			(xy 48.775587 -63.59119) (xy 48.704055 -63.629425) (xy 48.629119 -63.660464) (xy 48.551503 -63.684009)
			(xy 48.471952 -63.699832) (xy 48.391233 -63.707782) (xy 48.310123 -63.707782) (xy 48.229404 -63.699832)
			(xy 48.149853 -63.684009) (xy 48.072237 -63.660464) (xy 47.997301 -63.629425) (xy 47.925769 -63.59119)
			(xy 47.858329 -63.546128) (xy 47.79563 -63.494673) (xy 47.738277 -63.43732) (xy 47.686822 -63.374621)
			(xy 47.64176 -63.307181) (xy 47.603525 -63.235649) (xy 47.572486 -63.160713) (xy 47.548941 -63.083097)
			(xy 47.533118 -63.003546) (xy 47.525168 -62.922827) (xy 36.475431 -62.922827) (xy 36.479486 -62.966584)
			(xy 36.479988 -63.010034) (xy 36.479486 -63.053484) (xy 36.471468 -63.140013) (xy 36.4555 -63.225433)
			(xy 36.431719 -63.309015) (xy 36.400327 -63.390047) (xy 36.361593 -63.467836) (xy 36.315846 -63.54172)
			(xy 36.263477 -63.611067) (xy 36.204933 -63.675287) (xy 36.140713 -63.733831) (xy 36.071366 -63.7862)
			(xy 35.997482 -63.831947) (xy 35.919693 -63.870681) (xy 35.838661 -63.902073) (xy 35.755079 -63.925854)
			(xy 35.669659 -63.941822) (xy 35.58313 -63.94984) (xy 35.49623 -63.94984) (xy 35.409701 -63.941822)
			(xy 35.324281 -63.925854) (xy 35.240699 -63.902073) (xy 35.159667 -63.870681) (xy 35.081878 -63.831947)
			(xy 35.007994 -63.7862) (xy 34.938647 -63.733831) (xy 34.874427 -63.675287) (xy 34.815883 -63.611067)
			(xy 34.763514 -63.54172) (xy 34.717767 -63.467836) (xy 34.679033 -63.390047) (xy 34.647641 -63.309015)
			(xy 34.62386 -63.225433) (xy 34.607892 -63.140013) (xy 34.599874 -63.053484) (xy 31.399486 -63.053484)
			(xy 31.391468 -63.140013) (xy 31.3755 -63.225433) (xy 31.351719 -63.309015) (xy 31.320327 -63.390047)
			(xy 31.281593 -63.467836) (xy 31.235846 -63.54172) (xy 31.183477 -63.611067) (xy 31.124933 -63.675287)
			(xy 31.060713 -63.733831) (xy 30.991366 -63.7862) (xy 30.917482 -63.831947) (xy 30.839693 -63.870681)
			(xy 30.758661 -63.902073) (xy 30.675079 -63.925854) (xy 30.589659 -63.941822) (xy 30.50313 -63.94984)
			(xy 30.41623 -63.94984) (xy 30.329701 -63.941822) (xy 30.244281 -63.925854) (xy 30.160699 -63.902073)
			(xy 30.079667 -63.870681) (xy 30.001878 -63.831947) (xy 29.927994 -63.7862) (xy 29.858647 -63.733831)
			(xy 29.794427 -63.675287) (xy 29.735883 -63.611067) (xy 29.683514 -63.54172) (xy 29.637767 -63.467836)
			(xy 29.599033 -63.390047) (xy 29.567641 -63.309015) (xy 29.54386 -63.225433) (xy 29.527892 -63.140013)
			(xy 29.519874 -63.053484) (xy 29.170884 -63.053484) (xy 29.170884 -64.01328) (xy 63.833927 -64.01328)
			(xy 63.837817 -63.958933) (xy 63.849402 -63.905692) (xy 63.868446 -63.854643) (xy 63.894562 -63.806823)
			(xy 63.927217 -63.763207) (xy 63.965747 -63.724682) (xy 64.009368 -63.692033) (xy 64.057191 -63.665924)
			(xy 64.108243 -63.646887) (xy 64.161485 -63.63531) (xy 64.215833 -63.631427) (xy 64.270179 -63.635319)
			(xy 64.323419 -63.646906) (xy 64.374468 -63.665951) (xy 64.422287 -63.692068) (xy 64.444372 -63.708026)
			(xy 64.463384 -63.721622) (xy 64.505267 -63.742354) (xy 64.550235 -63.75508) (xy 64.596772 -63.75937)
			(xy 64.643309 -63.75508) (xy 64.688277 -63.742354) (xy 64.73016 -63.721622) (xy 64.749172 -63.708026)
			(xy 64.771229 -63.692018) (xy 64.819058 -63.665888) (xy 64.87012 -63.646832) (xy 64.923374 -63.635237)
			(xy 64.977736 -63.631339) (xy 65.032099 -63.635219) (xy 65.085357 -63.646796) (xy 65.136424 -63.665835)
			(xy 65.184263 -63.691948) (xy 65.227897 -63.724604) (xy 65.26644 -63.763139) (xy 65.299106 -63.806766)
			(xy 65.32523 -63.854598) (xy 65.34428 -63.905662) (xy 65.355869 -63.958917) (xy 65.359761 -64.01328)
			(xy 66.06352 -64.01328) (xy 66.06741 -63.958931) (xy 66.078996 -63.905689) (xy 66.098041 -63.854638)
			(xy 66.124157 -63.806817) (xy 66.156814 -63.7632) (xy 66.195345 -63.724674) (xy 66.238968 -63.692025)
			(xy 66.286793 -63.665916) (xy 66.337846 -63.646879) (xy 66.39109 -63.635302) (xy 66.445439 -63.63142)
			(xy 66.499788 -63.635313) (xy 66.553029 -63.646901) (xy 66.604079 -63.665948) (xy 66.651899 -63.692067)
			(xy 66.673984 -63.708026) (xy 66.692996 -63.721622) (xy 66.734879 -63.742354) (xy 66.779847 -63.75508)
			(xy 66.826384 -63.75937) (xy 66.872921 -63.75508) (xy 66.917889 -63.742354) (xy 66.959772 -63.721622)
			(xy 66.978784 -63.708026) (xy 67.000841 -63.692019) (xy 67.048669 -63.665891) (xy 67.09973 -63.646837)
			(xy 67.152982 -63.635243) (xy 67.207342 -63.631347) (xy 67.261704 -63.635227) (xy 67.31496 -63.646804)
			(xy 67.366026 -63.665843) (xy 67.413863 -63.691957) (xy 67.457495 -63.724612) (xy 67.496037 -63.763146)
			(xy 67.528701 -63.806772) (xy 67.554824 -63.854603) (xy 67.573874 -63.905665) (xy 67.585462 -63.958919)
			(xy 67.589353 -64.01328) (xy 67.586082 -64.05905) (xy 79.537542 -64.05905) (xy 79.537542 -63.999114)
			(xy 79.545365 -63.939692) (xy 79.560878 -63.881799) (xy 79.583814 -63.826426) (xy 79.613781 -63.77452)
			(xy 79.650268 -63.72697) (xy 79.692648 -63.68459) (xy 79.740198 -63.648103) (xy 79.792104 -63.618136)
			(xy 79.847477 -63.5952) (xy 79.90537 -63.579687) (xy 79.964792 -63.571864) (xy 80.024728 -63.571864)
			(xy 80.08415 -63.579687) (xy 80.142043 -63.5952) (xy 80.197416 -63.618136) (xy 80.249322 -63.648103)
			(xy 80.296872 -63.68459) (xy 80.339252 -63.72697) (xy 80.375739 -63.77452) (xy 80.405706 -63.826426)
			(xy 80.428642 -63.881799) (xy 80.444155 -63.939692) (xy 80.451978 -63.999114) (xy 80.452468 -64.029082)
			(xy 80.451978 -64.05905) (xy 80.444155 -64.118472) (xy 80.428642 -64.176365) (xy 80.405706 -64.231738)
			(xy 80.375739 -64.283644) (xy 80.339252 -64.331194) (xy 80.296872 -64.373574) (xy 80.249322 -64.410061)
			(xy 80.197416 -64.440028) (xy 80.142043 -64.462964) (xy 80.08415 -64.478477) (xy 80.024728 -64.4863)
			(xy 79.964792 -64.4863) (xy 79.90537 -64.478477) (xy 79.847477 -64.462964) (xy 79.792104 -64.440028)
			(xy 79.740198 -64.410061) (xy 79.692648 -64.373574) (xy 79.650268 -64.331194) (xy 79.613781 -64.283644)
			(xy 79.583814 -64.231738) (xy 79.560878 -64.176365) (xy 79.545365 -64.118472) (xy 79.537542 -64.05905)
			(xy 67.586082 -64.05905) (xy 67.585468 -64.067641) (xy 67.573885 -64.120896) (xy 67.554841 -64.17196)
			(xy 67.528723 -64.219794) (xy 67.496063 -64.263424) (xy 67.457526 -64.301961) (xy 67.413897 -64.334621)
			(xy 67.366063 -64.36074) (xy 67.314999 -64.379784) (xy 67.261744 -64.391367) (xy 67.207383 -64.395253)
			(xy 67.153022 -64.391363) (xy 67.099769 -64.379775) (xy 67.048706 -64.360726) (xy 67.000875 -64.334603)
			(xy 66.978784 -64.318642) (xy 66.959772 -64.305046) (xy 66.917889 -64.284314) (xy 66.872921 -64.271588)
			(xy 66.826384 -64.267298) (xy 66.779847 -64.271588) (xy 66.734879 -64.284314) (xy 66.692996 -64.305046)
			(xy 66.673984 -64.318642) (xy 66.651864 -64.334555) (xy 66.604042 -64.360668) (xy 66.55299 -64.37971)
			(xy 66.499747 -64.391293) (xy 66.445399 -64.39518) (xy 66.39105 -64.391292) (xy 66.337807 -64.37971)
			(xy 66.286755 -64.360667) (xy 66.238933 -64.334553) (xy 66.195314 -64.301899) (xy 66.156787 -64.263369)
			(xy 66.124135 -64.219748) (xy 66.098024 -64.171925) (xy 66.078984 -64.120872) (xy 66.067405 -64.067629)
			(xy 66.06352 -64.01328) (xy 65.359761 -64.01328) (xy 65.355875 -64.067642) (xy 65.344292 -64.120899)
			(xy 65.325247 -64.171964) (xy 65.299128 -64.2198) (xy 65.266467 -64.263431) (xy 65.227928 -64.301969)
			(xy 65.184297 -64.33463) (xy 65.136462 -64.360748) (xy 65.085396 -64.379793) (xy 65.032139 -64.391375)
			(xy 64.977776 -64.395261) (xy 64.923414 -64.391369) (xy 64.870159 -64.37978) (xy 64.819096 -64.360729)
			(xy 64.771263 -64.334604) (xy 64.749172 -64.318642) (xy 64.73016 -64.305046) (xy 64.688277 -64.284314)
			(xy 64.643309 -64.271588) (xy 64.596772 -64.267298) (xy 64.550235 -64.271588) (xy 64.505267 -64.284314)
			(xy 64.463384 -64.305046) (xy 64.444372 -64.318642) (xy 64.422253 -64.334554) (xy 64.374431 -64.360666)
			(xy 64.32338 -64.379706) (xy 64.270139 -64.391287) (xy 64.215792 -64.395173) (xy 64.161445 -64.391284)
			(xy 64.108204 -64.379701) (xy 64.057154 -64.360659) (xy 64.009333 -64.334545) (xy 63.965716 -64.301891)
			(xy 63.92719 -64.263362) (xy 63.89454 -64.219742) (xy 63.868429 -64.17192) (xy 63.849391 -64.120868)
			(xy 63.837812 -64.067627) (xy 63.833927 -64.01328) (xy 29.170884 -64.01328) (xy 29.170884 -65.593484)
			(xy 29.519874 -65.593484) (xy 29.519874 -65.506584) (xy 29.527892 -65.420055) (xy 29.54386 -65.334635)
			(xy 29.567641 -65.251053) (xy 29.599033 -65.170021) (xy 29.637767 -65.092232) (xy 29.683514 -65.018348)
			(xy 29.735883 -64.949001) (xy 29.794427 -64.884781) (xy 29.858647 -64.826237) (xy 29.927994 -64.773868)
			(xy 30.001878 -64.728121) (xy 30.079667 -64.689387) (xy 30.160699 -64.657995) (xy 30.244281 -64.634214)
			(xy 30.329701 -64.618246) (xy 30.41623 -64.610228) (xy 30.50313 -64.610228) (xy 30.589659 -64.618246)
			(xy 30.675079 -64.634214) (xy 30.758661 -64.657995) (xy 30.839693 -64.689387) (xy 30.917482 -64.728121)
			(xy 30.991366 -64.773868) (xy 31.060713 -64.826237) (xy 31.124933 -64.884781) (xy 31.183477 -64.949001)
			(xy 31.235846 -65.018348) (xy 31.281593 -65.092232) (xy 31.320327 -65.170021) (xy 31.351719 -65.251053)
			(xy 31.3755 -65.334635) (xy 31.391468 -65.420055) (xy 31.399486 -65.506584) (xy 31.399988 -65.550034)
			(xy 31.399486 -65.593484) (xy 34.599874 -65.593484) (xy 34.599874 -65.506584) (xy 34.607892 -65.420055)
			(xy 34.62386 -65.334635) (xy 34.647641 -65.251053) (xy 34.679033 -65.170021) (xy 34.717767 -65.092232)
			(xy 34.763514 -65.018348) (xy 34.815883 -64.949001) (xy 34.874427 -64.884781) (xy 34.938647 -64.826237)
			(xy 35.007994 -64.773868) (xy 35.081878 -64.728121) (xy 35.159667 -64.689387) (xy 35.240699 -64.657995)
			(xy 35.324281 -64.634214) (xy 35.409701 -64.618246) (xy 35.49623 -64.610228) (xy 35.58313 -64.610228)
			(xy 35.669659 -64.618246) (xy 35.755079 -64.634214) (xy 35.838661 -64.657995) (xy 35.919693 -64.689387)
			(xy 35.997482 -64.728121) (xy 36.071366 -64.773868) (xy 36.140713 -64.826237) (xy 36.204933 -64.884781)
			(xy 36.263477 -64.949001) (xy 36.315846 -65.018348) (xy 36.361593 -65.092232) (xy 36.400327 -65.170021)
			(xy 36.431719 -65.251053) (xy 36.4555 -65.334635) (xy 36.471468 -65.420055) (xy 36.479486 -65.506584)
			(xy 36.479988 -65.550034) (xy 36.479486 -65.593484) (xy 36.471468 -65.680013) (xy 36.4555 -65.765433)
			(xy 36.431719 -65.849015) (xy 36.400327 -65.930047) (xy 36.37736 -65.976172) (xy 63.833937 -65.976172)
			(xy 63.837828 -65.921827) (xy 63.849414 -65.868588) (xy 63.868458 -65.81754) (xy 63.894574 -65.769722)
			(xy 63.927229 -65.726108) (xy 63.965759 -65.687585) (xy 64.009379 -65.654937) (xy 64.057202 -65.62883)
			(xy 64.108253 -65.609795) (xy 64.161493 -65.598218) (xy 64.21584 -65.594337) (xy 64.270185 -65.59823)
			(xy 64.323423 -65.609817) (xy 64.374471 -65.628863) (xy 64.422288 -65.65498) (xy 64.444372 -65.670938)
			(xy 64.463384 -65.684534) (xy 64.505267 -65.705266) (xy 64.550235 -65.717992) (xy 64.596772 -65.722282)
			(xy 64.643309 -65.717992) (xy 64.688277 -65.705266) (xy 64.73016 -65.684534) (xy 64.749172 -65.670938)
			(xy 64.771218 -65.654914) (xy 64.819048 -65.628782) (xy 64.87011 -65.609725) (xy 64.923365 -65.598129)
			(xy 64.977728 -65.59423) (xy 65.032093 -65.598108) (xy 65.085352 -65.609684) (xy 65.136422 -65.628723)
			(xy 65.184262 -65.654836) (xy 65.227898 -65.687492) (xy 65.266443 -65.726027) (xy 65.29911 -65.769655)
			(xy 65.325236 -65.817488) (xy 65.344288 -65.868552) (xy 65.355878 -65.921809) (xy 65.35977 -65.976172)
			(xy 66.06353 -65.976172) (xy 66.067421 -65.921825) (xy 66.079007 -65.868585) (xy 66.098052 -65.817536)
			(xy 66.124169 -65.769716) (xy 66.156826 -65.726101) (xy 66.195357 -65.687577) (xy 66.238979 -65.654929)
			(xy 66.286803 -65.628822) (xy 66.337856 -65.609786) (xy 66.391099 -65.59821) (xy 66.445447 -65.59433)
			(xy 66.499794 -65.598224) (xy 66.553033 -65.609812) (xy 66.604082 -65.62886) (xy 66.6519 -65.654979)
			(xy 66.673984 -65.670938) (xy 66.692996 -65.684534) (xy 66.734879 -65.705266) (xy 66.779847 -65.717992)
			(xy 66.826384 -65.722282) (xy 66.872921 -65.717992) (xy 66.917889 -65.705266) (xy 66.959772 -65.684534)
			(xy 66.978784 -65.670938) (xy 67.000829 -65.654915) (xy 67.048659 -65.628785) (xy 67.09972 -65.609729)
			(xy 67.152974 -65.598135) (xy 67.207335 -65.594237) (xy 67.261698 -65.598116) (xy 67.314956 -65.609693)
			(xy 67.366023 -65.628732) (xy 67.413862 -65.654845) (xy 67.457496 -65.6875) (xy 67.496039 -65.726034)
			(xy 67.528705 -65.769661) (xy 67.55483 -65.817493) (xy 67.573881 -65.868556) (xy 67.585471 -65.92181)
			(xy 67.589363 -65.976172) (xy 67.585479 -66.030535) (xy 67.573897 -66.083791) (xy 67.554853 -66.134857)
			(xy 67.528735 -66.182693) (xy 67.496075 -66.226324) (xy 67.457538 -66.264864) (xy 67.413908 -66.297526)
			(xy 67.366074 -66.323645) (xy 67.315009 -66.342692) (xy 67.261753 -66.354276) (xy 67.20739 -66.358163)
			(xy 67.153028 -66.354273) (xy 67.099773 -66.342686) (xy 67.048709 -66.323638) (xy 67.000876 -66.297515)
			(xy 66.978784 -66.281554) (xy 66.959772 -66.267958) (xy 66.917889 -66.247226) (xy 66.872921 -66.2345)
			(xy 66.826384 -66.23021) (xy 66.779847 -66.2345) (xy 66.734879 -66.247226) (xy 66.692996 -66.267958)
			(xy 66.673984 -66.281554) (xy 66.651853 -66.297451) (xy 66.604031 -66.323563) (xy 66.55298 -66.342603)
			(xy 66.499739 -66.354184) (xy 66.445391 -66.35807) (xy 66.391044 -66.354182) (xy 66.337803 -66.342598)
			(xy 66.286753 -66.323556) (xy 66.238932 -66.297441) (xy 66.195315 -66.264787) (xy 66.156789 -66.226257)
			(xy 66.124139 -66.182637) (xy 66.098029 -66.134814) (xy 66.078992 -66.083762) (xy 66.067413 -66.03052)
			(xy 66.06353 -65.976172) (xy 65.35977 -65.976172) (xy 65.355886 -66.030537) (xy 65.344303 -66.083795)
			(xy 65.325259 -66.134862) (xy 65.29914 -66.182699) (xy 65.266479 -66.226331) (xy 65.22794 -66.264871)
			(xy 65.184308 -66.297534) (xy 65.136472 -66.323654) (xy 65.085405 -66.3427) (xy 65.032148 -66.354284)
			(xy 64.977784 -66.35817) (xy 64.92342 -66.354279) (xy 64.870163 -66.342691) (xy 64.819098 -66.32364)
			(xy 64.771264 -66.297516) (xy 64.749172 -66.281554) (xy 64.73016 -66.267958) (xy 64.688277 -66.247226)
			(xy 64.643309 -66.2345) (xy 64.596772 -66.23021) (xy 64.550235 -66.2345) (xy 64.505267 -66.247226)
			(xy 64.463384 -66.267958) (xy 64.444372 -66.281554) (xy 64.422241 -66.29745) (xy 64.374421 -66.32356)
			(xy 64.32337 -66.342599) (xy 64.270131 -66.354178) (xy 64.215785 -66.358063) (xy 64.161439 -66.354174)
			(xy 64.1082 -66.34259) (xy 64.057151 -66.323547) (xy 64.009333 -66.297433) (xy 63.965717 -66.264779)
			(xy 63.927193 -66.22625) (xy 63.894544 -66.182631) (xy 63.868435 -66.134809) (xy 63.849398 -66.083759)
			(xy 63.83782 -66.030519) (xy 63.833937 -65.976172) (xy 36.37736 -65.976172) (xy 36.361593 -66.007836)
			(xy 36.315846 -66.08172) (xy 36.263477 -66.151067) (xy 36.204933 -66.215287) (xy 36.140713 -66.273831)
			(xy 36.071366 -66.3262) (xy 35.997482 -66.371947) (xy 35.919693 -66.410681) (xy 35.838661 -66.442073)
			(xy 35.755079 -66.465854) (xy 35.669659 -66.481822) (xy 35.58313 -66.48984) (xy 35.49623 -66.48984)
			(xy 35.409701 -66.481822) (xy 35.324281 -66.465854) (xy 35.240699 -66.442073) (xy 35.159667 -66.410681)
			(xy 35.081878 -66.371947) (xy 35.007994 -66.3262) (xy 34.938647 -66.273831) (xy 34.874427 -66.215287)
			(xy 34.815883 -66.151067) (xy 34.763514 -66.08172) (xy 34.717767 -66.007836) (xy 34.679033 -65.930047)
			(xy 34.647641 -65.849015) (xy 34.62386 -65.765433) (xy 34.607892 -65.680013) (xy 34.599874 -65.593484)
			(xy 31.399486 -65.593484) (xy 31.391468 -65.680013) (xy 31.3755 -65.765433) (xy 31.351719 -65.849015)
			(xy 31.320327 -65.930047) (xy 31.281593 -66.007836) (xy 31.235846 -66.08172) (xy 31.183477 -66.151067)
			(xy 31.124933 -66.215287) (xy 31.060713 -66.273831) (xy 30.991366 -66.3262) (xy 30.917482 -66.371947)
			(xy 30.839693 -66.410681) (xy 30.758661 -66.442073) (xy 30.675079 -66.465854) (xy 30.589659 -66.481822)
			(xy 30.50313 -66.48984) (xy 30.41623 -66.48984) (xy 30.329701 -66.481822) (xy 30.244281 -66.465854)
			(xy 30.160699 -66.442073) (xy 30.079667 -66.410681) (xy 30.001878 -66.371947) (xy 29.927994 -66.3262)
			(xy 29.858647 -66.273831) (xy 29.794427 -66.215287) (xy 29.735883 -66.151067) (xy 29.683514 -66.08172)
			(xy 29.637767 -66.007836) (xy 29.599033 -65.930047) (xy 29.567641 -65.849015) (xy 29.54386 -65.765433)
			(xy 29.527892 -65.680013) (xy 29.519874 -65.593484) (xy 29.170884 -65.593484) (xy 29.170884 -68.133484)
			(xy 29.519874 -68.133484) (xy 29.519874 -68.046584) (xy 29.527892 -67.960055) (xy 29.54386 -67.874635)
			(xy 29.567641 -67.791053) (xy 29.599033 -67.710021) (xy 29.637767 -67.632232) (xy 29.683514 -67.558348)
			(xy 29.735883 -67.489001) (xy 29.794427 -67.424781) (xy 29.858647 -67.366237) (xy 29.927994 -67.313868)
			(xy 30.001878 -67.268121) (xy 30.079667 -67.229387) (xy 30.160699 -67.197995) (xy 30.244281 -67.174214)
			(xy 30.329701 -67.158246) (xy 30.41623 -67.150228) (xy 30.50313 -67.150228) (xy 30.589659 -67.158246)
			(xy 30.675079 -67.174214) (xy 30.758661 -67.197995) (xy 30.839693 -67.229387) (xy 30.917482 -67.268121)
			(xy 30.991366 -67.313868) (xy 31.060713 -67.366237) (xy 31.124933 -67.424781) (xy 31.183477 -67.489001)
			(xy 31.235846 -67.558348) (xy 31.281593 -67.632232) (xy 31.320327 -67.710021) (xy 31.351719 -67.791053)
			(xy 31.3755 -67.874635) (xy 31.391468 -67.960055) (xy 31.399486 -68.046584) (xy 31.399988 -68.090034)
			(xy 31.399486 -68.133484) (xy 34.599874 -68.133484) (xy 34.599874 -68.046584) (xy 34.607892 -67.960055)
			(xy 34.62386 -67.874635) (xy 34.647641 -67.791053) (xy 34.679033 -67.710021) (xy 34.717767 -67.632232)
			(xy 34.763514 -67.558348) (xy 34.815883 -67.489001) (xy 34.874427 -67.424781) (xy 34.938647 -67.366237)
			(xy 35.007994 -67.313868) (xy 35.081878 -67.268121) (xy 35.159667 -67.229387) (xy 35.240699 -67.197995)
			(xy 35.324281 -67.174214) (xy 35.409701 -67.158246) (xy 35.49623 -67.150228) (xy 35.58313 -67.150228)
			(xy 35.669659 -67.158246) (xy 35.755079 -67.174214) (xy 35.838661 -67.197995) (xy 35.919693 -67.229387)
			(xy 35.997482 -67.268121) (xy 36.071366 -67.313868) (xy 36.140713 -67.366237) (xy 36.204933 -67.424781)
			(xy 36.263477 -67.489001) (xy 36.278512 -67.508911) (xy 41.775639 -67.508911) (xy 41.779526 -67.454547)
			(xy 41.791111 -67.40129) (xy 41.810158 -67.350224) (xy 41.836279 -67.302388) (xy 41.868943 -67.258758)
			(xy 41.907484 -67.22022) (xy 41.951117 -67.18756) (xy 41.998955 -67.161444) (xy 42.050023 -67.142401)
			(xy 42.103281 -67.130821) (xy 42.157646 -67.126939) (xy 42.212009 -67.130834) (xy 42.265265 -67.142427)
			(xy 42.316328 -67.161482) (xy 42.364159 -67.18761) (xy 42.38625 -67.203574) (xy 42.405262 -67.21717)
			(xy 42.447145 -67.237902) (xy 42.492113 -67.250628) (xy 42.53865 -67.254918) (xy 42.585187 -67.250628)
			(xy 42.630155 -67.237902) (xy 42.672038 -67.21717) (xy 42.69105 -67.203574) (xy 42.713156 -67.187634)
			(xy 42.760984 -67.161508) (xy 42.812044 -67.142455) (xy 42.865295 -67.130863) (xy 42.919654 -67.126968)
			(xy 42.974014 -67.13085) (xy 43.027269 -67.142429) (xy 43.078333 -67.16147) (xy 43.126167 -67.187585)
			(xy 43.169797 -67.220242) (xy 43.208335 -67.258776) (xy 43.240996 -67.302404) (xy 43.267116 -67.350235)
			(xy 43.286161 -67.401298) (xy 43.297745 -67.454551) (xy 43.301632 -67.508911) (xy 43.297742 -67.56327)
			(xy 43.286155 -67.616523) (xy 43.267107 -67.667584) (xy 43.240985 -67.715414) (xy 43.208321 -67.75904)
			(xy 43.169781 -67.797572) (xy 43.126149 -67.830227) (xy 43.078313 -67.856339) (xy 43.027248 -67.875377)
			(xy 42.973993 -67.886953) (xy 42.919633 -67.890832) (xy 42.865274 -67.886934) (xy 42.812023 -67.875339)
			(xy 42.760964 -67.856283) (xy 42.713138 -67.830154) (xy 42.69105 -67.81419) (xy 42.672038 -67.800594)
			(xy 42.630155 -67.779862) (xy 42.585187 -67.767136) (xy 42.53865 -67.762846) (xy 42.492113 -67.767136)
			(xy 42.447145 -67.779862) (xy 42.405262 -67.800594) (xy 42.38625 -67.81419) (xy 42.364178 -67.830178)
			(xy 42.316348 -67.856309) (xy 42.265285 -67.875367) (xy 42.21203 -67.886963) (xy 42.157667 -67.890861)
			(xy 42.103303 -67.886982) (xy 42.050044 -67.875405) (xy 41.998975 -67.856365) (xy 41.951136 -67.830251)
			(xy 41.9075 -67.797594) (xy 41.868957 -67.759059) (xy 41.836291 -67.71543) (xy 41.810167 -67.667596)
			(xy 41.791117 -67.616531) (xy 41.779529 -67.563274) (xy 41.775639 -67.508911) (xy 36.278512 -67.508911)
			(xy 36.315846 -67.558348) (xy 36.361593 -67.632232) (xy 36.400327 -67.710021) (xy 36.431719 -67.791053)
			(xy 36.4555 -67.874635) (xy 36.471468 -67.960055) (xy 36.479486 -68.046584) (xy 36.479988 -68.090034)
			(xy 36.479644 -68.119829) (xy 63.833862 -68.119829) (xy 63.837745 -68.065472) (xy 63.849326 -68.012221)
			(xy 63.868366 -67.96116) (xy 63.89448 -67.913329) (xy 63.927135 -67.869701) (xy 63.965667 -67.831165)
			(xy 64.009291 -67.798505) (xy 64.057119 -67.772385) (xy 64.108177 -67.753338) (xy 64.161427 -67.741752)
			(xy 64.215783 -67.737862) (xy 64.27014 -67.741747) (xy 64.323391 -67.753329) (xy 64.374451 -67.772371)
			(xy 64.422281 -67.798487) (xy 64.444372 -67.814444) (xy 64.463384 -67.82804) (xy 64.505267 -67.848772)
			(xy 64.550235 -67.861498) (xy 64.596772 -67.865788) (xy 64.643309 -67.861498) (xy 64.688277 -67.848772)
			(xy 64.73016 -67.82804) (xy 64.749172 -67.814444) (xy 64.771306 -67.798546) (xy 64.81913 -67.772427)
			(xy 64.870186 -67.753381) (xy 64.923432 -67.741795) (xy 64.977785 -67.737905) (xy 65.032138 -67.741791)
			(xy 65.085385 -67.753373) (xy 65.136442 -67.772415) (xy 65.184269 -67.79853) (xy 65.227892 -67.831186)
			(xy 65.266423 -67.869719) (xy 65.299077 -67.913343) (xy 65.325191 -67.96117) (xy 65.344231 -68.012228)
			(xy 65.355811 -68.065475) (xy 65.359695 -68.119829) (xy 66.063455 -68.119829) (xy 66.067338 -68.06547)
			(xy 66.078919 -68.012218) (xy 66.09796 -67.961156) (xy 66.124075 -67.913323) (xy 66.156732 -67.869694)
			(xy 66.195265 -67.831157) (xy 66.238891 -67.798496) (xy 66.28672 -67.772377) (xy 66.337781 -67.75333)
			(xy 66.391032 -67.741744) (xy 66.44539 -67.737855) (xy 66.499748 -67.741741) (xy 66.553 -67.753324)
			(xy 66.604062 -67.772368) (xy 66.651893 -67.798486) (xy 66.673984 -67.814444) (xy 66.692996 -67.82804)
			(xy 66.734879 -67.848772) (xy 66.779847 -67.861498) (xy 66.826384 -67.865788) (xy 66.872921 -67.861498)
			(xy 66.917889 -67.848772) (xy 66.959772 -67.82804) (xy 66.978784 -67.814444) (xy 67.000918 -67.798547)
			(xy 67.048741 -67.77243) (xy 67.099795 -67.753386) (xy 67.15304 -67.741801) (xy 67.207392 -67.737912)
			(xy 67.261743 -67.741799) (xy 67.314989 -67.753381) (xy 67.366044 -67.772423) (xy 67.413868 -67.798538)
			(xy 67.45749 -67.831194) (xy 67.496019 -67.869726) (xy 67.528673 -67.913349) (xy 67.554785 -67.961175)
			(xy 67.573825 -68.012231) (xy 67.585404 -68.065477) (xy 67.589288 -68.119829) (xy 67.585396 -68.17418)
			(xy 67.573809 -68.227424) (xy 67.554761 -68.278477) (xy 67.528641 -68.3263) (xy 67.495982 -68.369918)
			(xy 67.457446 -68.408444) (xy 67.41382 -68.441093) (xy 67.365991 -68.4672) (xy 67.314933 -68.486235)
			(xy 67.261686 -68.49781) (xy 67.207334 -68.501688) (xy 67.152983 -68.497791) (xy 67.09974 -68.486198)
			(xy 67.048689 -68.467146) (xy 67.000869 -68.441021) (xy 66.978784 -68.42506) (xy 66.959772 -68.411464)
			(xy 66.917889 -68.390732) (xy 66.872921 -68.378006) (xy 66.826384 -68.373716) (xy 66.779847 -68.378006)
			(xy 66.734879 -68.390732) (xy 66.692996 -68.411464) (xy 66.673984 -68.42506) (xy 66.651941 -68.441083)
			(xy 66.604114 -68.467208) (xy 66.553056 -68.486259) (xy 66.499805 -68.497851) (xy 66.445448 -68.501745)
			(xy 66.391089 -68.497864) (xy 66.337836 -68.486286) (xy 66.286773 -68.467247) (xy 66.238939 -68.441135)
			(xy 66.195309 -68.408481) (xy 66.156769 -68.369949) (xy 66.124106 -68.326325) (xy 66.097984 -68.278497)
			(xy 66.078935 -68.227437) (xy 66.067347 -68.174187) (xy 66.063455 -68.119829) (xy 65.359695 -68.119829)
			(xy 65.355803 -68.174182) (xy 65.344215 -68.227428) (xy 65.325167 -68.278482) (xy 65.299046 -68.326306)
			(xy 65.266385 -68.369925) (xy 65.227848 -68.408451) (xy 65.18422 -68.441101) (xy 65.13639 -68.467209)
			(xy 65.08533 -68.486244) (xy 65.032081 -68.497818) (xy 64.977727 -68.501695) (xy 64.923375 -68.497797)
			(xy 64.87013 -68.486203) (xy 64.819078 -68.467149) (xy 64.771257 -68.441022) (xy 64.749172 -68.42506)
			(xy 64.73016 -68.411464) (xy 64.688277 -68.390732) (xy 64.643309 -68.378006) (xy 64.596772 -68.373716)
			(xy 64.550235 -68.378006) (xy 64.505267 -68.390732) (xy 64.463384 -68.411464) (xy 64.444372 -68.42506)
			(xy 64.422329 -68.441082) (xy 64.374503 -68.467205) (xy 64.323446 -68.486255) (xy 64.270197 -68.497845)
			(xy 64.215841 -68.501738) (xy 64.161484 -68.497856) (xy 64.108233 -68.486278) (xy 64.057171 -68.467239)
			(xy 64.009339 -68.441127) (xy 63.96571 -68.408473) (xy 63.927173 -68.369942) (xy 63.894511 -68.326319)
			(xy 63.86839 -68.278492) (xy 63.849342 -68.227434) (xy 63.837754 -68.174185) (xy 63.833862 -68.119829)
			(xy 36.479644 -68.119829) (xy 36.479486 -68.133484) (xy 36.471468 -68.220013) (xy 36.4555 -68.305433)
			(xy 36.431719 -68.389015) (xy 36.400327 -68.470047) (xy 36.361593 -68.547836) (xy 36.315846 -68.62172)
			(xy 36.263477 -68.691067) (xy 36.204933 -68.755287) (xy 36.140713 -68.813831) (xy 36.071366 -68.8662)
			(xy 35.997482 -68.911947) (xy 35.919693 -68.950681) (xy 35.838661 -68.982073) (xy 35.755079 -69.005854)
			(xy 35.669659 -69.021822) (xy 35.58313 -69.02984) (xy 35.49623 -69.02984) (xy 35.409701 -69.021822)
			(xy 35.324281 -69.005854) (xy 35.240699 -68.982073) (xy 35.159667 -68.950681) (xy 35.081878 -68.911947)
			(xy 35.007994 -68.8662) (xy 34.938647 -68.813831) (xy 34.874427 -68.755287) (xy 34.815883 -68.691067)
			(xy 34.763514 -68.62172) (xy 34.717767 -68.547836) (xy 34.679033 -68.470047) (xy 34.647641 -68.389015)
			(xy 34.62386 -68.305433) (xy 34.607892 -68.220013) (xy 34.599874 -68.133484) (xy 31.399486 -68.133484)
			(xy 31.391468 -68.220013) (xy 31.3755 -68.305433) (xy 31.351719 -68.389015) (xy 31.320327 -68.470047)
			(xy 31.281593 -68.547836) (xy 31.235846 -68.62172) (xy 31.183477 -68.691067) (xy 31.124933 -68.755287)
			(xy 31.060713 -68.813831) (xy 30.991366 -68.8662) (xy 30.917482 -68.911947) (xy 30.839693 -68.950681)
			(xy 30.758661 -68.982073) (xy 30.675079 -69.005854) (xy 30.589659 -69.021822) (xy 30.50313 -69.02984)
			(xy 30.41623 -69.02984) (xy 30.329701 -69.021822) (xy 30.244281 -69.005854) (xy 30.160699 -68.982073)
			(xy 30.079667 -68.950681) (xy 30.001878 -68.911947) (xy 29.927994 -68.8662) (xy 29.858647 -68.813831)
			(xy 29.794427 -68.755287) (xy 29.735883 -68.691067) (xy 29.683514 -68.62172) (xy 29.637767 -68.547836)
			(xy 29.599033 -68.470047) (xy 29.567641 -68.389015) (xy 29.54386 -68.305433) (xy 29.527892 -68.220013)
			(xy 29.519874 -68.133484) (xy 29.170884 -68.133484) (xy 29.170884 -70.673484) (xy 29.519874 -70.673484)
			(xy 29.519874 -70.586584) (xy 29.527892 -70.500055) (xy 29.54386 -70.414635) (xy 29.567641 -70.331053)
			(xy 29.599033 -70.250021) (xy 29.637767 -70.172232) (xy 29.683514 -70.098348) (xy 29.735883 -70.029001)
			(xy 29.794427 -69.964781) (xy 29.858647 -69.906237) (xy 29.927994 -69.853868) (xy 30.001878 -69.808121)
			(xy 30.079667 -69.769387) (xy 30.160699 -69.737995) (xy 30.244281 -69.714214) (xy 30.329701 -69.698246)
			(xy 30.41623 -69.690228) (xy 30.50313 -69.690228) (xy 30.589659 -69.698246) (xy 30.675079 -69.714214)
			(xy 30.758661 -69.737995) (xy 30.839693 -69.769387) (xy 30.917482 -69.808121) (xy 30.991366 -69.853868)
			(xy 31.060713 -69.906237) (xy 31.124933 -69.964781) (xy 31.183477 -70.029001) (xy 31.235846 -70.098348)
			(xy 31.281593 -70.172232) (xy 31.320327 -70.250021) (xy 31.351719 -70.331053) (xy 31.3755 -70.414635)
			(xy 31.391468 -70.500055) (xy 31.399486 -70.586584) (xy 31.399988 -70.630034) (xy 31.399486 -70.673484)
			(xy 34.599874 -70.673484) (xy 34.599874 -70.586584) (xy 34.607892 -70.500055) (xy 34.62386 -70.414635)
			(xy 34.647641 -70.331053) (xy 34.679033 -70.250021) (xy 34.717767 -70.172232) (xy 34.763514 -70.098348)
			(xy 34.815883 -70.029001) (xy 34.874427 -69.964781) (xy 34.938647 -69.906237) (xy 35.007994 -69.853868)
			(xy 35.081878 -69.808121) (xy 35.159667 -69.769387) (xy 35.240699 -69.737995) (xy 35.324281 -69.714214)
			(xy 35.409701 -69.698246) (xy 35.49623 -69.690228) (xy 35.58313 -69.690228) (xy 35.669659 -69.698246)
			(xy 35.755079 -69.714214) (xy 35.838661 -69.737995) (xy 35.919693 -69.769387) (xy 35.997482 -69.808121)
			(xy 36.071366 -69.853868) (xy 36.140713 -69.906237) (xy 36.204933 -69.964781) (xy 36.263477 -70.029001)
			(xy 36.315846 -70.098348) (xy 36.361593 -70.172232) (xy 36.365314 -70.179705) (xy 41.775647 -70.179705)
			(xy 41.779535 -70.125342) (xy 41.79112 -70.072086) (xy 41.810168 -70.021021) (xy 41.836289 -69.973187)
			(xy 41.868953 -69.929558) (xy 41.907494 -69.891022) (xy 41.951127 -69.858364) (xy 41.998964 -69.832248)
			(xy 42.050031 -69.813207) (xy 42.103289 -69.801628) (xy 42.157652 -69.797747) (xy 42.212014 -69.801643)
			(xy 42.265268 -69.813236) (xy 42.31633 -69.832291) (xy 42.36416 -69.85842) (xy 42.38625 -69.874384)
			(xy 42.405262 -69.88798) (xy 42.447145 -69.908712) (xy 42.492113 -69.921438) (xy 42.53865 -69.925728)
			(xy 42.585187 -69.921438) (xy 42.630155 -69.908712) (xy 42.672038 -69.88798) (xy 42.69105 -69.874384)
			(xy 42.713147 -69.858431) (xy 42.760975 -69.832303) (xy 42.812036 -69.813249) (xy 42.865288 -69.801656)
			(xy 42.919648 -69.79776) (xy 42.97401 -69.801641) (xy 43.027265 -69.81322) (xy 43.078331 -69.83226)
			(xy 43.126166 -69.858375) (xy 43.169798 -69.891032) (xy 43.208337 -69.929567) (xy 43.241 -69.973194)
			(xy 43.267121 -70.021027) (xy 43.286167 -70.07209) (xy 43.297752 -70.125344) (xy 43.30164 -70.179705)
			(xy 43.297751 -70.234066) (xy 43.286165 -70.287319) (xy 43.267117 -70.338382) (xy 43.240995 -70.386214)
			(xy 43.208331 -70.429841) (xy 43.169791 -70.468374) (xy 43.126158 -70.50103) (xy 43.078322 -70.527144)
			(xy 43.027256 -70.546183) (xy 42.974 -70.55776) (xy 42.919639 -70.56164) (xy 42.865279 -70.557743)
			(xy 42.812026 -70.546149) (xy 42.760967 -70.527093) (xy 42.713139 -70.500964) (xy 42.69105 -70.485)
			(xy 42.672038 -70.471404) (xy 42.630155 -70.450672) (xy 42.585187 -70.437946) (xy 42.53865 -70.433656)
			(xy 42.492113 -70.437946) (xy 42.447145 -70.450672) (xy 42.405262 -70.471404) (xy 42.38625 -70.485)
			(xy 42.364168 -70.500975) (xy 42.316339 -70.527105) (xy 42.265277 -70.546161) (xy 42.212023 -70.557756)
			(xy 42.157661 -70.561653) (xy 42.103298 -70.557773) (xy 42.05004 -70.546195) (xy 41.998973 -70.527156)
			(xy 41.951135 -70.501041) (xy 41.907501 -70.468384) (xy 41.868959 -70.429849) (xy 41.836294 -70.386221)
			(xy 41.810172 -70.338387) (xy 41.791123 -70.287323) (xy 41.779536 -70.234067) (xy 41.775647 -70.179705)
			(xy 36.365314 -70.179705) (xy 36.400327 -70.250021) (xy 36.431719 -70.331053) (xy 36.4555 -70.414635)
			(xy 36.471468 -70.500055) (xy 36.479486 -70.586584) (xy 36.479988 -70.630034) (xy 36.479486 -70.673484)
			(xy 36.471468 -70.760013) (xy 36.4555 -70.845433) (xy 36.431719 -70.929015) (xy 36.400327 -71.010047)
			(xy 36.361593 -71.087836) (xy 36.315846 -71.16172) (xy 36.263477 -71.231067) (xy 36.204933 -71.295287)
			(xy 36.140713 -71.353831) (xy 36.071366 -71.4062) (xy 35.997482 -71.451947) (xy 35.919693 -71.490681)
			(xy 35.838661 -71.522073) (xy 35.755079 -71.545854) (xy 35.669659 -71.561822) (xy 35.58313 -71.56984)
			(xy 35.49623 -71.56984) (xy 35.409701 -71.561822) (xy 35.324281 -71.545854) (xy 35.240699 -71.522073)
			(xy 35.159667 -71.490681) (xy 35.081878 -71.451947) (xy 35.007994 -71.4062) (xy 34.938647 -71.353831)
			(xy 34.874427 -71.295287) (xy 34.815883 -71.231067) (xy 34.763514 -71.16172) (xy 34.717767 -71.087836)
			(xy 34.679033 -71.010047) (xy 34.647641 -70.929015) (xy 34.62386 -70.845433) (xy 34.607892 -70.760013)
			(xy 34.599874 -70.673484) (xy 31.399486 -70.673484) (xy 31.391468 -70.760013) (xy 31.3755 -70.845433)
			(xy 31.351719 -70.929015) (xy 31.320327 -71.010047) (xy 31.281593 -71.087836) (xy 31.235846 -71.16172)
			(xy 31.183477 -71.231067) (xy 31.124933 -71.295287) (xy 31.060713 -71.353831) (xy 30.991366 -71.4062)
			(xy 30.917482 -71.451947) (xy 30.839693 -71.490681) (xy 30.758661 -71.522073) (xy 30.675079 -71.545854)
			(xy 30.589659 -71.561822) (xy 30.50313 -71.56984) (xy 30.41623 -71.56984) (xy 30.329701 -71.561822)
			(xy 30.244281 -71.545854) (xy 30.160699 -71.522073) (xy 30.079667 -71.490681) (xy 30.001878 -71.451947)
			(xy 29.927994 -71.4062) (xy 29.858647 -71.353831) (xy 29.794427 -71.295287) (xy 29.735883 -71.231067)
			(xy 29.683514 -71.16172) (xy 29.637767 -71.087836) (xy 29.599033 -71.010047) (xy 29.567641 -70.929015)
			(xy 29.54386 -70.845433) (xy 29.527892 -70.760013) (xy 29.519874 -70.673484) (xy 29.170884 -70.673484)
			(xy 29.170884 -73.213484) (xy 29.519874 -73.213484) (xy 29.519874 -73.126584) (xy 29.527892 -73.040055)
			(xy 29.54386 -72.954635) (xy 29.567641 -72.871053) (xy 29.599033 -72.790021) (xy 29.637767 -72.712232)
			(xy 29.683514 -72.638348) (xy 29.735883 -72.569001) (xy 29.794427 -72.504781) (xy 29.858647 -72.446237)
			(xy 29.927994 -72.393868) (xy 30.001878 -72.348121) (xy 30.079667 -72.309387) (xy 30.160699 -72.277995)
			(xy 30.244281 -72.254214) (xy 30.329701 -72.238246) (xy 30.41623 -72.230228) (xy 30.50313 -72.230228)
			(xy 30.589659 -72.238246) (xy 30.675079 -72.254214) (xy 30.758661 -72.277995) (xy 30.839693 -72.309387)
			(xy 30.917482 -72.348121) (xy 30.991366 -72.393868) (xy 31.060713 -72.446237) (xy 31.124933 -72.504781)
			(xy 31.183477 -72.569001) (xy 31.235846 -72.638348) (xy 31.281593 -72.712232) (xy 31.320327 -72.790021)
			(xy 31.351719 -72.871053) (xy 31.3755 -72.954635) (xy 31.391468 -73.040055) (xy 31.399486 -73.126584)
			(xy 31.399988 -73.170034) (xy 31.399486 -73.213484) (xy 34.599874 -73.213484) (xy 34.599874 -73.126584)
			(xy 34.607892 -73.040055) (xy 34.62386 -72.954635) (xy 34.647641 -72.871053) (xy 34.679033 -72.790021)
			(xy 34.717767 -72.712232) (xy 34.763514 -72.638348) (xy 34.815883 -72.569001) (xy 34.874427 -72.504781)
			(xy 34.938647 -72.446237) (xy 35.007994 -72.393868) (xy 35.081878 -72.348121) (xy 35.159667 -72.309387)
			(xy 35.240699 -72.277995) (xy 35.324281 -72.254214) (xy 35.409701 -72.238246) (xy 35.49623 -72.230228)
			(xy 35.58313 -72.230228) (xy 35.669659 -72.238246) (xy 35.755079 -72.254214) (xy 35.838661 -72.277995)
			(xy 35.919693 -72.309387) (xy 35.997482 -72.348121) (xy 36.071366 -72.393868) (xy 36.140713 -72.446237)
			(xy 36.204933 -72.504781) (xy 36.263477 -72.569001) (xy 36.315846 -72.638348) (xy 36.361593 -72.712232)
			(xy 36.400327 -72.790021) (xy 36.422797 -72.848023) (xy 41.775623 -72.848023) (xy 41.779509 -72.793657)
			(xy 41.791092 -72.740397) (xy 41.810139 -72.689328) (xy 41.836259 -72.64149) (xy 41.868923 -72.597856)
			(xy 41.907464 -72.559316) (xy 41.951099 -72.526653) (xy 41.998938 -72.500534) (xy 42.050007 -72.481489)
			(xy 42.103267 -72.469907) (xy 42.157634 -72.466023) (xy 42.211999 -72.469917) (xy 42.265258 -72.481508)
			(xy 42.316324 -72.500562) (xy 42.364158 -72.52669) (xy 42.38625 -72.542654) (xy 42.405262 -72.55625)
			(xy 42.447145 -72.576982) (xy 42.492113 -72.589708) (xy 42.53865 -72.593998) (xy 42.585187 -72.589708)
			(xy 42.630155 -72.576982) (xy 42.672038 -72.55625) (xy 42.69105 -72.542654) (xy 42.713175 -72.526741)
			(xy 42.761002 -72.500617) (xy 42.81206 -72.481567) (xy 42.865309 -72.469977) (xy 42.919666 -72.466084)
			(xy 42.974024 -72.469967) (xy 43.027276 -72.481548) (xy 43.078337 -72.500589) (xy 43.126168 -72.526705)
			(xy 43.169796 -72.559362) (xy 43.208331 -72.597896) (xy 43.240989 -72.641522) (xy 43.267106 -72.689353)
			(xy 43.286149 -72.740414) (xy 43.297731 -72.793665) (xy 43.301616 -72.848023) (xy 43.297725 -72.90238)
			(xy 43.286136 -72.95563) (xy 43.267087 -73.006688) (xy 43.240965 -73.054516) (xy 43.208301 -73.098138)
			(xy 43.169761 -73.136668) (xy 43.12613 -73.16932) (xy 43.078296 -73.19543) (xy 43.027232 -73.214465)
			(xy 42.973979 -73.226039) (xy 42.919621 -73.229916) (xy 42.865264 -73.226017) (xy 42.812016 -73.214421)
			(xy 42.76096 -73.195364) (xy 42.713137 -73.169234) (xy 42.69105 -73.15327) (xy 42.672038 -73.139674)
			(xy 42.630155 -73.118942) (xy 42.585187 -73.106216) (xy 42.53865 -73.101926) (xy 42.492113 -73.106216)
			(xy 42.447145 -73.118942) (xy 42.405262 -73.139674) (xy 42.38625 -73.15327) (xy 42.364196 -73.169285)
			(xy 42.316365 -73.195419) (xy 42.265301 -73.214479) (xy 42.212045 -73.226077) (xy 42.157679 -73.229977)
			(xy 42.103312 -73.226099) (xy 42.050051 -73.214524) (xy 41.998979 -73.195485) (xy 41.951137 -73.169371)
			(xy 41.907499 -73.136714) (xy 41.868953 -73.098178) (xy 41.836284 -73.054549) (xy 41.810157 -73.006714)
			(xy 41.791105 -72.955647) (xy 41.779515 -72.902389) (xy 41.775623 -72.848023) (xy 36.422797 -72.848023)
			(xy 36.431719 -72.871053) (xy 36.4555 -72.954635) (xy 36.471468 -73.040055) (xy 36.479486 -73.126584)
			(xy 36.479988 -73.170034) (xy 36.479486 -73.213484) (xy 36.471468 -73.300013) (xy 36.4555 -73.385433)
			(xy 36.431719 -73.469015) (xy 36.400327 -73.550047) (xy 36.361593 -73.627836) (xy 36.315846 -73.70172)
			(xy 36.263477 -73.771067) (xy 36.204933 -73.835287) (xy 36.140713 -73.893831) (xy 36.071366 -73.9462)
			(xy 35.997482 -73.991947) (xy 35.919693 -74.030681) (xy 35.838661 -74.062073) (xy 35.755079 -74.085854)
			(xy 35.669659 -74.101822) (xy 35.58313 -74.10984) (xy 35.49623 -74.10984) (xy 35.409701 -74.101822)
			(xy 35.324281 -74.085854) (xy 35.240699 -74.062073) (xy 35.159667 -74.030681) (xy 35.081878 -73.991947)
			(xy 35.007994 -73.9462) (xy 34.938647 -73.893831) (xy 34.874427 -73.835287) (xy 34.815883 -73.771067)
			(xy 34.763514 -73.70172) (xy 34.717767 -73.627836) (xy 34.679033 -73.550047) (xy 34.647641 -73.469015)
			(xy 34.62386 -73.385433) (xy 34.607892 -73.300013) (xy 34.599874 -73.213484) (xy 31.399486 -73.213484)
			(xy 31.391468 -73.300013) (xy 31.3755 -73.385433) (xy 31.351719 -73.469015) (xy 31.320327 -73.550047)
			(xy 31.281593 -73.627836) (xy 31.235846 -73.70172) (xy 31.183477 -73.771067) (xy 31.124933 -73.835287)
			(xy 31.060713 -73.893831) (xy 30.991366 -73.9462) (xy 30.917482 -73.991947) (xy 30.839693 -74.030681)
			(xy 30.758661 -74.062073) (xy 30.675079 -74.085854) (xy 30.589659 -74.101822) (xy 30.50313 -74.10984)
			(xy 30.41623 -74.10984) (xy 30.329701 -74.101822) (xy 30.244281 -74.085854) (xy 30.160699 -74.062073)
			(xy 30.079667 -74.030681) (xy 30.001878 -73.991947) (xy 29.927994 -73.9462) (xy 29.858647 -73.893831)
			(xy 29.794427 -73.835287) (xy 29.735883 -73.771067) (xy 29.683514 -73.70172) (xy 29.637767 -73.627836)
			(xy 29.599033 -73.550047) (xy 29.567641 -73.469015) (xy 29.54386 -73.385433) (xy 29.527892 -73.300013)
			(xy 29.519874 -73.213484) (xy 29.170884 -73.213484) (xy 29.170884 -75.753484) (xy 29.519874 -75.753484)
			(xy 29.519874 -75.666584) (xy 29.527892 -75.580055) (xy 29.54386 -75.494635) (xy 29.567641 -75.411053)
			(xy 29.599033 -75.330021) (xy 29.637767 -75.252232) (xy 29.683514 -75.178348) (xy 29.735883 -75.109001)
			(xy 29.794427 -75.044781) (xy 29.858647 -74.986237) (xy 29.927994 -74.933868) (xy 30.001878 -74.888121)
			(xy 30.079667 -74.849387) (xy 30.160699 -74.817995) (xy 30.244281 -74.794214) (xy 30.329701 -74.778246)
			(xy 30.41623 -74.770228) (xy 30.50313 -74.770228) (xy 30.589659 -74.778246) (xy 30.675079 -74.794214)
			(xy 30.758661 -74.817995) (xy 30.839693 -74.849387) (xy 30.917482 -74.888121) (xy 30.991366 -74.933868)
			(xy 31.060713 -74.986237) (xy 31.124933 -75.044781) (xy 31.183477 -75.109001) (xy 31.235846 -75.178348)
			(xy 31.281593 -75.252232) (xy 31.320327 -75.330021) (xy 31.351719 -75.411053) (xy 31.3755 -75.494635)
			(xy 31.391468 -75.580055) (xy 31.399486 -75.666584) (xy 31.399988 -75.710034) (xy 31.399486 -75.753484)
			(xy 34.599874 -75.753484) (xy 34.599874 -75.666584) (xy 34.607892 -75.580055) (xy 34.62386 -75.494635)
			(xy 34.647641 -75.411053) (xy 34.679033 -75.330021) (xy 34.717767 -75.252232) (xy 34.763514 -75.178348)
			(xy 34.815883 -75.109001) (xy 34.874427 -75.044781) (xy 34.938647 -74.986237) (xy 35.007994 -74.933868)
			(xy 35.081878 -74.888121) (xy 35.159667 -74.849387) (xy 35.240699 -74.817995) (xy 35.324281 -74.794214)
			(xy 35.409701 -74.778246) (xy 35.49623 -74.770228) (xy 35.58313 -74.770228) (xy 35.669659 -74.778246)
			(xy 35.755079 -74.794214) (xy 35.838661 -74.817995) (xy 35.919693 -74.849387) (xy 35.997482 -74.888121)
			(xy 36.071366 -74.933868) (xy 36.140713 -74.986237) (xy 36.204933 -75.044781) (xy 36.263477 -75.109001)
			(xy 36.315846 -75.178348) (xy 36.341403 -75.219624) (xy 41.775621 -75.219624) (xy 41.779507 -75.165257)
			(xy 41.79109 -75.111997) (xy 41.810137 -75.060928) (xy 41.836257 -75.01309) (xy 41.868921 -74.969456)
			(xy 41.907462 -74.930915) (xy 41.951097 -74.898253) (xy 41.998936 -74.872133) (xy 42.050006 -74.853088)
			(xy 42.103266 -74.841506) (xy 42.157632 -74.837621) (xy 42.211998 -74.841515) (xy 42.265257 -74.853106)
			(xy 42.316323 -74.87216) (xy 42.364158 -74.898288) (xy 42.38625 -74.914252) (xy 42.405262 -74.927848)
			(xy 42.447145 -74.94858) (xy 42.492113 -74.961306) (xy 42.53865 -74.965596) (xy 42.585187 -74.961306)
			(xy 42.630155 -74.94858) (xy 42.672038 -74.927848) (xy 42.69105 -74.914252) (xy 42.713177 -74.898342)
			(xy 42.761003 -74.872218) (xy 42.812061 -74.853168) (xy 42.865311 -74.841578) (xy 42.919668 -74.837686)
			(xy 42.974025 -74.841569) (xy 43.027276 -74.853149) (xy 43.078337 -74.872191) (xy 43.126169 -74.898307)
			(xy 43.169796 -74.930964) (xy 43.208331 -74.969498) (xy 43.240989 -75.013124) (xy 43.267105 -75.060955)
			(xy 43.286148 -75.112015) (xy 43.29773 -75.165267) (xy 43.301614 -75.219624) (xy 43.297723 -75.273981)
			(xy 43.286135 -75.327231) (xy 43.267085 -75.378289) (xy 43.240963 -75.426116) (xy 43.208299 -75.469738)
			(xy 43.169759 -75.508268) (xy 43.126128 -75.540919) (xy 43.078294 -75.567029) (xy 43.02723 -75.586064)
			(xy 42.973978 -75.597638) (xy 42.91962 -75.601514) (xy 42.865263 -75.597615) (xy 42.812015 -75.586019)
			(xy 42.76096 -75.566962) (xy 42.713136 -75.540832) (xy 42.69105 -75.524868) (xy 42.672038 -75.511272)
			(xy 42.630155 -75.49054) (xy 42.585187 -75.477814) (xy 42.53865 -75.473524) (xy 42.492113 -75.477814)
			(xy 42.447145 -75.49054) (xy 42.405262 -75.511272) (xy 42.38625 -75.524868) (xy 42.364198 -75.540886)
			(xy 42.316367 -75.56702) (xy 42.265303 -75.58608) (xy 42.212046 -75.597678) (xy 42.157681 -75.601579)
			(xy 42.103313 -75.597701) (xy 42.050052 -75.586125) (xy 41.99898 -75.567087) (xy 41.951137 -75.540973)
			(xy 41.907499 -75.508316) (xy 41.868952 -75.46978) (xy 41.836283 -75.426151) (xy 41.810157 -75.378315)
			(xy 41.791104 -75.327249) (xy 41.779514 -75.27399) (xy 41.775621 -75.219624) (xy 36.341403 -75.219624)
			(xy 36.361593 -75.252232) (xy 36.400327 -75.330021) (xy 36.431719 -75.411053) (xy 36.4555 -75.494635)
			(xy 36.471468 -75.580055) (xy 36.479486 -75.666584) (xy 36.479988 -75.710034) (xy 36.479486 -75.753484)
			(xy 36.471468 -75.840013) (xy 36.4555 -75.925433) (xy 36.431719 -76.009015) (xy 36.400327 -76.090047)
			(xy 36.361593 -76.167836) (xy 36.315846 -76.24172) (xy 36.263477 -76.311067) (xy 36.204933 -76.375287)
			(xy 36.140713 -76.433831) (xy 36.071366 -76.4862) (xy 35.997482 -76.531947) (xy 35.919693 -76.570681)
			(xy 35.838661 -76.602073) (xy 35.755079 -76.625854) (xy 35.669659 -76.641822) (xy 35.58313 -76.64984)
			(xy 35.49623 -76.64984) (xy 35.409701 -76.641822) (xy 35.324281 -76.625854) (xy 35.240699 -76.602073)
			(xy 35.159667 -76.570681) (xy 35.081878 -76.531947) (xy 35.007994 -76.4862) (xy 34.938647 -76.433831)
			(xy 34.874427 -76.375287) (xy 34.815883 -76.311067) (xy 34.763514 -76.24172) (xy 34.717767 -76.167836)
			(xy 34.679033 -76.090047) (xy 34.647641 -76.009015) (xy 34.62386 -75.925433) (xy 34.607892 -75.840013)
			(xy 34.599874 -75.753484) (xy 31.399486 -75.753484) (xy 31.391468 -75.840013) (xy 31.3755 -75.925433)
			(xy 31.351719 -76.009015) (xy 31.320327 -76.090047) (xy 31.281593 -76.167836) (xy 31.235846 -76.24172)
			(xy 31.183477 -76.311067) (xy 31.124933 -76.375287) (xy 31.060713 -76.433831) (xy 30.991366 -76.4862)
			(xy 30.917482 -76.531947) (xy 30.839693 -76.570681) (xy 30.758661 -76.602073) (xy 30.675079 -76.625854)
			(xy 30.589659 -76.641822) (xy 30.50313 -76.64984) (xy 30.41623 -76.64984) (xy 30.329701 -76.641822)
			(xy 30.244281 -76.625854) (xy 30.160699 -76.602073) (xy 30.079667 -76.570681) (xy 30.001878 -76.531947)
			(xy 29.927994 -76.4862) (xy 29.858647 -76.433831) (xy 29.794427 -76.375287) (xy 29.735883 -76.311067)
			(xy 29.683514 -76.24172) (xy 29.637767 -76.167836) (xy 29.599033 -76.090047) (xy 29.567641 -76.009015)
			(xy 29.54386 -75.925433) (xy 29.527892 -75.840013) (xy 29.519874 -75.753484) (xy 29.170884 -75.753484)
			(xy 29.170884 -77.182517) (xy 41.775631 -77.182517) (xy 41.779517 -77.128152) (xy 41.791102 -77.074893)
			(xy 41.810148 -77.023826) (xy 41.836269 -76.975989) (xy 41.868933 -76.932357) (xy 41.907474 -76.893818)
			(xy 41.951108 -76.861157) (xy 41.998946 -76.835039) (xy 42.050015 -76.815995) (xy 42.103274 -76.804414)
			(xy 42.15764 -76.800531) (xy 42.212004 -76.804425) (xy 42.265261 -76.816018) (xy 42.316326 -76.835072)
			(xy 42.364159 -76.8612) (xy 42.38625 -76.877164) (xy 42.405262 -76.89076) (xy 42.447145 -76.911492)
			(xy 42.492113 -76.924218) (xy 42.53865 -76.928508) (xy 42.585187 -76.924218) (xy 42.630155 -76.911492)
			(xy 42.672038 -76.89076) (xy 42.69105 -76.877164) (xy 42.713166 -76.861238) (xy 42.760993 -76.835113)
			(xy 42.812052 -76.816061) (xy 42.865302 -76.80447) (xy 42.91966 -76.800576) (xy 42.974019 -76.804458)
			(xy 43.027272 -76.816038) (xy 43.078335 -76.83508) (xy 43.126168 -76.861195) (xy 43.169797 -76.893852)
			(xy 43.208333 -76.932386) (xy 43.240993 -76.976013) (xy 43.267111 -77.023844) (xy 43.286155 -77.074906)
			(xy 43.297738 -77.128158) (xy 43.301624 -77.182517) (xy 43.297734 -77.236875) (xy 43.286146 -77.290126)
			(xy 43.267097 -77.341186) (xy 43.240975 -77.389015) (xy 43.208311 -77.432639) (xy 43.169771 -77.47117)
			(xy 43.126139 -77.503823) (xy 43.078304 -77.529934) (xy 43.02724 -77.548971) (xy 42.973986 -77.560546)
			(xy 42.919627 -77.564424) (xy 42.865269 -77.560525) (xy 42.812019 -77.54893) (xy 42.760962 -77.529874)
			(xy 42.713137 -77.503744) (xy 42.69105 -77.48778) (xy 42.672038 -77.474184) (xy 42.630155 -77.453452)
			(xy 42.585187 -77.440726) (xy 42.53865 -77.436436) (xy 42.492113 -77.440726) (xy 42.447145 -77.453452)
			(xy 42.405262 -77.474184) (xy 42.38625 -77.48778) (xy 42.364187 -77.503782) (xy 42.316356 -77.529914)
			(xy 42.265293 -77.548973) (xy 42.212037 -77.56057) (xy 42.157673 -77.564469) (xy 42.103308 -77.560591)
			(xy 42.050047 -77.549014) (xy 41.998977 -77.529975) (xy 41.951136 -77.503861) (xy 41.9075 -77.471204)
			(xy 41.868955 -77.432669) (xy 41.836288 -77.389039) (xy 41.810162 -77.341205) (xy 41.791111 -77.290139)
			(xy 41.779522 -77.236882) (xy 41.775631 -77.182517) (xy 29.170884 -77.182517) (xy 29.170884 -78.293484)
			(xy 29.519874 -78.293484) (xy 29.519874 -78.206584) (xy 29.527892 -78.120055) (xy 29.54386 -78.034635)
			(xy 29.567641 -77.951053) (xy 29.599033 -77.870021) (xy 29.637767 -77.792232) (xy 29.683514 -77.718348)
			(xy 29.735883 -77.649001) (xy 29.794427 -77.584781) (xy 29.858647 -77.526237) (xy 29.927994 -77.473868)
			(xy 30.001878 -77.428121) (xy 30.079667 -77.389387) (xy 30.160699 -77.357995) (xy 30.244281 -77.334214)
			(xy 30.329701 -77.318246) (xy 30.41623 -77.310228) (xy 30.50313 -77.310228) (xy 30.589659 -77.318246)
			(xy 30.675079 -77.334214) (xy 30.758661 -77.357995) (xy 30.839693 -77.389387) (xy 30.917482 -77.428121)
			(xy 30.991366 -77.473868) (xy 31.060713 -77.526237) (xy 31.124933 -77.584781) (xy 31.183477 -77.649001)
			(xy 31.235846 -77.718348) (xy 31.281593 -77.792232) (xy 31.320327 -77.870021) (xy 31.351719 -77.951053)
			(xy 31.3755 -78.034635) (xy 31.391468 -78.120055) (xy 31.399486 -78.206584) (xy 31.399988 -78.250034)
			(xy 31.399486 -78.293484) (xy 34.599874 -78.293484) (xy 34.599874 -78.206584) (xy 34.607892 -78.120055)
			(xy 34.62386 -78.034635) (xy 34.647641 -77.951053) (xy 34.679033 -77.870021) (xy 34.717767 -77.792232)
			(xy 34.763514 -77.718348) (xy 34.815883 -77.649001) (xy 34.874427 -77.584781) (xy 34.938647 -77.526237)
			(xy 35.007994 -77.473868) (xy 35.081878 -77.428121) (xy 35.159667 -77.389387) (xy 35.240699 -77.357995)
			(xy 35.324281 -77.334214) (xy 35.409701 -77.318246) (xy 35.49623 -77.310228) (xy 35.58313 -77.310228)
			(xy 35.669659 -77.318246) (xy 35.755079 -77.334214) (xy 35.838661 -77.357995) (xy 35.919693 -77.389387)
			(xy 35.997482 -77.428121) (xy 36.071366 -77.473868) (xy 36.140713 -77.526237) (xy 36.204933 -77.584781)
			(xy 36.263477 -77.649001) (xy 36.315846 -77.718348) (xy 36.361593 -77.792232) (xy 36.400327 -77.870021)
			(xy 36.431719 -77.951053) (xy 36.4555 -78.034635) (xy 36.471468 -78.120055) (xy 36.479486 -78.206584)
			(xy 36.479988 -78.250034) (xy 36.479486 -78.293484) (xy 36.478876 -78.300072) (xy 74.398638 -78.300072)
			(xy 74.402655 -78.130007) (xy 74.4147 -77.960322) (xy 74.434744 -77.791394) (xy 74.462744 -77.623602)
			(xy 74.498636 -77.457319) (xy 74.542341 -77.292917) (xy 74.593761 -77.130762) (xy 74.652781 -76.971216)
			(xy 74.71927 -76.814636) (xy 74.793079 -76.66137) (xy 74.874043 -76.511761) (xy 74.961983 -76.366142)
			(xy 75.056701 -76.224838) (xy 75.157986 -76.088165) (xy 75.265613 -75.956428) (xy 75.379341 -75.82992)
			(xy 75.498916 -75.708924) (xy 75.624071 -75.59371) (xy 75.754528 -75.484535) (xy 75.889996 -75.381643)
			(xy 76.030171 -75.285263) (xy 76.174741 -75.19561) (xy 76.323384 -75.112884) (xy 76.475767 -75.03727)
			(xy 76.631552 -74.968936) (xy 76.790389 -74.908036) (xy 76.951925 -74.854705) (xy 77.1158 -74.809061)
			(xy 77.281647 -74.771208) (xy 77.449097 -74.741229) (xy 77.617776 -74.719191) (xy 77.787307 -74.705143)
			(xy 77.957313 -74.699117) (xy 78.127413 -74.701126) (xy 78.297229 -74.711165) (xy 78.466382 -74.729213)
			(xy 78.634493 -74.755229) (xy 78.801188 -74.789155) (xy 78.966095 -74.830915) (xy 79.128846 -74.880417)
			(xy 79.289077 -74.937548) (xy 79.446432 -75.002183) (xy 79.600559 -75.074177) (xy 79.751114 -75.153369)
			(xy 79.897762 -75.239582) (xy 80.040174 -75.332625) (xy 80.178034 -75.432289) (xy 80.311033 -75.538352)
			(xy 80.438875 -75.650578) (xy 80.561274 -75.768716) (xy 80.677958 -75.892502) (xy 80.788667 -76.021661)
			(xy 80.893152 -76.155904) (xy 80.991181 -76.294931) (xy 81.082535 -76.438432) (xy 81.167011 -76.586087)
			(xy 81.244419 -76.737567) (xy 81.314587 -76.892534) (xy 81.377359 -77.050641) (xy 81.432595 -77.211536)
			(xy 81.48017 -77.37486) (xy 81.51998 -77.540249) (xy 81.551935 -77.707333) (xy 81.575963 -77.87574)
			(xy 81.592012 -78.045093) (xy 81.600046 -78.215016) (xy 81.600548 -78.300072) (xy 81.600046 -78.385128)
			(xy 81.592012 -78.555051) (xy 81.575963 -78.724404) (xy 81.551935 -78.892811) (xy 81.51998 -79.059895)
			(xy 81.48017 -79.225284) (xy 81.475042 -79.242888) (xy 83.360086 -79.242888) (xy 83.363976 -79.188532)
			(xy 83.375562 -79.135284) (xy 83.394609 -79.084226) (xy 83.420728 -79.036399) (xy 83.453389 -78.992777)
			(xy 83.491926 -78.954247) (xy 83.535554 -78.921593) (xy 83.583385 -78.895482) (xy 83.634446 -78.876444)
			(xy 83.687696 -78.864867) (xy 83.742053 -78.860986) (xy 83.796408 -78.864882) (xy 83.849655 -78.876473)
			(xy 83.900711 -78.895526) (xy 83.948535 -78.92165) (xy 83.970622 -78.937612) (xy 83.989634 -78.951208)
			(xy 84.031517 -78.97194) (xy 84.076485 -78.984666) (xy 84.123022 -78.988956) (xy 84.169559 -78.984666)
			(xy 84.214527 -78.97194) (xy 84.25641 -78.951208) (xy 84.275422 -78.937612) (xy 84.297491 -78.921627)
			(xy 84.345316 -78.895507) (xy 84.396372 -78.87646) (xy 84.449619 -78.864872) (xy 84.503972 -78.860981)
			(xy 84.558327 -78.864864) (xy 84.611575 -78.876444) (xy 84.662634 -78.895484) (xy 84.710463 -78.921597)
			(xy 84.754089 -78.954251) (xy 84.792623 -78.992782) (xy 84.825281 -79.036404) (xy 84.851399 -79.08423)
			(xy 84.870445 -79.135287) (xy 84.88203 -79.188534) (xy 84.885919 -79.242888) (xy 86.164478 -79.242888)
			(xy 86.168368 -79.188531) (xy 86.179954 -79.13528) (xy 86.199002 -79.084221) (xy 86.225123 -79.036392)
			(xy 86.257785 -78.992768) (xy 86.296323 -78.954237) (xy 86.339953 -78.921584) (xy 86.387787 -78.895472)
			(xy 86.43885 -78.876434) (xy 86.492102 -78.864857) (xy 86.546461 -78.860978) (xy 86.600817 -78.864875)
			(xy 86.654066 -78.876468) (xy 86.705123 -78.895522) (xy 86.752948 -78.921649) (xy 86.775036 -78.937612)
			(xy 86.794048 -78.951208) (xy 86.835931 -78.97194) (xy 86.880899 -78.984666) (xy 86.927436 -78.988956)
			(xy 86.973973 -78.984666) (xy 87.018941 -78.97194) (xy 87.060824 -78.951208) (xy 87.079836 -78.937612)
			(xy 87.101905 -78.921628) (xy 87.149729 -78.895511) (xy 87.200783 -78.876465) (xy 87.254028 -78.864879)
			(xy 87.30838 -78.860989) (xy 87.362733 -78.864874) (xy 87.415979 -78.876454) (xy 87.467036 -78.895494)
			(xy 87.514863 -78.921607) (xy 87.558486 -78.95426) (xy 87.597019 -78.99279) (xy 87.629676 -79.036411)
			(xy 87.655793 -79.084236) (xy 87.674837 -79.13529) (xy 87.686422 -79.188536) (xy 87.690311 -79.242888)
			(xy 87.686425 -79.29724) (xy 87.674844 -79.350487) (xy 87.655803 -79.401543) (xy 87.629689 -79.449369)
			(xy 87.597035 -79.492992) (xy 87.558504 -79.531524) (xy 87.514883 -79.56418) (xy 87.467057 -79.590296)
			(xy 87.416002 -79.609339) (xy 87.362757 -79.620923) (xy 87.308404 -79.624811) (xy 87.254052 -79.620924)
			(xy 87.200806 -79.609342) (xy 87.149751 -79.590299) (xy 87.101925 -79.564185) (xy 87.079836 -79.548228)
			(xy 87.060824 -79.534632) (xy 87.018941 -79.5139) (xy 86.973973 -79.501174) (xy 86.927436 -79.496884)
			(xy 86.880899 -79.501174) (xy 86.835931 -79.5139) (xy 86.794048 -79.534632) (xy 86.775036 -79.548228)
			(xy 86.752928 -79.564164) (xy 86.705101 -79.590288) (xy 86.654043 -79.609339) (xy 86.600794 -79.620929)
			(xy 86.546437 -79.624822) (xy 86.492079 -79.620939) (xy 86.438827 -79.609359) (xy 86.387765 -79.590318)
			(xy 86.339933 -79.564204) (xy 86.296305 -79.531547) (xy 86.257769 -79.493013) (xy 86.22511 -79.449387)
			(xy 86.198992 -79.401557) (xy 86.179948 -79.350497) (xy 86.168364 -79.297246) (xy 86.164478 -79.242888)
			(xy 84.885919 -79.242888) (xy 84.882033 -79.297242) (xy 84.870452 -79.35049) (xy 84.851409 -79.401548)
			(xy 84.825294 -79.449376) (xy 84.792639 -79.493) (xy 84.754107 -79.531533) (xy 84.710483 -79.56419)
			(xy 84.662656 -79.590306) (xy 84.611598 -79.609349) (xy 84.558351 -79.620932) (xy 84.503996 -79.624819)
			(xy 84.449642 -79.620931) (xy 84.396395 -79.609347) (xy 84.345338 -79.590303) (xy 84.297511 -79.564186)
			(xy 84.275422 -79.548228) (xy 84.25641 -79.534632) (xy 84.214527 -79.5139) (xy 84.169559 -79.501174)
			(xy 84.123022 -79.496884) (xy 84.076485 -79.501174) (xy 84.031517 -79.5139) (xy 83.989634 -79.534632)
			(xy 83.970622 -79.548228) (xy 83.948515 -79.564163) (xy 83.900689 -79.590284) (xy 83.849632 -79.609333)
			(xy 83.796384 -79.620922) (xy 83.742029 -79.624814) (xy 83.687673 -79.62093) (xy 83.634423 -79.609349)
			(xy 83.583363 -79.590308) (xy 83.535533 -79.564194) (xy 83.491907 -79.531538) (xy 83.453373 -79.493005)
			(xy 83.420715 -79.44938) (xy 83.394599 -79.401552) (xy 83.375555 -79.350493) (xy 83.363972 -79.297244)
			(xy 83.360086 -79.242888) (xy 81.475042 -79.242888) (xy 81.432595 -79.388608) (xy 81.377359 -79.549503)
			(xy 81.314587 -79.70761) (xy 81.244419 -79.862577) (xy 81.167011 -80.014057) (xy 81.082535 -80.161712)
			(xy 80.991181 -80.305213) (xy 80.893152 -80.44424) (xy 80.788667 -80.578483) (xy 80.677958 -80.707642)
			(xy 80.561274 -80.831428) (xy 80.456061 -80.932978) (xy 83.380882 -80.932978) (xy 83.384774 -80.878621)
			(xy 83.396362 -80.825371) (xy 83.415411 -80.774312) (xy 83.441533 -80.726484) (xy 83.474197 -80.682861)
			(xy 83.512737 -80.644332) (xy 83.556368 -80.611679) (xy 83.604203 -80.585569) (xy 83.655266 -80.566534)
			(xy 83.70852 -80.554959) (xy 83.762878 -80.551082) (xy 83.817235 -80.554982) (xy 83.870483 -80.566578)
			(xy 83.921539 -80.585634) (xy 83.969363 -80.611764) (xy 83.99145 -80.627728) (xy 84.010462 -80.641324)
			(xy 84.052345 -80.662056) (xy 84.097313 -80.674782) (xy 84.14385 -80.679072) (xy 84.190387 -80.674782)
			(xy 84.235355 -80.662056) (xy 84.277238 -80.641324) (xy 84.29625 -80.627728) (xy 84.318306 -80.611715)
			(xy 84.366137 -80.585582) (xy 84.4172 -80.566522) (xy 84.470457 -80.554925) (xy 84.524822 -80.551025)
			(xy 84.579189 -80.554902) (xy 84.63245 -80.566478) (xy 84.683521 -80.585517) (xy 84.731363 -80.611631)
			(xy 84.775001 -80.644288) (xy 84.813547 -80.682824) (xy 84.846215 -80.726453) (xy 84.872342 -80.774288)
			(xy 84.891394 -80.825355) (xy 84.902984 -80.878613) (xy 84.906875 -80.932978) (xy 86.185434 -80.932978)
			(xy 86.189324 -80.878633) (xy 86.200909 -80.825394) (xy 86.219952 -80.774346) (xy 86.246067 -80.726527)
			(xy 86.278721 -80.682912) (xy 86.31725 -80.644388) (xy 86.36087 -80.611739) (xy 86.408692 -80.585631)
			(xy 86.459743 -80.566594) (xy 86.512983 -80.555017) (xy 86.567329 -80.551134) (xy 86.621675 -80.555025)
			(xy 86.674913 -80.566611) (xy 86.725961 -80.585655) (xy 86.773779 -80.611771) (xy 86.795864 -80.627728)
			(xy 86.814876 -80.641324) (xy 86.856759 -80.662056) (xy 86.901727 -80.674782) (xy 86.948264 -80.679072)
			(xy 86.994801 -80.674782) (xy 87.039769 -80.662056) (xy 87.081652 -80.641324) (xy 87.100664 -80.627728)
			(xy 87.122719 -80.611716) (xy 87.170549 -80.585585) (xy 87.221612 -80.566528) (xy 87.274867 -80.554932)
			(xy 87.32923 -80.551033) (xy 87.383595 -80.554912) (xy 87.436854 -80.566488) (xy 87.487923 -80.585527)
			(xy 87.535763 -80.611641) (xy 87.579399 -80.644297) (xy 87.617943 -80.682832) (xy 87.65061 -80.72646)
			(xy 87.676735 -80.774294) (xy 87.695786 -80.825358) (xy 87.707375 -80.878615) (xy 87.711267 -80.932978)
			(xy 87.707381 -80.987343) (xy 87.695798 -81.0406) (xy 87.676753 -81.091667) (xy 87.650633 -81.139504)
			(xy 87.617971 -81.183135) (xy 87.579431 -81.221675) (xy 87.535799 -81.254336) (xy 87.487962 -81.280455)
			(xy 87.436895 -81.2995) (xy 87.383637 -81.311082) (xy 87.329273 -81.314967) (xy 87.274909 -81.311075)
			(xy 87.221653 -81.299485) (xy 87.170589 -81.280433) (xy 87.122756 -81.254307) (xy 87.100664 -81.238344)
			(xy 87.081652 -81.224748) (xy 87.039769 -81.204016) (xy 86.994801 -81.19129) (xy 86.948264 -81.187)
			(xy 86.901727 -81.19129) (xy 86.856759 -81.204016) (xy 86.814876 -81.224748) (xy 86.795864 -81.238344)
			(xy 86.773743 -81.254252) (xy 86.725922 -81.280363) (xy 86.674872 -81.299401) (xy 86.621632 -81.310981)
			(xy 86.567286 -81.314866) (xy 86.51294 -81.310977) (xy 86.459701 -81.299394) (xy 86.408652 -81.280351)
			(xy 86.360833 -81.254237) (xy 86.317218 -81.221584) (xy 86.278693 -81.183055) (xy 86.246044 -81.139437)
			(xy 86.219934 -81.091615) (xy 86.200896 -81.040565) (xy 86.189318 -80.987325) (xy 86.185434 -80.932978)
			(xy 84.906875 -80.932978) (xy 84.90299 -80.987344) (xy 84.891406 -81.040604) (xy 84.87236 -81.091673)
			(xy 84.846239 -81.139511) (xy 84.813575 -81.183144) (xy 84.775034 -81.221684) (xy 84.731399 -81.254346)
			(xy 84.683561 -81.280465) (xy 84.632491 -81.29951) (xy 84.579231 -81.311092) (xy 84.524865 -81.314975)
			(xy 84.4705 -81.311082) (xy 84.417242 -81.29949) (xy 84.366176 -81.280436) (xy 84.318342 -81.254308)
			(xy 84.29625 -81.238344) (xy 84.277238 -81.224748) (xy 84.235355 -81.204016) (xy 84.190387 -81.19129)
			(xy 84.14385 -81.187) (xy 84.097313 -81.19129) (xy 84.052345 -81.204016) (xy 84.010462 -81.224748)
			(xy 83.99145 -81.238344) (xy 83.969327 -81.25426) (xy 83.9215 -81.280384) (xy 83.870442 -81.299435)
			(xy 83.817192 -81.311025) (xy 83.762835 -81.314918) (xy 83.708477 -81.311035) (xy 83.655225 -81.299454)
			(xy 83.604163 -81.280413) (xy 83.556332 -81.254297) (xy 83.512704 -81.22164) (xy 83.474169 -81.183106)
			(xy 83.44151 -81.139479) (xy 83.415393 -81.091649) (xy 83.396349 -81.040588) (xy 83.384767 -80.987336)
			(xy 83.380882 -80.932978) (xy 80.456061 -80.932978) (xy 80.438875 -80.949566) (xy 80.311033 -81.061792)
			(xy 80.178034 -81.167855) (xy 80.040174 -81.267519) (xy 79.897762 -81.360562) (xy 79.751114 -81.446775)
			(xy 79.600559 -81.525967) (xy 79.446432 -81.597961) (xy 79.289077 -81.662596) (xy 79.128846 -81.719727)
			(xy 78.966095 -81.769229) (xy 78.801188 -81.810989) (xy 78.634493 -81.844915) (xy 78.466382 -81.870931)
			(xy 78.297229 -81.888979) (xy 78.127413 -81.899018) (xy 77.957313 -81.901027) (xy 77.787307 -81.895001)
			(xy 77.617776 -81.880953) (xy 77.449097 -81.858915) (xy 77.281647 -81.828936) (xy 77.1158 -81.791083)
			(xy 76.951925 -81.745439) (xy 76.790389 -81.692108) (xy 76.631552 -81.631208) (xy 76.475767 -81.562874)
			(xy 76.323384 -81.48726) (xy 76.174741 -81.404534) (xy 76.030171 -81.314881) (xy 75.889996 -81.218501)
			(xy 75.754528 -81.115609) (xy 75.624071 -81.006434) (xy 75.498916 -80.89122) (xy 75.379341 -80.770224)
			(xy 75.265613 -80.643716) (xy 75.157986 -80.511979) (xy 75.056701 -80.375306) (xy 74.961983 -80.234002)
			(xy 74.874043 -80.088383) (xy 74.793079 -79.938774) (xy 74.71927 -79.785508) (xy 74.652781 -79.628928)
			(xy 74.593761 -79.469382) (xy 74.542341 -79.307227) (xy 74.498636 -79.142825) (xy 74.462744 -78.976542)
			(xy 74.434744 -78.80875) (xy 74.4147 -78.639822) (xy 74.402655 -78.470137) (xy 74.398638 -78.300072)
			(xy 36.478876 -78.300072) (xy 36.471468 -78.380013) (xy 36.4555 -78.465433) (xy 36.431719 -78.549015)
			(xy 36.400327 -78.630047) (xy 36.361593 -78.707836) (xy 36.315846 -78.78172) (xy 36.263477 -78.851067)
			(xy 36.204933 -78.915287) (xy 36.140713 -78.973831) (xy 36.071366 -79.0262) (xy 35.997482 -79.071947)
			(xy 35.919693 -79.110681) (xy 35.838661 -79.142073) (xy 35.755079 -79.165854) (xy 35.669659 -79.181822)
			(xy 35.58313 -79.18984) (xy 35.49623 -79.18984) (xy 35.409701 -79.181822) (xy 35.324281 -79.165854)
			(xy 35.240699 -79.142073) (xy 35.159667 -79.110681) (xy 35.081878 -79.071947) (xy 35.007994 -79.0262)
			(xy 34.938647 -78.973831) (xy 34.874427 -78.915287) (xy 34.815883 -78.851067) (xy 34.763514 -78.78172)
			(xy 34.717767 -78.707836) (xy 34.679033 -78.630047) (xy 34.647641 -78.549015) (xy 34.62386 -78.465433)
			(xy 34.607892 -78.380013) (xy 34.599874 -78.293484) (xy 31.399486 -78.293484) (xy 31.391468 -78.380013)
			(xy 31.3755 -78.465433) (xy 31.351719 -78.549015) (xy 31.320327 -78.630047) (xy 31.281593 -78.707836)
			(xy 31.235846 -78.78172) (xy 31.183477 -78.851067) (xy 31.124933 -78.915287) (xy 31.060713 -78.973831)
			(xy 30.991366 -79.0262) (xy 30.917482 -79.071947) (xy 30.839693 -79.110681) (xy 30.758661 -79.142073)
			(xy 30.675079 -79.165854) (xy 30.589659 -79.181822) (xy 30.50313 -79.18984) (xy 30.41623 -79.18984)
			(xy 30.329701 -79.181822) (xy 30.244281 -79.165854) (xy 30.160699 -79.142073) (xy 30.079667 -79.110681)
			(xy 30.001878 -79.071947) (xy 29.927994 -79.0262) (xy 29.858647 -78.973831) (xy 29.794427 -78.915287)
			(xy 29.735883 -78.851067) (xy 29.683514 -78.78172) (xy 29.637767 -78.707836) (xy 29.599033 -78.630047)
			(xy 29.567641 -78.549015) (xy 29.54386 -78.465433) (xy 29.527892 -78.380013) (xy 29.519874 -78.293484)
			(xy 29.170884 -78.293484) (xy 29.170884 -79.326013) (xy 41.775636 -79.326013) (xy 41.779523 -79.271649)
			(xy 41.791107 -79.218391) (xy 41.810154 -79.167324) (xy 41.836275 -79.119488) (xy 41.868939 -79.075857)
			(xy 41.90748 -79.037319) (xy 41.951114 -79.004659) (xy 41.998952 -78.978542) (xy 42.05002 -78.959499)
			(xy 42.103279 -78.947918) (xy 42.157643 -78.944036) (xy 42.212007 -78.947931) (xy 42.265263 -78.959523)
			(xy 42.316327 -78.978578) (xy 42.364159 -79.004706) (xy 42.38625 -79.02067) (xy 42.405262 -79.034266)
			(xy 42.447145 -79.054998) (xy 42.492113 -79.067724) (xy 42.53865 -79.072014) (xy 42.585187 -79.067724)
			(xy 42.630155 -79.054998) (xy 42.672038 -79.034266) (xy 42.69105 -79.02067) (xy 42.71316 -79.004735)
			(xy 42.760988 -78.97861) (xy 42.812047 -78.959557) (xy 42.865298 -78.947965) (xy 42.919657 -78.944071)
			(xy 42.974016 -78.947953) (xy 43.02727 -78.959533) (xy 43.078334 -78.978574) (xy 43.126167 -79.004689)
			(xy 43.169797 -79.037346) (xy 43.208334 -79.07588) (xy 43.240995 -79.119507) (xy 43.267114 -79.167339)
			(xy 43.286159 -79.218401) (xy 43.297743 -79.271654) (xy 43.301629 -79.326013) (xy 43.297739 -79.380372)
			(xy 43.286151 -79.433624) (xy 43.267103 -79.484685) (xy 43.240981 -79.532515) (xy 43.208317 -79.57614)
			(xy 43.169777 -79.614671) (xy 43.126145 -79.647326) (xy 43.07831 -79.673437) (xy 43.027245 -79.692475)
			(xy 42.97399 -79.704051) (xy 42.91963 -79.707929) (xy 42.865272 -79.704031) (xy 42.812021 -79.692436)
			(xy 42.760964 -79.673379) (xy 42.713138 -79.64725) (xy 42.69105 -79.631286) (xy 42.672038 -79.61769)
			(xy 42.630155 -79.596958) (xy 42.585187 -79.584232) (xy 42.53865 -79.579942) (xy 42.492113 -79.584232)
			(xy 42.447145 -79.596958) (xy 42.405262 -79.61769) (xy 42.38625 -79.631286) (xy 42.364181 -79.64728)
			(xy 42.316351 -79.673411) (xy 42.265288 -79.692469) (xy 42.212033 -79.704066) (xy 42.15767 -79.707964)
			(xy 42.103305 -79.704085) (xy 42.050045 -79.692509) (xy 41.998976 -79.673469) (xy 41.951136 -79.647355)
			(xy 41.9075 -79.614698) (xy 41.868956 -79.576163) (xy 41.83629 -79.532534) (xy 41.810165 -79.4847)
			(xy 41.791115 -79.433634) (xy 41.779526 -79.380377) (xy 41.775636 -79.326013) (xy 29.170884 -79.326013)
			(xy 29.170884 -81.24698) (xy 29.171376 -81.263637) (xy 29.179994 -81.295818) (xy 29.196647 -81.324671)
			(xy 29.2202 -81.348231) (xy 29.249049 -81.364893) (xy 29.281227 -81.373519) (xy 29.297884 -81.37398)
			(xy 29.311854 -81.37398) (xy 29.335377 -81.373473) (xy 29.381621 -81.364823) (xy 29.425483 -81.347812)
			(xy 29.465466 -81.32302) (xy 29.500204 -81.291293) (xy 29.52851 -81.253715) (xy 29.549417 -81.211571)
			(xy 29.562212 -81.166298) (xy 29.566457 -81.119444) (xy 29.562007 -81.07261) (xy 29.555948 -81.049876)
			(xy 29.544393 -81.007918) (xy 29.528176 -80.922407) (xy 29.519929 -80.835764) (xy 29.519724 -80.74873)
			(xy 29.527563 -80.662049) (xy 29.543378 -80.576463) (xy 29.567033 -80.492704) (xy 29.598328 -80.41149)
			(xy 29.636993 -80.333516) (xy 29.682698 -80.259447) (xy 29.735052 -80.18992) (xy 29.793607 -80.125527)
			(xy 29.857861 -80.066821) (xy 29.927266 -80.014303) (xy 30.001226 -79.968424) (xy 30.079109 -79.929575)
			(xy 30.160249 -79.89809) (xy 30.243952 -79.874237) (xy 30.3295 -79.858221) (xy 30.416163 -79.850178)
			(xy 30.503197 -79.850178) (xy 30.58986 -79.858221) (xy 30.675408 -79.874237) (xy 30.759111 -79.89809)
			(xy 30.840251 -79.929575) (xy 30.918134 -79.968424) (xy 30.992094 -80.014303) (xy 31.061499 -80.066821)
			(xy 31.125753 -80.125527) (xy 31.184308 -80.18992) (xy 31.236662 -80.259447) (xy 31.282367 -80.333516)
			(xy 31.321032 -80.41149) (xy 31.352327 -80.492704) (xy 31.375982 -80.576463) (xy 31.391797 -80.662049)
			(xy 31.399636 -80.74873) (xy 31.399436 -80.833484) (xy 34.599874 -80.833484) (xy 34.599874 -80.746584)
			(xy 34.607892 -80.660055) (xy 34.62386 -80.574635) (xy 34.647641 -80.491053) (xy 34.679033 -80.410021)
			(xy 34.717767 -80.332232) (xy 34.763514 -80.258348) (xy 34.815883 -80.189001) (xy 34.874427 -80.124781)
			(xy 34.938647 -80.066237) (xy 35.007994 -80.013868) (xy 35.081878 -79.968121) (xy 35.159667 -79.929387)
			(xy 35.240699 -79.897995) (xy 35.324281 -79.874214) (xy 35.409701 -79.858246) (xy 35.49623 -79.850228)
			(xy 35.58313 -79.850228) (xy 35.669659 -79.858246) (xy 35.755079 -79.874214) (xy 35.838661 -79.897995)
			(xy 35.919693 -79.929387) (xy 35.997482 -79.968121) (xy 36.071366 -80.013868) (xy 36.140713 -80.066237)
			(xy 36.204933 -80.124781) (xy 36.263477 -80.189001) (xy 36.315846 -80.258348) (xy 36.361593 -80.332232)
			(xy 36.400327 -80.410021) (xy 36.431719 -80.491053) (xy 36.4555 -80.574635) (xy 36.471468 -80.660055)
			(xy 36.479486 -80.746584) (xy 36.479988 -80.790034) (xy 36.479486 -80.833484) (xy 36.471468 -80.920013)
			(xy 36.4555 -81.005433) (xy 36.431719 -81.089015) (xy 36.400327 -81.170047) (xy 36.361593 -81.247836)
			(xy 36.315846 -81.32172) (xy 36.263477 -81.391067) (xy 36.204933 -81.455287) (xy 36.140713 -81.513831)
			(xy 36.071366 -81.5662) (xy 35.997482 -81.611947) (xy 35.919693 -81.650681) (xy 35.838661 -81.682073)
			(xy 35.755079 -81.705854) (xy 35.669659 -81.721822) (xy 35.58313 -81.72984) (xy 35.49623 -81.72984)
			(xy 35.409701 -81.721822) (xy 35.324281 -81.705854) (xy 35.240699 -81.682073) (xy 35.159667 -81.650681)
			(xy 35.081878 -81.611947) (xy 35.007994 -81.5662) (xy 34.938647 -81.513831) (xy 34.874427 -81.455287)
			(xy 34.815883 -81.391067) (xy 34.763514 -81.32172) (xy 34.717767 -81.247836) (xy 34.679033 -81.170047)
			(xy 34.647641 -81.089015) (xy 34.62386 -81.005433) (xy 34.607892 -80.920013) (xy 34.599874 -80.833484)
			(xy 31.399436 -80.833484) (xy 31.399431 -80.835764) (xy 31.391184 -80.922407) (xy 31.374967 -81.007918)
			(xy 31.363412 -81.049876) (xy 31.357411 -81.072624) (xy 31.352965 -81.119456) (xy 31.357211 -81.166306)
			(xy 31.370002 -81.211576) (xy 31.390902 -81.253721) (xy 31.419198 -81.291301) (xy 31.453925 -81.323035)
			(xy 31.493897 -81.347839) (xy 31.537749 -81.364867) (xy 31.583985 -81.373538) (xy 31.607506 -81.37398)
			(xy 32.415988 -81.37398) (xy 32.415988 -83.373484) (xy 34.599874 -83.373484) (xy 34.599874 -83.286584)
			(xy 34.607892 -83.200055) (xy 34.62386 -83.114635) (xy 34.647641 -83.031053) (xy 34.679033 -82.950021)
			(xy 34.717767 -82.872232) (xy 34.763514 -82.798348) (xy 34.815883 -82.729001) (xy 34.874427 -82.664781)
			(xy 34.938647 -82.606237) (xy 35.007994 -82.553868) (xy 35.081878 -82.508121) (xy 35.159667 -82.469387)
			(xy 35.240699 -82.437995) (xy 35.324281 -82.414214) (xy 35.409701 -82.398246) (xy 35.49623 -82.390228)
			(xy 35.58313 -82.390228) (xy 35.669659 -82.398246) (xy 35.755079 -82.414214) (xy 35.838661 -82.437995)
			(xy 35.919693 -82.469387) (xy 35.997482 -82.508121) (xy 36.071366 -82.553868) (xy 36.140713 -82.606237)
			(xy 36.204933 -82.664781) (xy 36.263477 -82.729001) (xy 36.307658 -82.787506) (xy 83.380846 -82.787506)
			(xy 83.384733 -82.733143) (xy 83.396319 -82.679887) (xy 83.415366 -82.628822) (xy 83.441487 -82.580988)
			(xy 83.474151 -82.537358) (xy 83.512692 -82.498822) (xy 83.556325 -82.466163) (xy 83.604162 -82.440047)
			(xy 83.65523 -82.421006) (xy 83.708487 -82.409427) (xy 83.76285 -82.405546) (xy 83.817213 -82.409441)
			(xy 83.870467 -82.421034) (xy 83.92153 -82.440089) (xy 83.96936 -82.466218) (xy 83.99145 -82.482182)
			(xy 84.010462 -82.495778) (xy 84.052345 -82.51651) (xy 84.097313 -82.529236) (xy 84.14385 -82.533526)
			(xy 84.190387 -82.529236) (xy 84.235355 -82.51651) (xy 84.277238 -82.495778) (xy 84.29625 -82.482182)
			(xy 84.318349 -82.466231) (xy 84.366177 -82.440104) (xy 84.417237 -82.42105) (xy 84.470489 -82.409457)
			(xy 84.52485 -82.405562) (xy 84.579211 -82.409443) (xy 84.632466 -82.421021) (xy 84.683531 -82.440062)
			(xy 84.731366 -82.466177) (xy 84.774998 -82.498834) (xy 84.813537 -82.537369) (xy 84.846199 -82.580996)
			(xy 84.87232 -82.628828) (xy 84.891366 -82.679891) (xy 84.902951 -82.733145) (xy 84.906838 -82.787506)
			(xy 86.185397 -82.787506) (xy 86.189284 -82.733155) (xy 86.200865 -82.67991) (xy 86.219907 -82.628855)
			(xy 86.246021 -82.58103) (xy 86.278675 -82.537409) (xy 86.317205 -82.498878) (xy 86.360827 -82.466223)
			(xy 86.408651 -82.440109) (xy 86.459706 -82.421067) (xy 86.51295 -82.409484) (xy 86.567302 -82.405597)
			(xy 86.621653 -82.409485) (xy 86.674897 -82.421068) (xy 86.725952 -82.44011) (xy 86.773776 -82.466225)
			(xy 86.795864 -82.482182) (xy 86.814876 -82.495778) (xy 86.856759 -82.51651) (xy 86.901727 -82.529236)
			(xy 86.948264 -82.533526) (xy 86.994801 -82.529236) (xy 87.039769 -82.51651) (xy 87.081652 -82.495778)
			(xy 87.100664 -82.482182) (xy 87.122762 -82.466232) (xy 87.17059 -82.440107) (xy 87.221649 -82.421055)
			(xy 87.274899 -82.409464) (xy 87.329257 -82.40557) (xy 87.383617 -82.409452) (xy 87.43687 -82.421031)
			(xy 87.487933 -82.440072) (xy 87.535766 -82.466187) (xy 87.579396 -82.498843) (xy 87.617933 -82.537377)
			(xy 87.650594 -82.581003) (xy 87.676713 -82.628834) (xy 87.695758 -82.679895) (xy 87.707343 -82.733147)
			(xy 87.71123 -82.787506) (xy 87.707341 -82.841865) (xy 87.695755 -82.895116) (xy 87.676708 -82.946177)
			(xy 87.650587 -82.994007) (xy 87.617925 -83.037632) (xy 87.579386 -83.076165) (xy 87.535756 -83.10882)
			(xy 87.487922 -83.134933) (xy 87.436858 -83.153972) (xy 87.383605 -83.16555) (xy 87.329245 -83.16943)
			(xy 87.274887 -83.165534) (xy 87.221637 -83.153941) (xy 87.170579 -83.134888) (xy 87.122752 -83.108761)
			(xy 87.100664 -83.092798) (xy 87.081652 -83.079202) (xy 87.039769 -83.05847) (xy 86.994801 -83.045744)
			(xy 86.948264 -83.041454) (xy 86.901727 -83.045744) (xy 86.856759 -83.05847) (xy 86.814876 -83.079202)
			(xy 86.795864 -83.092798) (xy 86.773786 -83.108768) (xy 86.725962 -83.134885) (xy 86.674909 -83.153929)
			(xy 86.621665 -83.165514) (xy 86.567314 -83.169403) (xy 86.512962 -83.165518) (xy 86.459717 -83.153937)
			(xy 86.408662 -83.134896) (xy 86.360837 -83.108783) (xy 86.317214 -83.07613) (xy 86.278683 -83.0376)
			(xy 86.246028 -82.99398) (xy 86.219912 -82.946156) (xy 86.200869 -82.895102) (xy 86.189285 -82.841857)
			(xy 86.185397 -82.787506) (xy 84.906838 -82.787506) (xy 84.902949 -82.841867) (xy 84.891363 -82.89512)
			(xy 84.872315 -82.946182) (xy 84.846193 -82.994014) (xy 84.813529 -83.03764) (xy 84.774989 -83.076174)
			(xy 84.731356 -83.10883) (xy 84.68352 -83.134943) (xy 84.632454 -83.153982) (xy 84.579199 -83.165559)
			(xy 84.524838 -83.169438) (xy 84.470478 -83.165541) (xy 84.417226 -83.153947) (xy 84.366166 -83.134891)
			(xy 84.318339 -83.108762) (xy 84.29625 -83.092798) (xy 84.277238 -83.079202) (xy 84.235355 -83.05847)
			(xy 84.190387 -83.045744) (xy 84.14385 -83.041454) (xy 84.097313 -83.045744) (xy 84.052345 -83.05847)
			(xy 84.010462 -83.079202) (xy 83.99145 -83.092798) (xy 83.96937 -83.108776) (xy 83.92154 -83.134906)
			(xy 83.870479 -83.153962) (xy 83.817225 -83.165557) (xy 83.762862 -83.169454) (xy 83.708499 -83.165575)
			(xy 83.655241 -83.153997) (xy 83.604173 -83.134958) (xy 83.556335 -83.108843) (xy 83.512701 -83.076186)
			(xy 83.474159 -83.037651) (xy 83.441494 -82.994023) (xy 83.415371 -82.946189) (xy 83.396322 -82.895125)
			(xy 83.384735 -82.841869) (xy 83.380846 -82.787506) (xy 36.307658 -82.787506) (xy 36.315846 -82.798348)
			(xy 36.361593 -82.872232) (xy 36.400327 -82.950021) (xy 36.431719 -83.031053) (xy 36.4555 -83.114635)
			(xy 36.471468 -83.200055) (xy 36.479486 -83.286584) (xy 36.479988 -83.330034) (xy 36.479486 -83.373484)
			(xy 36.472615 -83.447636) (xy 51.141884 -83.447636) (xy 52.793392 -83.447636) (xy 52.793392 -85.099652)
			(xy 51.141884 -85.099652) (xy 51.141884 -83.447636) (xy 36.472615 -83.447636) (xy 36.471468 -83.460013)
			(xy 36.4555 -83.545433) (xy 36.431719 -83.629015) (xy 36.400327 -83.710047) (xy 36.361593 -83.787836)
			(xy 36.315846 -83.86172) (xy 36.263477 -83.931067) (xy 36.204933 -83.995287) (xy 36.140713 -84.053831)
			(xy 36.071366 -84.1062) (xy 35.997482 -84.151947) (xy 35.919693 -84.190681) (xy 35.838661 -84.222073)
			(xy 35.755079 -84.245854) (xy 35.669659 -84.261822) (xy 35.58313 -84.26984) (xy 35.49623 -84.26984)
			(xy 35.409701 -84.261822) (xy 35.324281 -84.245854) (xy 35.240699 -84.222073) (xy 35.159667 -84.190681)
			(xy 35.081878 -84.151947) (xy 35.007994 -84.1062) (xy 34.938647 -84.053831) (xy 34.874427 -83.995287)
			(xy 34.815883 -83.931067) (xy 34.763514 -83.86172) (xy 34.717767 -83.787836) (xy 34.679033 -83.710047)
			(xy 34.647641 -83.629015) (xy 34.62386 -83.545433) (xy 34.607892 -83.460013) (xy 34.599874 -83.373484)
			(xy 32.415988 -83.373484) (xy 32.415988 -84.314199) (xy 47.642008 -84.314199) (xy 47.642008 -84.233089)
			(xy 47.649958 -84.15237) (xy 47.665781 -84.072819) (xy 47.689326 -83.995203) (xy 47.720365 -83.920267)
			(xy 47.7586 -83.848735) (xy 47.803662 -83.781295) (xy 47.855117 -83.718596) (xy 47.91247 -83.661243)
			(xy 47.975169 -83.609788) (xy 48.042609 -83.564726) (xy 48.114141 -83.526491) (xy 48.189077 -83.495452)
			(xy 48.266693 -83.471907) (xy 48.346244 -83.456084) (xy 48.426963 -83.448134) (xy 48.508073 -83.448134)
			(xy 48.588792 -83.456084) (xy 48.668343 -83.471907) (xy 48.745959 -83.495452) (xy 48.820895 -83.526491)
			(xy 48.892427 -83.564726) (xy 48.959867 -83.609788) (xy 49.022566 -83.661243) (xy 49.079919 -83.718596)
			(xy 49.131374 -83.781295) (xy 49.176436 -83.848735) (xy 49.214671 -83.920267) (xy 49.24571 -83.995203)
			(xy 49.269255 -84.072819) (xy 49.285078 -84.15237) (xy 49.293028 -84.233089) (xy 49.293526 -84.273644)
			(xy 49.293028 -84.314199) (xy 49.285078 -84.394918) (xy 49.269255 -84.474469) (xy 49.24571 -84.552085)
			(xy 49.214671 -84.627021) (xy 49.176436 -84.698553) (xy 49.131374 -84.765993) (xy 49.079919 -84.828692)
			(xy 49.022566 -84.886045) (xy 48.959867 -84.9375) (xy 48.892427 -84.982562) (xy 48.820895 -85.020797)
			(xy 48.745959 -85.051836) (xy 48.668343 -85.075381) (xy 48.588792 -85.091204) (xy 48.508073 -85.099154)
			(xy 48.426963 -85.099154) (xy 48.346244 -85.091204) (xy 48.266693 -85.075381) (xy 48.189077 -85.051836)
			(xy 48.114141 -85.020797) (xy 48.042609 -84.982562) (xy 47.975169 -84.9375) (xy 47.91247 -84.886045)
			(xy 47.855117 -84.828692) (xy 47.803662 -84.765993) (xy 47.7586 -84.698553) (xy 47.720365 -84.627021)
			(xy 47.689326 -84.552085) (xy 47.665781 -84.474469) (xy 47.649958 -84.394918) (xy 47.642008 -84.314199)
			(xy 32.415988 -84.314199) (xy 32.415988 -85.159107) (xy 83.380844 -85.159107) (xy 83.384731 -85.104744)
			(xy 83.396317 -85.051488) (xy 83.415364 -85.000422) (xy 83.441485 -84.952588) (xy 83.474149 -84.908958)
			(xy 83.51269 -84.870421) (xy 83.556323 -84.837763) (xy 83.604161 -84.811646) (xy 83.655228 -84.792605)
			(xy 83.708486 -84.781025) (xy 83.762849 -84.777144) (xy 83.817212 -84.781039) (xy 83.870467 -84.792633)
			(xy 83.921529 -84.811687) (xy 83.96936 -84.837816) (xy 83.99145 -84.85378) (xy 84.010462 -84.867376)
			(xy 84.052345 -84.888108) (xy 84.097313 -84.900834) (xy 84.14385 -84.905124) (xy 84.190387 -84.900834)
			(xy 84.235355 -84.888108) (xy 84.277238 -84.867376) (xy 84.29625 -84.85378) (xy 84.318351 -84.837832)
			(xy 84.366179 -84.811705) (xy 84.417239 -84.792651) (xy 84.470491 -84.781058) (xy 84.524851 -84.777163)
			(xy 84.579212 -84.781044) (xy 84.632467 -84.792623) (xy 84.683532 -84.811664) (xy 84.731366 -84.837779)
			(xy 84.774998 -84.870436) (xy 84.813537 -84.908971) (xy 84.846199 -84.952598) (xy 84.872319 -85.00043)
			(xy 84.891365 -85.051493) (xy 84.90295 -85.104747) (xy 84.906837 -85.159107) (xy 86.185395 -85.159107)
			(xy 86.189282 -85.104756) (xy 86.200864 -85.051511) (xy 86.219905 -85.000456) (xy 86.246019 -84.952631)
			(xy 86.278673 -84.909009) (xy 86.317203 -84.870478) (xy 86.360825 -84.837823) (xy 86.40865 -84.811708)
			(xy 86.459704 -84.792666) (xy 86.512949 -84.781083) (xy 86.5673 -84.777195) (xy 86.621652 -84.781083)
			(xy 86.674897 -84.792666) (xy 86.725951 -84.811708) (xy 86.773776 -84.837823) (xy 86.795864 -84.85378)
			(xy 86.814876 -84.867376) (xy 86.856759 -84.888108) (xy 86.901727 -84.900834) (xy 86.948264 -84.905124)
			(xy 86.994801 -84.900834) (xy 87.039769 -84.888108) (xy 87.081652 -84.867376) (xy 87.100664 -84.85378)
			(xy 87.122764 -84.837833) (xy 87.170592 -84.811708) (xy 87.22165 -84.792656) (xy 87.274901 -84.781065)
			(xy 87.329259 -84.777172) (xy 87.383618 -84.781054) (xy 87.436871 -84.792633) (xy 87.487933 -84.811674)
			(xy 87.535766 -84.837789) (xy 87.579395 -84.870445) (xy 87.617933 -84.908979) (xy 87.650593 -84.952605)
			(xy 87.676712 -85.000436) (xy 87.695757 -85.051497) (xy 87.707341 -85.104749) (xy 87.711228 -85.159107)
			(xy 87.707339 -85.213466) (xy 87.695753 -85.266717) (xy 87.676706 -85.317777) (xy 87.650585 -85.365607)
			(xy 87.617923 -85.409232) (xy 87.579385 -85.447764) (xy 87.535754 -85.480419) (xy 87.48792 -85.506532)
			(xy 87.436857 -85.525571) (xy 87.383603 -85.537148) (xy 87.329244 -85.541028) (xy 87.274886 -85.537132)
			(xy 87.221636 -85.52554) (xy 87.170578 -85.506486) (xy 87.122752 -85.480359) (xy 87.100664 -85.464396)
			(xy 87.081652 -85.4508) (xy 87.039769 -85.430068) (xy 86.994801 -85.417342) (xy 86.948264 -85.413052)
			(xy 86.901727 -85.417342) (xy 86.856759 -85.430068) (xy 86.814876 -85.4508) (xy 86.795864 -85.464396)
			(xy 86.773788 -85.480369) (xy 86.725964 -85.506486) (xy 86.67491 -85.52553) (xy 86.621666 -85.537115)
			(xy 86.567315 -85.541005) (xy 86.512963 -85.537119) (xy 86.459718 -85.525539) (xy 86.408663 -85.506498)
			(xy 86.360837 -85.480385) (xy 86.317214 -85.447732) (xy 86.278683 -85.409202) (xy 86.246027 -85.365582)
			(xy 86.219911 -85.317757) (xy 86.200868 -85.266703) (xy 86.189284 -85.213458) (xy 86.185395 -85.159107)
			(xy 84.906837 -85.159107) (xy 84.902948 -85.213467) (xy 84.891361 -85.266721) (xy 84.872313 -85.317783)
			(xy 84.846191 -85.365614) (xy 84.813527 -85.40924) (xy 84.774987 -85.447774) (xy 84.731354 -85.480429)
			(xy 84.683518 -85.506542) (xy 84.632453 -85.525581) (xy 84.579197 -85.537158) (xy 84.524836 -85.541037)
			(xy 84.470477 -85.53714) (xy 84.417225 -85.525545) (xy 84.366166 -85.506489) (xy 84.318338 -85.48036)
			(xy 84.29625 -85.464396) (xy 84.277238 -85.4508) (xy 84.235355 -85.430068) (xy 84.190387 -85.417342)
			(xy 84.14385 -85.413052) (xy 84.097313 -85.417342) (xy 84.052345 -85.430068) (xy 84.010462 -85.4508)
			(xy 83.99145 -85.464396) (xy 83.969372 -85.480376) (xy 83.921542 -85.506507) (xy 83.87048 -85.525563)
			(xy 83.817226 -85.537159) (xy 83.762864 -85.541056) (xy 83.7085 -85.537177) (xy 83.655242 -85.525599)
			(xy 83.604174 -85.50656) (xy 83.556335 -85.480445) (xy 83.512701 -85.447788) (xy 83.474158 -85.409253)
			(xy 83.441493 -85.365624) (xy 83.41537 -85.317791) (xy 83.396321 -85.266726) (xy 83.384733 -85.21347)
			(xy 83.380844 -85.159107) (xy 32.415988 -85.159107) (xy 32.415988 -85.286342) (xy 32.408368 -85.286342)
			(xy 32.38533 -85.286837) (xy 32.340008 -85.295132) (xy 32.296923 -85.311463) (xy 32.257489 -85.335294)
			(xy 32.222999 -85.365845) (xy 32.194581 -85.402113) (xy 32.173169 -85.442911) (xy 32.159463 -85.486901)
			(xy 32.153913 -85.532641) (xy 32.156701 -85.578632) (xy 32.167736 -85.623366) (xy 32.186655 -85.665378)
			(xy 32.212838 -85.703291) (xy 32.22879 -85.71992) (xy 33.494124 -86.985104) (xy 83.380849 -86.985104)
			(xy 83.384737 -86.930741) (xy 83.396322 -86.877485) (xy 83.41537 -86.826421) (xy 83.441491 -86.778587)
			(xy 83.474155 -86.734958) (xy 83.512696 -86.696423) (xy 83.556329 -86.663765) (xy 83.604166 -86.637649)
			(xy 83.655233 -86.618608) (xy 83.70849 -86.60703) (xy 83.762853 -86.603149) (xy 83.817215 -86.607045)
			(xy 83.870469 -86.618638) (xy 83.92153 -86.637693) (xy 83.96936 -86.663822) (xy 83.99145 -86.679786)
			(xy 84.010462 -86.693382) (xy 84.052345 -86.714114) (xy 84.097313 -86.72684) (xy 84.14385 -86.73113)
			(xy 84.190387 -86.72684) (xy 84.235355 -86.714114) (xy 84.277238 -86.693382) (xy 84.29625 -86.679786)
			(xy 84.318345 -86.66383) (xy 84.366174 -86.637702) (xy 84.417234 -86.618647) (xy 84.470487 -86.607054)
			(xy 84.524847 -86.603158) (xy 84.579209 -86.607039) (xy 84.632465 -86.618618) (xy 84.68353 -86.637658)
			(xy 84.731366 -86.663773) (xy 84.774998 -86.69643) (xy 84.813538 -86.734965) (xy 84.846201 -86.778592)
			(xy 84.872321 -86.826425) (xy 84.891368 -86.877488) (xy 84.902954 -86.930743) (xy 84.906842 -86.985104)
			(xy 86.1854 -86.985104) (xy 86.189287 -86.930753) (xy 86.200869 -86.877509) (xy 86.219911 -86.826455)
			(xy 86.246025 -86.77863) (xy 86.278679 -86.735009) (xy 86.317209 -86.696479) (xy 86.36083 -86.663825)
			(xy 86.408655 -86.637711) (xy 86.459709 -86.618669) (xy 86.512953 -86.607087) (xy 86.567304 -86.6032)
			(xy 86.621655 -86.607088) (xy 86.674899 -86.618671) (xy 86.725952 -86.637714) (xy 86.773776 -86.663829)
			(xy 86.795864 -86.679786) (xy 86.814876 -86.693382) (xy 86.856759 -86.714114) (xy 86.901727 -86.72684)
			(xy 86.948264 -86.73113) (xy 86.994801 -86.72684) (xy 87.039769 -86.714114) (xy 87.081652 -86.693382)
			(xy 87.100664 -86.679786) (xy 87.122759 -86.663831) (xy 87.170586 -86.637705) (xy 87.221645 -86.618653)
			(xy 87.274896 -86.607061) (xy 87.329255 -86.603167) (xy 87.383615 -86.607048) (xy 87.436868 -86.618628)
			(xy 87.487932 -86.637668) (xy 87.535766 -86.663783) (xy 87.579396 -86.696439) (xy 87.617934 -86.734973)
			(xy 87.650595 -86.778599) (xy 87.676715 -86.82643) (xy 87.695761 -86.877492) (xy 87.707346 -86.930744)
			(xy 87.711233 -86.985104) (xy 87.707345 -87.039463) (xy 87.695759 -87.092715) (xy 87.676712 -87.143776)
			(xy 87.650591 -87.191607) (xy 87.617929 -87.235233) (xy 87.57939 -87.273766) (xy 87.53576 -87.306421)
			(xy 87.487925 -87.332535) (xy 87.436861 -87.351575) (xy 87.383608 -87.363153) (xy 87.329248 -87.367033)
			(xy 87.274889 -87.363138) (xy 87.221638 -87.351545) (xy 87.17058 -87.332492) (xy 87.122753 -87.306365)
			(xy 87.100664 -87.290402) (xy 87.081652 -87.276806) (xy 87.039769 -87.256074) (xy 86.994801 -87.243348)
			(xy 86.948264 -87.239058) (xy 86.901727 -87.243348) (xy 86.856759 -87.256074) (xy 86.814876 -87.276806)
			(xy 86.795864 -87.290402) (xy 86.773782 -87.306367) (xy 86.725959 -87.332483) (xy 86.674906 -87.351527)
			(xy 86.621662 -87.363111) (xy 86.567311 -87.367) (xy 86.51296 -87.363114) (xy 86.459716 -87.351533)
			(xy 86.408661 -87.332492) (xy 86.360836 -87.306379) (xy 86.317215 -87.273726) (xy 86.278684 -87.235196)
			(xy 86.246029 -87.191576) (xy 86.219914 -87.143752) (xy 86.200871 -87.092698) (xy 86.189288 -87.039454)
			(xy 86.1854 -86.985104) (xy 84.906842 -86.985104) (xy 84.902953 -87.039465) (xy 84.891366 -87.092719)
			(xy 84.872318 -87.143782) (xy 84.846197 -87.191614) (xy 84.813533 -87.235241) (xy 84.774993 -87.273775)
			(xy 84.73136 -87.306431) (xy 84.683524 -87.332545) (xy 84.632458 -87.351584) (xy 84.579202 -87.363162)
			(xy 84.52484 -87.367042) (xy 84.470479 -87.363145) (xy 84.417227 -87.351551) (xy 84.366167 -87.332495)
			(xy 84.318339 -87.306366) (xy 84.29625 -87.290402) (xy 84.277238 -87.276806) (xy 84.235355 -87.256074)
			(xy 84.190387 -87.243348) (xy 84.14385 -87.239058) (xy 84.097313 -87.243348) (xy 84.052345 -87.256074)
			(xy 84.010462 -87.276806) (xy 83.99145 -87.290402) (xy 83.969366 -87.306374) (xy 83.921537 -87.332504)
			(xy 83.870476 -87.35156) (xy 83.817222 -87.363154) (xy 83.76286 -87.367051) (xy 83.708497 -87.363171)
			(xy 83.65524 -87.351594) (xy 83.604172 -87.332554) (xy 83.556335 -87.306439) (xy 83.512701 -87.273782)
			(xy 83.47416 -87.235247) (xy 83.441495 -87.191619) (xy 83.415373 -87.143786) (xy 83.396324 -87.092721)
			(xy 83.384738 -87.039466) (xy 83.380849 -86.985104) (xy 33.494124 -86.985104) (xy 34.375344 -87.86622)
			(xy 36.394136 -87.86622) (xy 37.086334 -88.558418) (xy 83.358065 -88.558418) (xy 83.361951 -88.504061)
			(xy 83.373533 -88.45081) (xy 83.392575 -88.399749) (xy 83.418691 -88.351919) (xy 83.451348 -88.308292)
			(xy 83.489882 -88.269757) (xy 83.533507 -88.237098) (xy 83.581337 -88.210981) (xy 83.632397 -88.191936)
			(xy 83.685647 -88.180353) (xy 83.740004 -88.176465) (xy 83.794361 -88.180354) (xy 83.847611 -88.191939)
			(xy 83.898671 -88.210984) (xy 83.9465 -88.237103) (xy 83.96859 -88.253062) (xy 83.987602 -88.266658)
			(xy 84.029485 -88.28739) (xy 84.074453 -88.300116) (xy 84.12099 -88.304406) (xy 84.167527 -88.300116)
			(xy 84.212495 -88.28739) (xy 84.254378 -88.266658) (xy 84.27339 -88.253062) (xy 84.295507 -88.237142)
			(xy 84.343331 -88.211023) (xy 84.394386 -88.191977) (xy 84.447632 -88.180391) (xy 84.501984 -88.176501)
			(xy 84.556337 -88.180387) (xy 84.609584 -88.191968) (xy 84.66064 -88.21101) (xy 84.708467 -88.237125)
			(xy 84.75209 -88.26978) (xy 84.790621 -88.308312) (xy 84.823277 -88.351935) (xy 84.849391 -88.399762)
			(xy 84.868432 -88.450818) (xy 84.880013 -88.504065) (xy 84.883899 -88.558418) (xy 86.162457 -88.558418)
			(xy 86.166343 -88.504059) (xy 86.177925 -88.450806) (xy 86.196968 -88.399744) (xy 86.223085 -88.351912)
			(xy 86.255744 -88.308284) (xy 86.294279 -88.269748) (xy 86.337907 -88.237088) (xy 86.385739 -88.210971)
			(xy 86.436801 -88.191927) (xy 86.490053 -88.180343) (xy 86.544412 -88.176457) (xy 86.598771 -88.180347)
			(xy 86.652023 -88.191933) (xy 86.703084 -88.210981) (xy 86.750914 -88.237102) (xy 86.773004 -88.253062)
			(xy 86.792016 -88.266658) (xy 86.833899 -88.28739) (xy 86.878867 -88.300116) (xy 86.925404 -88.304406)
			(xy 86.971941 -88.300116) (xy 87.016909 -88.28739) (xy 87.058792 -88.266658) (xy 87.077804 -88.253062)
			(xy 87.09992 -88.237143) (xy 87.147744 -88.211027) (xy 87.198797 -88.191983) (xy 87.252041 -88.180398)
			(xy 87.306392 -88.17651) (xy 87.360743 -88.180396) (xy 87.413988 -88.191978) (xy 87.465042 -88.21102)
			(xy 87.512867 -88.237134) (xy 87.556488 -88.269789) (xy 87.595017 -88.30832) (xy 87.627671 -88.351942)
			(xy 87.653784 -88.399767) (xy 87.672825 -88.450822) (xy 87.684405 -88.504067) (xy 87.68829 -88.558418)
			(xy 87.6844 -88.612769) (xy 87.672814 -88.666013) (xy 87.653769 -88.717066) (xy 87.627652 -88.764888)
			(xy 87.594994 -88.808507) (xy 87.556461 -88.847034) (xy 87.512836 -88.879685) (xy 87.465009 -88.905795)
			(xy 87.413953 -88.924832) (xy 87.360708 -88.936409) (xy 87.306356 -88.94029) (xy 87.252006 -88.936396)
			(xy 87.198763 -88.924807) (xy 87.147711 -88.905758) (xy 87.09989 -88.879638) (xy 87.077804 -88.863678)
			(xy 87.058792 -88.850082) (xy 87.016909 -88.82935) (xy 86.971941 -88.816624) (xy 86.925404 -88.812334)
			(xy 86.878867 -88.816624) (xy 86.833899 -88.82935) (xy 86.792016 -88.850082) (xy 86.773004 -88.863678)
			(xy 86.750944 -88.879679) (xy 86.703116 -88.905804) (xy 86.652057 -88.924856) (xy 86.598807 -88.936448)
			(xy 86.544448 -88.940343) (xy 86.490089 -88.936462) (xy 86.436835 -88.924884) (xy 86.385772 -88.905844)
			(xy 86.337937 -88.879731) (xy 86.294307 -88.847076) (xy 86.255768 -88.808543) (xy 86.223105 -88.764918)
			(xy 86.196983 -88.717089) (xy 86.177935 -88.666028) (xy 86.166348 -88.612777) (xy 86.162457 -88.558418)
			(xy 84.883899 -88.558418) (xy 84.880008 -88.612771) (xy 84.868422 -88.666016) (xy 84.849376 -88.717071)
			(xy 84.823257 -88.764895) (xy 84.790598 -88.808516) (xy 84.752063 -88.847043) (xy 84.708437 -88.879695)
			(xy 84.660608 -88.905805) (xy 84.609549 -88.924842) (xy 84.556302 -88.936418) (xy 84.501948 -88.940298)
			(xy 84.447596 -88.936404) (xy 84.394351 -88.924813) (xy 84.343298 -88.905762) (xy 84.295476 -88.879639)
			(xy 84.27339 -88.863678) (xy 84.254378 -88.850082) (xy 84.212495 -88.82935) (xy 84.167527 -88.816624)
			(xy 84.12099 -88.812334) (xy 84.074453 -88.816624) (xy 84.029485 -88.82935) (xy 83.987602 -88.850082)
			(xy 83.96859 -88.863678) (xy 83.94653 -88.879678) (xy 83.898704 -88.905801) (xy 83.847646 -88.924851)
			(xy 83.794397 -88.936441) (xy 83.74004 -88.940335) (xy 83.685683 -88.936452) (xy 83.632431 -88.924874)
			(xy 83.58137 -88.905834) (xy 83.533538 -88.879721) (xy 83.489909 -88.847067) (xy 83.451372 -88.808535)
			(xy 83.41871 -88.764911) (xy 83.39259 -88.717083) (xy 83.373543 -88.666025) (xy 83.361956 -88.612775)
			(xy 83.358065 -88.558418) (xy 37.086334 -88.558418) (xy 40.166544 -91.638628) (xy 40.166544 -91.896946)
			(xy 40.375332 -92.105734) (xy 40.375332 -94.0816) (xy 40.375846 -94.105143) (xy 40.384518 -94.151423)
			(xy 40.401566 -94.195314) (xy 40.426407 -94.235314) (xy 40.458191 -94.270054) (xy 40.495829 -94.298346)
			(xy 40.538034 -94.319221) (xy 40.583362 -94.331966) (xy 40.630262 -94.336144) (xy 40.677129 -94.331612)
			(xy 40.72236 -94.318525) (xy 40.743632 -94.308422) (xy 40.799496 -94.280945) (xy 40.914551 -94.233364)
			(xy 41.03281 -94.194422) (xy 41.153625 -94.164332) (xy 41.276335 -94.143261) (xy 41.338246 -94.136718)
			(xy 41.378471 -94.133122) (xy 41.459151 -94.129309) (xy 41.499536 -94.129098) (xy 41.556943 -94.129589)
			(xy 41.671488 -94.137426) (xy 41.785231 -94.153062) (xy 41.897643 -94.176423) (xy 42.008198 -94.207401)
			(xy 42.116381 -94.245851) (xy 42.221689 -94.291594) (xy 42.323629 -94.344417) (xy 42.421727 -94.404072)
			(xy 42.501043 -94.46006) (xy 63.647577 -94.46006) (xy 63.651612 -94.384356) (xy 63.663671 -94.309511)
			(xy 63.683617 -94.23637) (xy 63.711224 -94.165765) (xy 63.74618 -94.098494) (xy 63.788088 -94.035319)
			(xy 63.836474 -93.976957) (xy 63.89079 -93.924069) (xy 63.950419 -93.877254) (xy 64.014687 -93.837042)
			(xy 64.082864 -93.80389) (xy 64.15418 -93.778172) (xy 64.227825 -93.76018) (xy 64.302965 -93.750118)
			(xy 64.378749 -93.748099) (xy 64.454319 -93.754148) (xy 64.528817 -93.768195) (xy 64.6014 -93.790081)
			(xy 64.671246 -93.819558) (xy 64.737563 -93.856293) (xy 64.799599 -93.899868) (xy 64.856652 -93.94979)
			(xy 64.908076 -94.005494) (xy 64.953287 -94.066349) (xy 64.991774 -94.131664) (xy 65.0231 -94.2007)
			(xy 65.04691 -94.272675) (xy 65.062935 -94.346773) (xy 65.070994 -94.422154) (xy 65.071498 -94.46006)
			(xy 66.187577 -94.46006) (xy 66.191612 -94.384356) (xy 66.203671 -94.309511) (xy 66.223617 -94.23637)
			(xy 66.251224 -94.165765) (xy 66.28618 -94.098494) (xy 66.328088 -94.035319) (xy 66.376474 -93.976957)
			(xy 66.43079 -93.924069) (xy 66.490419 -93.877254) (xy 66.554687 -93.837042) (xy 66.622864 -93.80389)
			(xy 66.69418 -93.778172) (xy 66.767825 -93.76018) (xy 66.842965 -93.750118) (xy 66.918749 -93.748099)
			(xy 66.994319 -93.754148) (xy 67.068817 -93.768195) (xy 67.1414 -93.790081) (xy 67.211246 -93.819558)
			(xy 67.277563 -93.856293) (xy 67.339599 -93.899868) (xy 67.396652 -93.94979) (xy 67.448076 -94.005494)
			(xy 67.493287 -94.066349) (xy 67.531774 -94.131664) (xy 67.5631 -94.2007) (xy 67.58691 -94.272675)
			(xy 67.602935 -94.346773) (xy 67.610994 -94.422154) (xy 67.611498 -94.46006) (xy 68.727577 -94.46006)
			(xy 68.731612 -94.384356) (xy 68.743671 -94.309511) (xy 68.763617 -94.23637) (xy 68.791224 -94.165765)
			(xy 68.82618 -94.098494) (xy 68.868088 -94.035319) (xy 68.916474 -93.976957) (xy 68.97079 -93.924069)
			(xy 69.030419 -93.877254) (xy 69.094687 -93.837042) (xy 69.162864 -93.80389) (xy 69.23418 -93.778172)
			(xy 69.307825 -93.76018) (xy 69.382965 -93.750118) (xy 69.458749 -93.748099) (xy 69.534319 -93.754148)
			(xy 69.608817 -93.768195) (xy 69.6814 -93.790081) (xy 69.751246 -93.819558) (xy 69.817563 -93.856293)
			(xy 69.879599 -93.899868) (xy 69.936652 -93.94979) (xy 69.988076 -94.005494) (xy 70.033287 -94.066349)
			(xy 70.071774 -94.131664) (xy 70.1031 -94.2007) (xy 70.12691 -94.272675) (xy 70.142935 -94.346773)
			(xy 70.150994 -94.422154) (xy 70.151498 -94.46006) (xy 71.267577 -94.46006) (xy 71.271612 -94.384356)
			(xy 71.283671 -94.309511) (xy 71.303617 -94.23637) (xy 71.331224 -94.165765) (xy 71.36618 -94.098494)
			(xy 71.408088 -94.035319) (xy 71.456474 -93.976957) (xy 71.51079 -93.924069) (xy 71.570419 -93.877254)
			(xy 71.634687 -93.837042) (xy 71.702864 -93.80389) (xy 71.77418 -93.778172) (xy 71.847825 -93.76018)
			(xy 71.922965 -93.750118) (xy 71.998749 -93.748099) (xy 72.074319 -93.754148) (xy 72.148817 -93.768195)
			(xy 72.2214 -93.790081) (xy 72.291246 -93.819558) (xy 72.357563 -93.856293) (xy 72.419599 -93.899868)
			(xy 72.476652 -93.94979) (xy 72.528076 -94.005494) (xy 72.573287 -94.066349) (xy 72.611774 -94.131664)
			(xy 72.6431 -94.2007) (xy 72.66691 -94.272675) (xy 72.682935 -94.346773) (xy 72.690994 -94.422154)
			(xy 72.691498 -94.46006) (xy 73.807577 -94.46006) (xy 73.811612 -94.384356) (xy 73.823671 -94.309511)
			(xy 73.843617 -94.23637) (xy 73.871224 -94.165765) (xy 73.90618 -94.098494) (xy 73.948088 -94.035319)
			(xy 73.996474 -93.976957) (xy 74.05079 -93.924069) (xy 74.110419 -93.877254) (xy 74.174687 -93.837042)
			(xy 74.242864 -93.80389) (xy 74.31418 -93.778172) (xy 74.387825 -93.76018) (xy 74.462965 -93.750118)
			(xy 74.538749 -93.748099) (xy 74.614319 -93.754148) (xy 74.688817 -93.768195) (xy 74.7614 -93.790081)
			(xy 74.831246 -93.819558) (xy 74.897563 -93.856293) (xy 74.959599 -93.899868) (xy 75.016652 -93.94979)
			(xy 75.068076 -94.005494) (xy 75.113287 -94.066349) (xy 75.151774 -94.131664) (xy 75.1831 -94.2007)
			(xy 75.20691 -94.272675) (xy 75.222935 -94.346773) (xy 75.230994 -94.422154) (xy 75.231498 -94.46006)
			(xy 76.347577 -94.46006) (xy 76.351612 -94.384356) (xy 76.363671 -94.309511) (xy 76.383617 -94.23637)
			(xy 76.411224 -94.165765) (xy 76.44618 -94.098494) (xy 76.488088 -94.035319) (xy 76.536474 -93.976957)
			(xy 76.59079 -93.924069) (xy 76.650419 -93.877254) (xy 76.714687 -93.837042) (xy 76.782864 -93.80389)
			(xy 76.85418 -93.778172) (xy 76.927825 -93.76018) (xy 77.002965 -93.750118) (xy 77.078749 -93.748099)
			(xy 77.154319 -93.754148) (xy 77.228817 -93.768195) (xy 77.3014 -93.790081) (xy 77.371246 -93.819558)
			(xy 77.437563 -93.856293) (xy 77.499599 -93.899868) (xy 77.556652 -93.94979) (xy 77.608076 -94.005494)
			(xy 77.653287 -94.066349) (xy 77.691774 -94.131664) (xy 77.7231 -94.2007) (xy 77.74691 -94.272675)
			(xy 77.762935 -94.346773) (xy 77.770994 -94.422154) (xy 77.771498 -94.46006) (xy 78.887577 -94.46006)
			(xy 78.891612 -94.384356) (xy 78.903671 -94.309511) (xy 78.923617 -94.23637) (xy 78.951224 -94.165765)
			(xy 78.98618 -94.098494) (xy 79.028088 -94.035319) (xy 79.076474 -93.976957) (xy 79.13079 -93.924069)
			(xy 79.190419 -93.877254) (xy 79.254687 -93.837042) (xy 79.322864 -93.80389) (xy 79.39418 -93.778172)
			(xy 79.467825 -93.76018) (xy 79.542965 -93.750118) (xy 79.618749 -93.748099) (xy 79.694319 -93.754148)
			(xy 79.768817 -93.768195) (xy 79.8414 -93.790081) (xy 79.911246 -93.819558) (xy 79.977563 -93.856293)
			(xy 80.039599 -93.899868) (xy 80.096652 -93.94979) (xy 80.148076 -94.005494) (xy 80.193287 -94.066349)
			(xy 80.231774 -94.131664) (xy 80.2631 -94.2007) (xy 80.28691 -94.272675) (xy 80.302935 -94.346773)
			(xy 80.310994 -94.422154) (xy 80.311498 -94.46006) (xy 81.427577 -94.46006) (xy 81.431612 -94.384356)
			(xy 81.443671 -94.309511) (xy 81.463617 -94.23637) (xy 81.491224 -94.165765) (xy 81.52618 -94.098494)
			(xy 81.568088 -94.035319) (xy 81.616474 -93.976957) (xy 81.67079 -93.924069) (xy 81.730419 -93.877254)
			(xy 81.794687 -93.837042) (xy 81.862864 -93.80389) (xy 81.93418 -93.778172) (xy 82.007825 -93.76018)
			(xy 82.082965 -93.750118) (xy 82.158749 -93.748099) (xy 82.234319 -93.754148) (xy 82.308817 -93.768195)
			(xy 82.3814 -93.790081) (xy 82.451246 -93.819558) (xy 82.517563 -93.856293) (xy 82.579599 -93.899868)
			(xy 82.585544 -93.90507) (xy 86.197697 -93.90507) (xy 86.201732 -93.829366) (xy 86.213791 -93.754521)
			(xy 86.233737 -93.68138) (xy 86.261344 -93.610775) (xy 86.2963 -93.543504) (xy 86.338208 -93.480329)
			(xy 86.386594 -93.421967) (xy 86.44091 -93.369079) (xy 86.500539 -93.322264) (xy 86.564807 -93.282052)
			(xy 86.632984 -93.2489) (xy 86.7043 -93.223182) (xy 86.777945 -93.20519) (xy 86.853085 -93.195128)
			(xy 86.928869 -93.193109) (xy 87.004439 -93.199158) (xy 87.078937 -93.213205) (xy 87.15152 -93.235091)
			(xy 87.221366 -93.264568) (xy 87.287683 -93.301303) (xy 87.349719 -93.344878) (xy 87.406772 -93.3948)
			(xy 87.458196 -93.450504) (xy 87.503407 -93.511359) (xy 87.541894 -93.576674) (xy 87.57322 -93.64571)
			(xy 87.59703 -93.717685) (xy 87.613055 -93.791783) (xy 87.621114 -93.867164) (xy 87.621618 -93.90507)
			(xy 87.621114 -93.942976) (xy 87.613055 -94.018357) (xy 87.59703 -94.092455) (xy 87.57322 -94.16443)
			(xy 87.541894 -94.233466) (xy 87.503407 -94.298781) (xy 87.458196 -94.359636) (xy 87.406772 -94.41534)
			(xy 87.349719 -94.465262) (xy 87.287683 -94.508837) (xy 87.221366 -94.545572) (xy 87.15152 -94.575049)
			(xy 87.078937 -94.596935) (xy 87.004439 -94.610982) (xy 86.928869 -94.617031) (xy 86.853085 -94.615012)
			(xy 86.777945 -94.60495) (xy 86.7043 -94.586958) (xy 86.632984 -94.56124) (xy 86.564807 -94.528088)
			(xy 86.500539 -94.487876) (xy 86.44091 -94.441061) (xy 86.386594 -94.388173) (xy 86.338208 -94.329811)
			(xy 86.2963 -94.266636) (xy 86.261344 -94.199365) (xy 86.233737 -94.12876) (xy 86.213791 -94.055619)
			(xy 86.201732 -93.980774) (xy 86.197697 -93.90507) (xy 82.585544 -93.90507) (xy 82.636652 -93.94979)
			(xy 82.688076 -94.005494) (xy 82.733287 -94.066349) (xy 82.771774 -94.131664) (xy 82.8031 -94.2007)
			(xy 82.82691 -94.272675) (xy 82.842935 -94.346773) (xy 82.850994 -94.422154) (xy 82.851498 -94.46006)
			(xy 82.850994 -94.497966) (xy 82.842935 -94.573347) (xy 82.82691 -94.647445) (xy 82.8031 -94.71942)
			(xy 82.771774 -94.788456) (xy 82.733287 -94.853771) (xy 82.688076 -94.914626) (xy 82.636652 -94.97033)
			(xy 82.579599 -95.020252) (xy 82.517563 -95.063827) (xy 82.451246 -95.100562) (xy 82.3814 -95.130039)
			(xy 82.308817 -95.151925) (xy 82.234319 -95.165972) (xy 82.158749 -95.172021) (xy 82.082965 -95.170002)
			(xy 82.007825 -95.15994) (xy 81.93418 -95.141948) (xy 81.862864 -95.11623) (xy 81.794687 -95.083078)
			(xy 81.730419 -95.042866) (xy 81.67079 -94.996051) (xy 81.616474 -94.943163) (xy 81.568088 -94.884801)
			(xy 81.52618 -94.821626) (xy 81.491224 -94.754355) (xy 81.463617 -94.68375) (xy 81.443671 -94.610609)
			(xy 81.431612 -94.535764) (xy 81.427577 -94.46006) (xy 80.311498 -94.46006) (xy 80.310994 -94.497966)
			(xy 80.302935 -94.573347) (xy 80.28691 -94.647445) (xy 80.2631 -94.71942) (xy 80.231774 -94.788456)
			(xy 80.193287 -94.853771) (xy 80.148076 -94.914626) (xy 80.096652 -94.97033) (xy 80.039599 -95.020252)
			(xy 79.977563 -95.063827) (xy 79.911246 -95.100562) (xy 79.8414 -95.130039) (xy 79.768817 -95.151925)
			(xy 79.694319 -95.165972) (xy 79.618749 -95.172021) (xy 79.542965 -95.170002) (xy 79.467825 -95.15994)
			(xy 79.39418 -95.141948) (xy 79.322864 -95.11623) (xy 79.254687 -95.083078) (xy 79.190419 -95.042866)
			(xy 79.13079 -94.996051) (xy 79.076474 -94.943163) (xy 79.028088 -94.884801) (xy 78.98618 -94.821626)
			(xy 78.951224 -94.754355) (xy 78.923617 -94.68375) (xy 78.903671 -94.610609) (xy 78.891612 -94.535764)
			(xy 78.887577 -94.46006) (xy 77.771498 -94.46006) (xy 77.770994 -94.497966) (xy 77.762935 -94.573347)
			(xy 77.74691 -94.647445) (xy 77.7231 -94.71942) (xy 77.691774 -94.788456) (xy 77.653287 -94.853771)
			(xy 77.608076 -94.914626) (xy 77.556652 -94.97033) (xy 77.499599 -95.020252) (xy 77.437563 -95.063827)
			(xy 77.371246 -95.100562) (xy 77.3014 -95.130039) (xy 77.228817 -95.151925) (xy 77.154319 -95.165972)
			(xy 77.078749 -95.172021) (xy 77.002965 -95.170002) (xy 76.927825 -95.15994) (xy 76.85418 -95.141948)
			(xy 76.782864 -95.11623) (xy 76.714687 -95.083078) (xy 76.650419 -95.042866) (xy 76.59079 -94.996051)
			(xy 76.536474 -94.943163) (xy 76.488088 -94.884801) (xy 76.44618 -94.821626) (xy 76.411224 -94.754355)
			(xy 76.383617 -94.68375) (xy 76.363671 -94.610609) (xy 76.351612 -94.535764) (xy 76.347577 -94.46006)
			(xy 75.231498 -94.46006) (xy 75.230994 -94.497966) (xy 75.222935 -94.573347) (xy 75.20691 -94.647445)
			(xy 75.1831 -94.71942) (xy 75.151774 -94.788456) (xy 75.113287 -94.853771) (xy 75.068076 -94.914626)
			(xy 75.016652 -94.97033) (xy 74.959599 -95.020252) (xy 74.897563 -95.063827) (xy 74.831246 -95.100562)
			(xy 74.7614 -95.130039) (xy 74.688817 -95.151925) (xy 74.614319 -95.165972) (xy 74.538749 -95.172021)
			(xy 74.462965 -95.170002) (xy 74.387825 -95.15994) (xy 74.31418 -95.141948) (xy 74.242864 -95.11623)
			(xy 74.174687 -95.083078) (xy 74.110419 -95.042866) (xy 74.05079 -94.996051) (xy 73.996474 -94.943163)
			(xy 73.948088 -94.884801) (xy 73.90618 -94.821626) (xy 73.871224 -94.754355) (xy 73.843617 -94.68375)
			(xy 73.823671 -94.610609) (xy 73.811612 -94.535764) (xy 73.807577 -94.46006) (xy 72.691498 -94.46006)
			(xy 72.690994 -94.497966) (xy 72.682935 -94.573347) (xy 72.66691 -94.647445) (xy 72.6431 -94.71942)
			(xy 72.611774 -94.788456) (xy 72.573287 -94.853771) (xy 72.528076 -94.914626) (xy 72.476652 -94.97033)
			(xy 72.419599 -95.020252) (xy 72.357563 -95.063827) (xy 72.291246 -95.100562) (xy 72.2214 -95.130039)
			(xy 72.148817 -95.151925) (xy 72.074319 -95.165972) (xy 71.998749 -95.172021) (xy 71.922965 -95.170002)
			(xy 71.847825 -95.15994) (xy 71.77418 -95.141948) (xy 71.702864 -95.11623) (xy 71.634687 -95.083078)
			(xy 71.570419 -95.042866) (xy 71.51079 -94.996051) (xy 71.456474 -94.943163) (xy 71.408088 -94.884801)
			(xy 71.36618 -94.821626) (xy 71.331224 -94.754355) (xy 71.303617 -94.68375) (xy 71.283671 -94.610609)
			(xy 71.271612 -94.535764) (xy 71.267577 -94.46006) (xy 70.151498 -94.46006) (xy 70.150994 -94.497966)
			(xy 70.142935 -94.573347) (xy 70.12691 -94.647445) (xy 70.1031 -94.71942) (xy 70.071774 -94.788456)
			(xy 70.033287 -94.853771) (xy 69.988076 -94.914626) (xy 69.936652 -94.97033) (xy 69.879599 -95.020252)
			(xy 69.817563 -95.063827) (xy 69.751246 -95.100562) (xy 69.6814 -95.130039) (xy 69.608817 -95.151925)
			(xy 69.534319 -95.165972) (xy 69.458749 -95.172021) (xy 69.382965 -95.170002) (xy 69.307825 -95.15994)
			(xy 69.23418 -95.141948) (xy 69.162864 -95.11623) (xy 69.094687 -95.083078) (xy 69.030419 -95.042866)
			(xy 68.97079 -94.996051) (xy 68.916474 -94.943163) (xy 68.868088 -94.884801) (xy 68.82618 -94.821626)
			(xy 68.791224 -94.754355) (xy 68.763617 -94.68375) (xy 68.743671 -94.610609) (xy 68.731612 -94.535764)
			(xy 68.727577 -94.46006) (xy 67.611498 -94.46006) (xy 67.610994 -94.497966) (xy 67.602935 -94.573347)
			(xy 67.58691 -94.647445) (xy 67.5631 -94.71942) (xy 67.531774 -94.788456) (xy 67.493287 -94.853771)
			(xy 67.448076 -94.914626) (xy 67.396652 -94.97033) (xy 67.339599 -95.020252) (xy 67.277563 -95.063827)
			(xy 67.211246 -95.100562) (xy 67.1414 -95.130039) (xy 67.068817 -95.151925) (xy 66.994319 -95.165972)
			(xy 66.918749 -95.172021) (xy 66.842965 -95.170002) (xy 66.767825 -95.15994) (xy 66.69418 -95.141948)
			(xy 66.622864 -95.11623) (xy 66.554687 -95.083078) (xy 66.490419 -95.042866) (xy 66.43079 -94.996051)
			(xy 66.376474 -94.943163) (xy 66.328088 -94.884801) (xy 66.28618 -94.821626) (xy 66.251224 -94.754355)
			(xy 66.223617 -94.68375) (xy 66.203671 -94.610609) (xy 66.191612 -94.535764) (xy 66.187577 -94.46006)
			(xy 65.071498 -94.46006) (xy 65.070994 -94.497966) (xy 65.062935 -94.573347) (xy 65.04691 -94.647445)
			(xy 65.0231 -94.71942) (xy 64.991774 -94.788456) (xy 64.953287 -94.853771) (xy 64.908076 -94.914626)
			(xy 64.856652 -94.97033) (xy 64.799599 -95.020252) (xy 64.737563 -95.063827) (xy 64.671246 -95.100562)
			(xy 64.6014 -95.130039) (xy 64.528817 -95.151925) (xy 64.454319 -95.165972) (xy 64.378749 -95.172021)
			(xy 64.302965 -95.170002) (xy 64.227825 -95.15994) (xy 64.15418 -95.141948) (xy 64.082864 -95.11623)
			(xy 64.014687 -95.083078) (xy 63.950419 -95.042866) (xy 63.89079 -94.996051) (xy 63.836474 -94.943163)
			(xy 63.788088 -94.884801) (xy 63.74618 -94.821626) (xy 63.711224 -94.754355) (xy 63.683617 -94.68375)
			(xy 63.663671 -94.610609) (xy 63.651612 -94.535764) (xy 63.647577 -94.46006) (xy 42.501043 -94.46006)
			(xy 42.515526 -94.470283) (xy 42.604587 -94.542741) (xy 42.688497 -94.621107) (xy 42.766863 -94.705017)
			(xy 42.83932 -94.794079) (xy 42.905531 -94.887878) (xy 42.965186 -94.985976) (xy 43.018009 -95.087917)
			(xy 43.055865 -95.17507) (xy 84.927697 -95.17507) (xy 84.931732 -95.099366) (xy 84.943791 -95.024521)
			(xy 84.963737 -94.95138) (xy 84.991344 -94.880775) (xy 85.0263 -94.813504) (xy 85.068208 -94.750329)
			(xy 85.116594 -94.691967) (xy 85.17091 -94.639079) (xy 85.230539 -94.592264) (xy 85.294807 -94.552052)
			(xy 85.362984 -94.5189) (xy 85.4343 -94.493182) (xy 85.507945 -94.47519) (xy 85.583085 -94.465128)
			(xy 85.658869 -94.463109) (xy 85.734439 -94.469158) (xy 85.808937 -94.483205) (xy 85.88152 -94.505091)
			(xy 85.951366 -94.534568) (xy 86.017683 -94.571303) (xy 86.079719 -94.614878) (xy 86.136772 -94.6648)
			(xy 86.188196 -94.720504) (xy 86.233407 -94.781359) (xy 86.271894 -94.846674) (xy 86.30322 -94.91571)
			(xy 86.32703 -94.987685) (xy 86.343055 -95.061783) (xy 86.351114 -95.137164) (xy 86.351618 -95.17507)
			(xy 86.351114 -95.212976) (xy 86.343055 -95.288357) (xy 86.32703 -95.362455) (xy 86.30322 -95.43443)
			(xy 86.271894 -95.503466) (xy 86.233407 -95.568781) (xy 86.188196 -95.629636) (xy 86.136772 -95.68534)
			(xy 86.079719 -95.735262) (xy 86.017683 -95.778837) (xy 85.951366 -95.815572) (xy 85.88152 -95.845049)
			(xy 85.808937 -95.866935) (xy 85.734439 -95.880982) (xy 85.658869 -95.887031) (xy 85.583085 -95.885012)
			(xy 85.507945 -95.87495) (xy 85.4343 -95.856958) (xy 85.362984 -95.83124) (xy 85.294807 -95.798088)
			(xy 85.230539 -95.757876) (xy 85.17091 -95.711061) (xy 85.116594 -95.658173) (xy 85.068208 -95.599811)
			(xy 85.0263 -95.536636) (xy 84.991344 -95.469365) (xy 84.963737 -95.39876) (xy 84.943791 -95.325619)
			(xy 84.931732 -95.250774) (xy 84.927697 -95.17507) (xy 43.055865 -95.17507) (xy 43.063751 -95.193224)
			(xy 43.102201 -95.301408) (xy 43.133178 -95.411963) (xy 43.156539 -95.524374) (xy 43.172174 -95.638118)
			(xy 43.180011 -95.752663) (xy 43.180508 -95.81007) (xy 43.180428 -95.836885) (xy 43.178775 -95.890489)
			(xy 43.177206 -95.917258) (xy 43.177206 -95.917512) (xy 43.175428 -95.942658) (xy 43.170488 -95.999072)
			(xy 43.153973 -96.111116) (xy 43.129954 -96.221795) (xy 43.098541 -96.330606) (xy 43.059875 -96.437056)
			(xy 43.056337 -96.44507) (xy 86.197697 -96.44507) (xy 86.201732 -96.369366) (xy 86.213791 -96.294521)
			(xy 86.233737 -96.22138) (xy 86.261344 -96.150775) (xy 86.2963 -96.083504) (xy 86.338208 -96.020329)
			(xy 86.386594 -95.961967) (xy 86.44091 -95.909079) (xy 86.500539 -95.862264) (xy 86.564807 -95.822052)
			(xy 86.632984 -95.7889) (xy 86.7043 -95.763182) (xy 86.777945 -95.74519) (xy 86.853085 -95.735128)
			(xy 86.928869 -95.733109) (xy 87.004439 -95.739158) (xy 87.078937 -95.753205) (xy 87.15152 -95.775091)
			(xy 87.221366 -95.804568) (xy 87.287683 -95.841303) (xy 87.349719 -95.884878) (xy 87.406772 -95.9348)
			(xy 87.458196 -95.990504) (xy 87.503407 -96.051359) (xy 87.541894 -96.116674) (xy 87.57322 -96.18571)
			(xy 87.59703 -96.257685) (xy 87.613055 -96.331783) (xy 87.621114 -96.407164) (xy 87.621618 -96.44507)
			(xy 87.621114 -96.482976) (xy 87.613055 -96.558357) (xy 87.59703 -96.632455) (xy 87.57322 -96.70443)
			(xy 87.541894 -96.773466) (xy 87.503407 -96.838781) (xy 87.458196 -96.899636) (xy 87.406772 -96.95534)
			(xy 87.349719 -97.005262) (xy 87.287683 -97.048837) (xy 87.221366 -97.085572) (xy 87.15152 -97.115049)
			(xy 87.078937 -97.136935) (xy 87.004439 -97.150982) (xy 86.928869 -97.157031) (xy 86.853085 -97.155012)
			(xy 86.777945 -97.14495) (xy 86.7043 -97.126958) (xy 86.632984 -97.10124) (xy 86.564807 -97.068088)
			(xy 86.500539 -97.027876) (xy 86.44091 -96.981061) (xy 86.386594 -96.928173) (xy 86.338208 -96.869811)
			(xy 86.2963 -96.806636) (xy 86.261344 -96.739365) (xy 86.233737 -96.66876) (xy 86.213791 -96.595619)
			(xy 86.201732 -96.520774) (xy 86.197697 -96.44507) (xy 43.056337 -96.44507) (xy 43.014133 -96.540662)
			(xy 42.96152 -96.640955) (xy 42.902277 -96.737479) (xy 42.836672 -96.829797) (xy 42.765002 -96.91749)
			(xy 42.687592 -97.000161) (xy 42.604793 -97.077434) (xy 42.516982 -97.148958) (xy 42.501276 -97.16008)
			(xy 63.647577 -97.16008) (xy 63.651612 -97.084376) (xy 63.663671 -97.009531) (xy 63.683617 -96.93639)
			(xy 63.711224 -96.865785) (xy 63.74618 -96.798514) (xy 63.788088 -96.735339) (xy 63.836474 -96.676977)
			(xy 63.89079 -96.624089) (xy 63.950419 -96.577274) (xy 64.014687 -96.537062) (xy 64.082864 -96.50391)
			(xy 64.15418 -96.478192) (xy 64.227825 -96.4602) (xy 64.302965 -96.450138) (xy 64.378749 -96.448119)
			(xy 64.454319 -96.454168) (xy 64.528817 -96.468215) (xy 64.6014 -96.490101) (xy 64.671246 -96.519578)
			(xy 64.737563 -96.556313) (xy 64.799599 -96.599888) (xy 64.856652 -96.64981) (xy 64.908076 -96.705514)
			(xy 64.953287 -96.766369) (xy 64.991774 -96.831684) (xy 65.0231 -96.90072) (xy 65.04691 -96.972695)
			(xy 65.062935 -97.046793) (xy 65.070994 -97.122174) (xy 65.071498 -97.16008) (xy 66.187577 -97.16008)
			(xy 66.191612 -97.084376) (xy 66.203671 -97.009531) (xy 66.223617 -96.93639) (xy 66.251224 -96.865785)
			(xy 66.28618 -96.798514) (xy 66.328088 -96.735339) (xy 66.376474 -96.676977) (xy 66.43079 -96.624089)
			(xy 66.490419 -96.577274) (xy 66.554687 -96.537062) (xy 66.622864 -96.50391) (xy 66.69418 -96.478192)
			(xy 66.767825 -96.4602) (xy 66.842965 -96.450138) (xy 66.918749 -96.448119) (xy 66.994319 -96.454168)
			(xy 67.068817 -96.468215) (xy 67.1414 -96.490101) (xy 67.211246 -96.519578) (xy 67.277563 -96.556313)
			(xy 67.339599 -96.599888) (xy 67.396652 -96.64981) (xy 67.448076 -96.705514) (xy 67.493287 -96.766369)
			(xy 67.531774 -96.831684) (xy 67.5631 -96.90072) (xy 67.58691 -96.972695) (xy 67.602935 -97.046793)
			(xy 67.610994 -97.122174) (xy 67.611498 -97.16008) (xy 68.727577 -97.16008) (xy 68.731612 -97.084376)
			(xy 68.743671 -97.009531) (xy 68.763617 -96.93639) (xy 68.791224 -96.865785) (xy 68.82618 -96.798514)
			(xy 68.868088 -96.735339) (xy 68.916474 -96.676977) (xy 68.97079 -96.624089) (xy 69.030419 -96.577274)
			(xy 69.094687 -96.537062) (xy 69.162864 -96.50391) (xy 69.23418 -96.478192) (xy 69.307825 -96.4602)
			(xy 69.382965 -96.450138) (xy 69.458749 -96.448119) (xy 69.534319 -96.454168) (xy 69.608817 -96.468215)
			(xy 69.6814 -96.490101) (xy 69.751246 -96.519578) (xy 69.817563 -96.556313) (xy 69.879599 -96.599888)
			(xy 69.936652 -96.64981) (xy 69.988076 -96.705514) (xy 70.033287 -96.766369) (xy 70.071774 -96.831684)
			(xy 70.1031 -96.90072) (xy 70.12691 -96.972695) (xy 70.142935 -97.046793) (xy 70.150994 -97.122174)
			(xy 70.151498 -97.16008) (xy 71.267577 -97.16008) (xy 71.271612 -97.084376) (xy 71.283671 -97.009531)
			(xy 71.303617 -96.93639) (xy 71.331224 -96.865785) (xy 71.36618 -96.798514) (xy 71.408088 -96.735339)
			(xy 71.456474 -96.676977) (xy 71.51079 -96.624089) (xy 71.570419 -96.577274) (xy 71.634687 -96.537062)
			(xy 71.702864 -96.50391) (xy 71.77418 -96.478192) (xy 71.847825 -96.4602) (xy 71.922965 -96.450138)
			(xy 71.998749 -96.448119) (xy 72.074319 -96.454168) (xy 72.148817 -96.468215) (xy 72.2214 -96.490101)
			(xy 72.291246 -96.519578) (xy 72.357563 -96.556313) (xy 72.419599 -96.599888) (xy 72.476652 -96.64981)
			(xy 72.528076 -96.705514) (xy 72.573287 -96.766369) (xy 72.611774 -96.831684) (xy 72.6431 -96.90072)
			(xy 72.66691 -96.972695) (xy 72.682935 -97.046793) (xy 72.690994 -97.122174) (xy 72.691498 -97.16008)
			(xy 73.807577 -97.16008) (xy 73.811612 -97.084376) (xy 73.823671 -97.009531) (xy 73.843617 -96.93639)
			(xy 73.871224 -96.865785) (xy 73.90618 -96.798514) (xy 73.948088 -96.735339) (xy 73.996474 -96.676977)
			(xy 74.05079 -96.624089) (xy 74.110419 -96.577274) (xy 74.174687 -96.537062) (xy 74.242864 -96.50391)
			(xy 74.31418 -96.478192) (xy 74.387825 -96.4602) (xy 74.462965 -96.450138) (xy 74.538749 -96.448119)
			(xy 74.614319 -96.454168) (xy 74.688817 -96.468215) (xy 74.7614 -96.490101) (xy 74.831246 -96.519578)
			(xy 74.897563 -96.556313) (xy 74.959599 -96.599888) (xy 75.016652 -96.64981) (xy 75.068076 -96.705514)
			(xy 75.113287 -96.766369) (xy 75.151774 -96.831684) (xy 75.1831 -96.90072) (xy 75.20691 -96.972695)
			(xy 75.222935 -97.046793) (xy 75.230994 -97.122174) (xy 75.231498 -97.16008) (xy 76.347577 -97.16008)
			(xy 76.351612 -97.084376) (xy 76.363671 -97.009531) (xy 76.383617 -96.93639) (xy 76.411224 -96.865785)
			(xy 76.44618 -96.798514) (xy 76.488088 -96.735339) (xy 76.536474 -96.676977) (xy 76.59079 -96.624089)
			(xy 76.650419 -96.577274) (xy 76.714687 -96.537062) (xy 76.782864 -96.50391) (xy 76.85418 -96.478192)
			(xy 76.927825 -96.4602) (xy 77.002965 -96.450138) (xy 77.078749 -96.448119) (xy 77.154319 -96.454168)
			(xy 77.228817 -96.468215) (xy 77.3014 -96.490101) (xy 77.371246 -96.519578) (xy 77.437563 -96.556313)
			(xy 77.499599 -96.599888) (xy 77.556652 -96.64981) (xy 77.608076 -96.705514) (xy 77.653287 -96.766369)
			(xy 77.691774 -96.831684) (xy 77.7231 -96.90072) (xy 77.74691 -96.972695) (xy 77.762935 -97.046793)
			(xy 77.770994 -97.122174) (xy 77.771498 -97.16008) (xy 78.887577 -97.16008) (xy 78.891612 -97.084376)
			(xy 78.903671 -97.009531) (xy 78.923617 -96.93639) (xy 78.951224 -96.865785) (xy 78.98618 -96.798514)
			(xy 79.028088 -96.735339) (xy 79.076474 -96.676977) (xy 79.13079 -96.624089) (xy 79.190419 -96.577274)
			(xy 79.254687 -96.537062) (xy 79.322864 -96.50391) (xy 79.39418 -96.478192) (xy 79.467825 -96.4602)
			(xy 79.542965 -96.450138) (xy 79.618749 -96.448119) (xy 79.694319 -96.454168) (xy 79.768817 -96.468215)
			(xy 79.8414 -96.490101) (xy 79.911246 -96.519578) (xy 79.977563 -96.556313) (xy 80.039599 -96.599888)
			(xy 80.096652 -96.64981) (xy 80.148076 -96.705514) (xy 80.193287 -96.766369) (xy 80.231774 -96.831684)
			(xy 80.2631 -96.90072) (xy 80.28691 -96.972695) (xy 80.302935 -97.046793) (xy 80.310994 -97.122174)
			(xy 80.311498 -97.16008) (xy 81.427577 -97.16008) (xy 81.431612 -97.084376) (xy 81.443671 -97.009531)
			(xy 81.463617 -96.93639) (xy 81.491224 -96.865785) (xy 81.52618 -96.798514) (xy 81.568088 -96.735339)
			(xy 81.616474 -96.676977) (xy 81.67079 -96.624089) (xy 81.730419 -96.577274) (xy 81.794687 -96.537062)
			(xy 81.862864 -96.50391) (xy 81.93418 -96.478192) (xy 82.007825 -96.4602) (xy 82.082965 -96.450138)
			(xy 82.158749 -96.448119) (xy 82.234319 -96.454168) (xy 82.308817 -96.468215) (xy 82.3814 -96.490101)
			(xy 82.451246 -96.519578) (xy 82.517563 -96.556313) (xy 82.579599 -96.599888) (xy 82.636652 -96.64981)
			(xy 82.688076 -96.705514) (xy 82.733287 -96.766369) (xy 82.771774 -96.831684) (xy 82.8031 -96.90072)
			(xy 82.82691 -96.972695) (xy 82.842935 -97.046793) (xy 82.850994 -97.122174) (xy 82.851498 -97.16008)
			(xy 82.850994 -97.197986) (xy 82.842935 -97.273367) (xy 82.82691 -97.347465) (xy 82.8031 -97.41944)
			(xy 82.771774 -97.488476) (xy 82.733287 -97.553791) (xy 82.688076 -97.614646) (xy 82.636652 -97.67035)
			(xy 82.585544 -97.71507) (xy 84.927697 -97.71507) (xy 84.931732 -97.639366) (xy 84.943791 -97.564521)
			(xy 84.963737 -97.49138) (xy 84.991344 -97.420775) (xy 85.0263 -97.353504) (xy 85.068208 -97.290329)
			(xy 85.116594 -97.231967) (xy 85.17091 -97.179079) (xy 85.230539 -97.132264) (xy 85.294807 -97.092052)
			(xy 85.362984 -97.0589) (xy 85.4343 -97.033182) (xy 85.507945 -97.01519) (xy 85.583085 -97.005128)
			(xy 85.658869 -97.003109) (xy 85.734439 -97.009158) (xy 85.808937 -97.023205) (xy 85.88152 -97.045091)
			(xy 85.951366 -97.074568) (xy 86.017683 -97.111303) (xy 86.079719 -97.154878) (xy 86.136772 -97.2048)
			(xy 86.188196 -97.260504) (xy 86.233407 -97.321359) (xy 86.271894 -97.386674) (xy 86.30322 -97.45571)
			(xy 86.32703 -97.527685) (xy 86.343055 -97.601783) (xy 86.351114 -97.677164) (xy 86.351618 -97.71507)
			(xy 87.467697 -97.71507) (xy 87.471732 -97.639366) (xy 87.483791 -97.564521) (xy 87.503737 -97.49138)
			(xy 87.531344 -97.420775) (xy 87.5663 -97.353504) (xy 87.608208 -97.290329) (xy 87.656594 -97.231967)
			(xy 87.71091 -97.179079) (xy 87.770539 -97.132264) (xy 87.834807 -97.092052) (xy 87.902984 -97.0589)
			(xy 87.9743 -97.033182) (xy 88.047945 -97.01519) (xy 88.123085 -97.005128) (xy 88.198869 -97.003109)
			(xy 88.274439 -97.009158) (xy 88.348937 -97.023205) (xy 88.42152 -97.045091) (xy 88.491366 -97.074568)
			(xy 88.557683 -97.111303) (xy 88.619719 -97.154878) (xy 88.676772 -97.2048) (xy 88.728196 -97.260504)
			(xy 88.773407 -97.321359) (xy 88.811894 -97.386674) (xy 88.84322 -97.45571) (xy 88.86703 -97.527685)
			(xy 88.883055 -97.601783) (xy 88.891114 -97.677164) (xy 88.891618 -97.71507) (xy 90.007697 -97.71507)
			(xy 90.011732 -97.639366) (xy 90.023791 -97.564521) (xy 90.043737 -97.49138) (xy 90.071344 -97.420775)
			(xy 90.1063 -97.353504) (xy 90.148208 -97.290329) (xy 90.196594 -97.231967) (xy 90.25091 -97.179079)
			(xy 90.310539 -97.132264) (xy 90.374807 -97.092052) (xy 90.442984 -97.0589) (xy 90.5143 -97.033182)
			(xy 90.587945 -97.01519) (xy 90.663085 -97.005128) (xy 90.738869 -97.003109) (xy 90.814439 -97.009158)
			(xy 90.888937 -97.023205) (xy 90.96152 -97.045091) (xy 91.031366 -97.074568) (xy 91.097683 -97.111303)
			(xy 91.159719 -97.154878) (xy 91.165664 -97.16008) (xy 93.154506 -97.16008) (xy 93.158522 -97.04381)
			(xy 93.170549 -96.928095) (xy 93.190531 -96.813485) (xy 93.218373 -96.700526) (xy 93.253942 -96.589758)
			(xy 93.297068 -96.481707) (xy 93.347545 -96.376889) (xy 93.405134 -96.275804) (xy 93.46956 -96.178932)
			(xy 93.540515 -96.086736) (xy 93.617662 -95.999655) (xy 93.700633 -95.918104) (xy 93.789033 -95.842472)
			(xy 93.88244 -95.773118) (xy 93.980409 -95.710375) (xy 94.082473 -95.654539) (xy 94.188147 -95.605878)
			(xy 94.296926 -95.564624) (xy 94.408291 -95.530973) (xy 94.521714 -95.505085) (xy 94.636651 -95.487084)
			(xy 94.752557 -95.477055) (xy 94.868879 -95.475047) (xy 94.985062 -95.481069) (xy 95.100553 -95.495092)
			(xy 95.214801 -95.51705) (xy 95.327262 -95.546837) (xy 95.4374 -95.584312) (xy 95.54469 -95.629297)
			(xy 95.648621 -95.681576) (xy 95.748697 -95.740901) (xy 95.844443 -95.806989) (xy 95.9354 -95.879525)
			(xy 96.021136 -95.958164) (xy 96.101243 -96.04253) (xy 96.175339 -96.132222) (xy 96.243069 -96.226812)
			(xy 96.304113 -96.32585) (xy 96.358178 -96.428863) (xy 96.405008 -96.53536) (xy 96.444379 -96.644835)
			(xy 96.476103 -96.756765) (xy 96.500029 -96.870617) (xy 96.516043 -96.985849) (xy 96.52407 -97.101911)
			(xy 96.524572 -97.16008) (xy 96.52407 -97.218249) (xy 96.516043 -97.334311) (xy 96.500029 -97.449543)
			(xy 96.476103 -97.563395) (xy 96.444379 -97.675325) (xy 96.405008 -97.7848) (xy 96.358178 -97.891297)
			(xy 96.304113 -97.99431) (xy 96.243069 -98.093348) (xy 96.175339 -98.187938) (xy 96.101243 -98.27763)
			(xy 96.021136 -98.361996) (xy 95.9354 -98.440635) (xy 95.844443 -98.513171) (xy 95.748697 -98.579259)
			(xy 95.648621 -98.638584) (xy 95.54469 -98.690863) (xy 95.4374 -98.735848) (xy 95.327262 -98.773323)
			(xy 95.214801 -98.80311) (xy 95.100553 -98.825068) (xy 94.985062 -98.839091) (xy 94.868879 -98.845113)
			(xy 94.752557 -98.843105) (xy 94.636651 -98.833076) (xy 94.521714 -98.815075) (xy 94.408291 -98.789187)
			(xy 94.296926 -98.755536) (xy 94.188147 -98.714282) (xy 94.082473 -98.665621) (xy 93.980409 -98.609785)
			(xy 93.88244 -98.547042) (xy 93.789033 -98.477688) (xy 93.700633 -98.402056) (xy 93.617662 -98.320505)
			(xy 93.540515 -98.233424) (xy 93.46956 -98.141228) (xy 93.405134 -98.044356) (xy 93.347545 -97.943271)
			(xy 93.297068 -97.838453) (xy 93.253942 -97.730402) (xy 93.218373 -97.619634) (xy 93.190531 -97.506675)
			(xy 93.170549 -97.392065) (xy 93.158522 -97.27635) (xy 93.154506 -97.16008) (xy 91.165664 -97.16008)
			(xy 91.216772 -97.2048) (xy 91.268196 -97.260504) (xy 91.313407 -97.321359) (xy 91.351894 -97.386674)
			(xy 91.38322 -97.45571) (xy 91.40703 -97.527685) (xy 91.423055 -97.601783) (xy 91.431114 -97.677164)
			(xy 91.431618 -97.71507) (xy 91.431114 -97.752976) (xy 91.423055 -97.828357) (xy 91.40703 -97.902455)
			(xy 91.38322 -97.97443) (xy 91.351894 -98.043466) (xy 91.313407 -98.108781) (xy 91.268196 -98.169636)
			(xy 91.216772 -98.22534) (xy 91.159719 -98.275262) (xy 91.097683 -98.318837) (xy 91.031366 -98.355572)
			(xy 90.96152 -98.385049) (xy 90.888937 -98.406935) (xy 90.814439 -98.420982) (xy 90.738869 -98.427031)
			(xy 90.663085 -98.425012) (xy 90.587945 -98.41495) (xy 90.5143 -98.396958) (xy 90.442984 -98.37124)
			(xy 90.374807 -98.338088) (xy 90.310539 -98.297876) (xy 90.25091 -98.251061) (xy 90.196594 -98.198173)
			(xy 90.148208 -98.139811) (xy 90.1063 -98.076636) (xy 90.071344 -98.009365) (xy 90.043737 -97.93876)
			(xy 90.023791 -97.865619) (xy 90.011732 -97.790774) (xy 90.007697 -97.71507) (xy 88.891618 -97.71507)
			(xy 88.891114 -97.752976) (xy 88.883055 -97.828357) (xy 88.86703 -97.902455) (xy 88.84322 -97.97443)
			(xy 88.811894 -98.043466) (xy 88.773407 -98.108781) (xy 88.728196 -98.169636) (xy 88.676772 -98.22534)
			(xy 88.619719 -98.275262) (xy 88.557683 -98.318837) (xy 88.491366 -98.355572) (xy 88.42152 -98.385049)
			(xy 88.348937 -98.406935) (xy 88.274439 -98.420982) (xy 88.198869 -98.427031) (xy 88.123085 -98.425012)
			(xy 88.047945 -98.41495) (xy 87.9743 -98.396958) (xy 87.902984 -98.37124) (xy 87.834807 -98.338088)
			(xy 87.770539 -98.297876) (xy 87.71091 -98.251061) (xy 87.656594 -98.198173) (xy 87.608208 -98.139811)
			(xy 87.5663 -98.076636) (xy 87.531344 -98.009365) (xy 87.503737 -97.93876) (xy 87.483791 -97.865619)
			(xy 87.471732 -97.790774) (xy 87.467697 -97.71507) (xy 86.351618 -97.71507) (xy 86.351114 -97.752976)
			(xy 86.343055 -97.828357) (xy 86.32703 -97.902455) (xy 86.30322 -97.97443) (xy 86.271894 -98.043466)
			(xy 86.233407 -98.108781) (xy 86.188196 -98.169636) (xy 86.136772 -98.22534) (xy 86.079719 -98.275262)
			(xy 86.017683 -98.318837) (xy 85.951366 -98.355572) (xy 85.88152 -98.385049) (xy 85.808937 -98.406935)
			(xy 85.734439 -98.420982) (xy 85.658869 -98.427031) (xy 85.583085 -98.425012) (xy 85.507945 -98.41495)
			(xy 85.4343 -98.396958) (xy 85.362984 -98.37124) (xy 85.294807 -98.338088) (xy 85.230539 -98.297876)
			(xy 85.17091 -98.251061) (xy 85.116594 -98.198173) (xy 85.068208 -98.139811) (xy 85.0263 -98.076636)
			(xy 84.991344 -98.009365) (xy 84.963737 -97.93876) (xy 84.943791 -97.865619) (xy 84.931732 -97.790774)
			(xy 84.927697 -97.71507) (xy 82.585544 -97.71507) (xy 82.579599 -97.720272) (xy 82.517563 -97.763847)
			(xy 82.451246 -97.800582) (xy 82.3814 -97.830059) (xy 82.308817 -97.851945) (xy 82.234319 -97.865992)
			(xy 82.158749 -97.872041) (xy 82.082965 -97.870022) (xy 82.007825 -97.85996) (xy 81.93418 -97.841968)
			(xy 81.862864 -97.81625) (xy 81.794687 -97.783098) (xy 81.730419 -97.742886) (xy 81.67079 -97.696071)
			(xy 81.616474 -97.643183) (xy 81.568088 -97.584821) (xy 81.52618 -97.521646) (xy 81.491224 -97.454375)
			(xy 81.463617 -97.38377) (xy 81.443671 -97.310629) (xy 81.431612 -97.235784) (xy 81.427577 -97.16008)
			(xy 80.311498 -97.16008) (xy 80.310994 -97.197986) (xy 80.302935 -97.273367) (xy 80.28691 -97.347465)
			(xy 80.2631 -97.41944) (xy 80.231774 -97.488476) (xy 80.193287 -97.553791) (xy 80.148076 -97.614646)
			(xy 80.096652 -97.67035) (xy 80.039599 -97.720272) (xy 79.977563 -97.763847) (xy 79.911246 -97.800582)
			(xy 79.8414 -97.830059) (xy 79.768817 -97.851945) (xy 79.694319 -97.865992) (xy 79.618749 -97.872041)
			(xy 79.542965 -97.870022) (xy 79.467825 -97.85996) (xy 79.39418 -97.841968) (xy 79.322864 -97.81625)
			(xy 79.254687 -97.783098) (xy 79.190419 -97.742886) (xy 79.13079 -97.696071) (xy 79.076474 -97.643183)
			(xy 79.028088 -97.584821) (xy 78.98618 -97.521646) (xy 78.951224 -97.454375) (xy 78.923617 -97.38377)
			(xy 78.903671 -97.310629) (xy 78.891612 -97.235784) (xy 78.887577 -97.16008) (xy 77.771498 -97.16008)
			(xy 77.770994 -97.197986) (xy 77.762935 -97.273367) (xy 77.74691 -97.347465) (xy 77.7231 -97.41944)
			(xy 77.691774 -97.488476) (xy 77.653287 -97.553791) (xy 77.608076 -97.614646) (xy 77.556652 -97.67035)
			(xy 77.499599 -97.720272) (xy 77.437563 -97.763847) (xy 77.371246 -97.800582) (xy 77.3014 -97.830059)
			(xy 77.228817 -97.851945) (xy 77.154319 -97.865992) (xy 77.078749 -97.872041) (xy 77.002965 -97.870022)
			(xy 76.927825 -97.85996) (xy 76.85418 -97.841968) (xy 76.782864 -97.81625) (xy 76.714687 -97.783098)
			(xy 76.650419 -97.742886) (xy 76.59079 -97.696071) (xy 76.536474 -97.643183) (xy 76.488088 -97.584821)
			(xy 76.44618 -97.521646) (xy 76.411224 -97.454375) (xy 76.383617 -97.38377) (xy 76.363671 -97.310629)
			(xy 76.351612 -97.235784) (xy 76.347577 -97.16008) (xy 75.231498 -97.16008) (xy 75.230994 -97.197986)
			(xy 75.222935 -97.273367) (xy 75.20691 -97.347465) (xy 75.1831 -97.41944) (xy 75.151774 -97.488476)
			(xy 75.113287 -97.553791) (xy 75.068076 -97.614646) (xy 75.016652 -97.67035) (xy 74.959599 -97.720272)
			(xy 74.897563 -97.763847) (xy 74.831246 -97.800582) (xy 74.7614 -97.830059) (xy 74.688817 -97.851945)
			(xy 74.614319 -97.865992) (xy 74.538749 -97.872041) (xy 74.462965 -97.870022) (xy 74.387825 -97.85996)
			(xy 74.31418 -97.841968) (xy 74.242864 -97.81625) (xy 74.174687 -97.783098) (xy 74.110419 -97.742886)
			(xy 74.05079 -97.696071) (xy 73.996474 -97.643183) (xy 73.948088 -97.584821) (xy 73.90618 -97.521646)
			(xy 73.871224 -97.454375) (xy 73.843617 -97.38377) (xy 73.823671 -97.310629) (xy 73.811612 -97.235784)
			(xy 73.807577 -97.16008) (xy 72.691498 -97.16008) (xy 72.690994 -97.197986) (xy 72.682935 -97.273367)
			(xy 72.66691 -97.347465) (xy 72.6431 -97.41944) (xy 72.611774 -97.488476) (xy 72.573287 -97.553791)
			(xy 72.528076 -97.614646) (xy 72.476652 -97.67035) (xy 72.419599 -97.720272) (xy 72.357563 -97.763847)
			(xy 72.291246 -97.800582) (xy 72.2214 -97.830059) (xy 72.148817 -97.851945) (xy 72.074319 -97.865992)
			(xy 71.998749 -97.872041) (xy 71.922965 -97.870022) (xy 71.847825 -97.85996) (xy 71.77418 -97.841968)
			(xy 71.702864 -97.81625) (xy 71.634687 -97.783098) (xy 71.570419 -97.742886) (xy 71.51079 -97.696071)
			(xy 71.456474 -97.643183) (xy 71.408088 -97.584821) (xy 71.36618 -97.521646) (xy 71.331224 -97.454375)
			(xy 71.303617 -97.38377) (xy 71.283671 -97.310629) (xy 71.271612 -97.235784) (xy 71.267577 -97.16008)
			(xy 70.151498 -97.16008) (xy 70.150994 -97.197986) (xy 70.142935 -97.273367) (xy 70.12691 -97.347465)
			(xy 70.1031 -97.41944) (xy 70.071774 -97.488476) (xy 70.033287 -97.553791) (xy 69.988076 -97.614646)
			(xy 69.936652 -97.67035) (xy 69.879599 -97.720272) (xy 69.817563 -97.763847) (xy 69.751246 -97.800582)
			(xy 69.6814 -97.830059) (xy 69.608817 -97.851945) (xy 69.534319 -97.865992) (xy 69.458749 -97.872041)
			(xy 69.382965 -97.870022) (xy 69.307825 -97.85996) (xy 69.23418 -97.841968) (xy 69.162864 -97.81625)
			(xy 69.094687 -97.783098) (xy 69.030419 -97.742886) (xy 68.97079 -97.696071) (xy 68.916474 -97.643183)
			(xy 68.868088 -97.584821) (xy 68.82618 -97.521646) (xy 68.791224 -97.454375) (xy 68.763617 -97.38377)
			(xy 68.743671 -97.310629) (xy 68.731612 -97.235784) (xy 68.727577 -97.16008) (xy 67.611498 -97.16008)
			(xy 67.610994 -97.197986) (xy 67.602935 -97.273367) (xy 67.58691 -97.347465) (xy 67.5631 -97.41944)
			(xy 67.531774 -97.488476) (xy 67.493287 -97.553791) (xy 67.448076 -97.614646) (xy 67.396652 -97.67035)
			(xy 67.339599 -97.720272) (xy 67.277563 -97.763847) (xy 67.211246 -97.800582) (xy 67.1414 -97.830059)
			(xy 67.068817 -97.851945) (xy 66.994319 -97.865992) (xy 66.918749 -97.872041) (xy 66.842965 -97.870022)
			(xy 66.767825 -97.85996) (xy 66.69418 -97.841968) (xy 66.622864 -97.81625) (xy 66.554687 -97.783098)
			(xy 66.490419 -97.742886) (xy 66.43079 -97.696071) (xy 66.376474 -97.643183) (xy 66.328088 -97.584821)
			(xy 66.28618 -97.521646) (xy 66.251224 -97.454375) (xy 66.223617 -97.38377) (xy 66.203671 -97.310629)
			(xy 66.191612 -97.235784) (xy 66.187577 -97.16008) (xy 65.071498 -97.16008) (xy 65.070994 -97.197986)
			(xy 65.062935 -97.273367) (xy 65.04691 -97.347465) (xy 65.0231 -97.41944) (xy 64.991774 -97.488476)
			(xy 64.953287 -97.553791) (xy 64.908076 -97.614646) (xy 64.856652 -97.67035) (xy 64.799599 -97.720272)
			(xy 64.737563 -97.763847) (xy 64.671246 -97.800582) (xy 64.6014 -97.830059) (xy 64.528817 -97.851945)
			(xy 64.454319 -97.865992) (xy 64.378749 -97.872041) (xy 64.302965 -97.870022) (xy 64.227825 -97.85996)
			(xy 64.15418 -97.841968) (xy 64.082864 -97.81625) (xy 64.014687 -97.783098) (xy 63.950419 -97.742886)
			(xy 63.89079 -97.696071) (xy 63.836474 -97.643183) (xy 63.788088 -97.584821) (xy 63.74618 -97.521646)
			(xy 63.711224 -97.454375) (xy 63.683617 -97.38377) (xy 63.663671 -97.310629) (xy 63.651612 -97.235784)
			(xy 63.647577 -97.16008) (xy 42.501276 -97.16008) (xy 42.424555 -97.214411) (xy 42.327933 -97.273494)
			(xy 42.227553 -97.32594) (xy 42.123871 -97.371511) (xy 42.070782 -97.39122) (xy 42.049139 -97.399602)
			(xy 42.009096 -97.423056) (xy 41.973978 -97.453393) (xy 41.944953 -97.489602) (xy 41.922986 -97.53048)
			(xy 41.908807 -97.574668) (xy 41.902889 -97.620695) (xy 41.905428 -97.667033) (xy 41.916339 -97.712138)
			(xy 41.93526 -97.754512) (xy 41.961562 -97.792746) (xy 41.977564 -97.809558) (xy 44.136564 -99.968558)
			(xy 44.136564 -101.568984) (xy 60.513567 -101.568984) (xy 60.517459 -101.514629) (xy 60.529047 -101.461382)
			(xy 60.548095 -101.410326) (xy 60.574216 -101.3625) (xy 60.590176 -101.340412) (xy 60.603762 -101.321393)
			(xy 60.624497 -101.279512) (xy 60.637225 -101.234545) (xy 60.641518 -101.18801) (xy 60.637229 -101.141474)
			(xy 60.624504 -101.096506) (xy 60.603772 -101.054624) (xy 60.590176 -101.035612) (xy 60.574216 -101.013524)
			(xy 60.548095 -100.965698) (xy 60.529047 -100.914642) (xy 60.517459 -100.861395) (xy 60.513567 -100.80704)
			(xy 60.517451 -100.752685) (xy 60.529031 -100.699436) (xy 60.548072 -100.648377) (xy 60.574186 -100.600547)
			(xy 60.606841 -100.556921) (xy 60.645372 -100.518387) (xy 60.688996 -100.485729) (xy 60.736823 -100.459612)
			(xy 60.787881 -100.440567) (xy 60.841129 -100.428983) (xy 60.895484 -100.425095) (xy 60.949839 -100.428983)
			(xy 61.003087 -100.440567) (xy 61.054145 -100.459612) (xy 61.101972 -100.485729) (xy 61.145596 -100.518387)
			(xy 61.184127 -100.556921) (xy 61.216782 -100.600547) (xy 61.242896 -100.648377) (xy 61.261937 -100.699436)
			(xy 61.273517 -100.752685) (xy 61.277401 -100.80704) (xy 61.273509 -100.861395) (xy 61.261921 -100.914642)
			(xy 61.242873 -100.965698) (xy 61.216752 -101.013524) (xy 61.200792 -101.035612) (xy 61.187186 -101.054617)
			(xy 61.166455 -101.096502) (xy 61.153731 -101.141472) (xy 61.149442 -101.18801) (xy 61.153734 -101.234547)
			(xy 61.166462 -101.279516) (xy 61.187196 -101.3214) (xy 61.200792 -101.340412) (xy 61.216752 -101.3625)
			(xy 61.242873 -101.410326) (xy 61.261921 -101.461382) (xy 61.273509 -101.514629) (xy 61.277401 -101.568984)
			(xy 61.274806 -101.605306) (xy 62.791439 -101.605306) (xy 62.795331 -101.550951) (xy 62.806919 -101.497704)
			(xy 62.825967 -101.446648) (xy 62.852088 -101.398822) (xy 62.868048 -101.376734) (xy 62.88161 -101.3577)
			(xy 62.902341 -101.315821) (xy 62.915068 -101.270859) (xy 62.919362 -101.224327) (xy 62.915078 -101.177795)
			(xy 62.902361 -101.13283) (xy 62.881638 -101.090947) (xy 62.868048 -101.071934) (xy 62.852088 -101.049846)
			(xy 62.825967 -101.00202) (xy 62.806919 -100.950964) (xy 62.795331 -100.897717) (xy 62.791439 -100.843362)
			(xy 62.795323 -100.789007) (xy 62.806903 -100.735758) (xy 62.825944 -100.684699) (xy 62.852058 -100.636869)
			(xy 62.884713 -100.593243) (xy 62.923244 -100.554709) (xy 62.966868 -100.522051) (xy 63.014695 -100.495934)
			(xy 63.065753 -100.476889) (xy 63.119001 -100.465305) (xy 63.173356 -100.461417) (xy 63.227711 -100.465305)
			(xy 63.280959 -100.476889) (xy 63.332017 -100.495934) (xy 63.379844 -100.522051) (xy 63.423468 -100.554709)
			(xy 63.461999 -100.593243) (xy 63.494654 -100.636869) (xy 63.520768 -100.684699) (xy 63.539809 -100.735758)
			(xy 63.551389 -100.789007) (xy 63.555273 -100.843362) (xy 63.551381 -100.897717) (xy 63.539793 -100.950964)
			(xy 63.520745 -101.00202) (xy 63.494624 -101.049846) (xy 63.478664 -101.071934) (xy 63.465039 -101.090925)
			(xy 63.444312 -101.132815) (xy 63.431592 -101.177787) (xy 63.427307 -101.224327) (xy 63.431602 -101.270866)
			(xy 63.444331 -101.315836) (xy 63.465067 -101.357721) (xy 63.478664 -101.376734) (xy 63.494624 -101.398822)
			(xy 63.520745 -101.446648) (xy 63.539793 -101.497704) (xy 63.541597 -101.505992) (xy 65.041371 -101.505992)
			(xy 65.045263 -101.451637) (xy 65.056851 -101.39839) (xy 65.075899 -101.347334) (xy 65.10202 -101.299508)
			(xy 65.11798 -101.27742) (xy 65.131558 -101.258396) (xy 65.152294 -101.216516) (xy 65.165023 -101.171551)
			(xy 65.169316 -101.125016) (xy 65.165029 -101.078481) (xy 65.152305 -101.033514) (xy 65.131575 -100.991632)
			(xy 65.11798 -100.97262) (xy 65.10202 -100.950532) (xy 65.075899 -100.902706) (xy 65.056851 -100.85165)
			(xy 65.045263 -100.798403) (xy 65.041371 -100.744048) (xy 65.045255 -100.689693) (xy 65.056835 -100.636444)
			(xy 65.075876 -100.585385) (xy 65.10199 -100.537555) (xy 65.134645 -100.493929) (xy 65.173176 -100.455395)
			(xy 65.2168 -100.422737) (xy 65.264627 -100.39662) (xy 65.315685 -100.377575) (xy 65.368933 -100.365991)
			(xy 65.423288 -100.362103) (xy 65.477643 -100.365991) (xy 65.530891 -100.377575) (xy 65.581949 -100.39662)
			(xy 65.629776 -100.422737) (xy 65.6734 -100.455395) (xy 65.711931 -100.493929) (xy 65.744586 -100.537555)
			(xy 65.7707 -100.585385) (xy 65.789741 -100.636444) (xy 65.801321 -100.689693) (xy 65.805205 -100.744048)
			(xy 65.801313 -100.798403) (xy 65.789725 -100.85165) (xy 65.770677 -100.902706) (xy 65.744556 -100.950532)
			(xy 65.728596 -100.97262) (xy 65.714982 -100.99162) (xy 65.694252 -101.033506) (xy 65.681528 -101.078477)
			(xy 65.677241 -101.125016) (xy 65.681534 -101.171554) (xy 65.694263 -101.216524) (xy 65.714999 -101.258408)
			(xy 65.728596 -101.27742) (xy 65.744556 -101.299508) (xy 65.770677 -101.347334) (xy 65.789725 -101.39839)
			(xy 65.801313 -101.451637) (xy 65.805205 -101.505992) (xy 65.805187 -101.506246) (xy 67.192243 -101.506246)
			(xy 67.196135 -101.451891) (xy 67.207723 -101.398644) (xy 67.226771 -101.347588) (xy 67.252892 -101.299762)
			(xy 67.268852 -101.277674) (xy 67.282474 -101.258679) (xy 67.303208 -101.216792) (xy 67.315934 -101.17182)
			(xy 67.320221 -101.125279) (xy 67.315926 -101.078739) (xy 67.303193 -101.033769) (xy 67.282452 -100.991885)
			(xy 67.268852 -100.972874) (xy 67.252892 -100.950786) (xy 67.226771 -100.90296) (xy 67.207723 -100.851904)
			(xy 67.196135 -100.798657) (xy 67.192243 -100.744302) (xy 67.196127 -100.689947) (xy 67.207707 -100.636698)
			(xy 67.226748 -100.585639) (xy 67.252862 -100.537809) (xy 67.285517 -100.494183) (xy 67.324048 -100.455649)
			(xy 67.367672 -100.422991) (xy 67.415499 -100.396874) (xy 67.466557 -100.377829) (xy 67.519805 -100.366245)
			(xy 67.57416 -100.362357) (xy 67.628515 -100.366245) (xy 67.681763 -100.377829) (xy 67.732821 -100.396874)
			(xy 67.780648 -100.422991) (xy 67.824272 -100.455649) (xy 67.862803 -100.494183) (xy 67.895458 -100.537809)
			(xy 67.921572 -100.585639) (xy 67.940613 -100.636698) (xy 67.952193 -100.689947) (xy 67.956077 -100.744302)
			(xy 67.952185 -100.798657) (xy 67.940597 -100.851904) (xy 67.921549 -100.90296) (xy 67.895428 -100.950786)
			(xy 67.879468 -100.972874) (xy 67.865898 -100.991903) (xy 67.845166 -101.033783) (xy 67.832439 -101.078746)
			(xy 67.828146 -101.125279) (xy 67.832431 -101.171813) (xy 67.845151 -101.216778) (xy 67.865876 -101.258661)
			(xy 67.879468 -101.277674) (xy 67.895428 -101.299762) (xy 67.921549 -101.347588) (xy 67.940597 -101.398644)
			(xy 67.952185 -101.451891) (xy 67.956077 -101.506246) (xy 67.953482 -101.542568) (xy 69.348957 -101.542568)
			(xy 69.352849 -101.488213) (xy 69.364437 -101.434966) (xy 69.383485 -101.38391) (xy 69.409606 -101.336084)
			(xy 69.425566 -101.313996) (xy 69.439167 -101.294987) (xy 69.459902 -101.253104) (xy 69.472629 -101.208135)
			(xy 69.476919 -101.161597) (xy 69.472628 -101.115059) (xy 69.4599 -101.070091) (xy 69.439164 -101.028207)
			(xy 69.425566 -101.009196) (xy 69.409606 -100.987108) (xy 69.383485 -100.939282) (xy 69.364437 -100.888226)
			(xy 69.352849 -100.834979) (xy 69.348957 -100.780624) (xy 69.352841 -100.726269) (xy 69.364421 -100.67302)
			(xy 69.383462 -100.621961) (xy 69.409576 -100.574131) (xy 69.442231 -100.530505) (xy 69.480762 -100.491971)
			(xy 69.524386 -100.459313) (xy 69.572213 -100.433196) (xy 69.623271 -100.414151) (xy 69.676519 -100.402567)
			(xy 69.730874 -100.398679) (xy 69.785229 -100.402567) (xy 69.838477 -100.414151) (xy 69.889535 -100.433196)
			(xy 69.937362 -100.459313) (xy 69.980986 -100.491971) (xy 70.019517 -100.530505) (xy 70.052172 -100.574131)
			(xy 70.078286 -100.621961) (xy 70.097327 -100.67302) (xy 70.108907 -100.726269) (xy 70.112791 -100.780624)
			(xy 70.108899 -100.834979) (xy 70.097311 -100.888226) (xy 70.078263 -100.939282) (xy 70.052142 -100.987108)
			(xy 70.036182 -101.009196) (xy 70.022591 -101.028211) (xy 70.00186 -101.070094) (xy 69.989134 -101.115061)
			(xy 69.984844 -101.161597) (xy 69.989133 -101.208133) (xy 70.001857 -101.2531) (xy 70.022588 -101.294984)
			(xy 70.036182 -101.313996) (xy 70.052142 -101.336084) (xy 70.078263 -101.38391) (xy 70.097311 -101.434966)
			(xy 70.108899 -101.488213) (xy 70.112791 -101.542568) (xy 70.108907 -101.596923) (xy 70.097327 -101.650172)
			(xy 70.078286 -101.701231) (xy 70.052172 -101.749061) (xy 70.019517 -101.792687) (xy 69.980986 -101.831221)
			(xy 69.937362 -101.863879) (xy 69.889535 -101.889996) (xy 69.838477 -101.909041) (xy 69.785229 -101.920625)
			(xy 69.730874 -101.924513) (xy 69.676519 -101.920625) (xy 69.623271 -101.909041) (xy 69.572213 -101.889996)
			(xy 69.524386 -101.863879) (xy 69.480762 -101.831221) (xy 69.442231 -101.792687) (xy 69.409576 -101.749061)
			(xy 69.383462 -101.701231) (xy 69.364421 -101.650172) (xy 69.352841 -101.596923) (xy 69.348957 -101.542568)
			(xy 67.953482 -101.542568) (xy 67.952193 -101.560601) (xy 67.940613 -101.61385) (xy 67.921572 -101.664909)
			(xy 67.895458 -101.712739) (xy 67.862803 -101.756365) (xy 67.824272 -101.794899) (xy 67.780648 -101.827557)
			(xy 67.732821 -101.853674) (xy 67.681763 -101.872719) (xy 67.628515 -101.884303) (xy 67.57416 -101.888191)
			(xy 67.519805 -101.884303) (xy 67.466557 -101.872719) (xy 67.415499 -101.853674) (xy 67.367672 -101.827557)
			(xy 67.324048 -101.794899) (xy 67.285517 -101.756365) (xy 67.252862 -101.712739) (xy 67.226748 -101.664909)
			(xy 67.207707 -101.61385) (xy 67.196127 -101.560601) (xy 67.192243 -101.506246) (xy 65.805187 -101.506246)
			(xy 65.801321 -101.560347) (xy 65.789741 -101.613596) (xy 65.7707 -101.664655) (xy 65.744586 -101.712485)
			(xy 65.711931 -101.756111) (xy 65.6734 -101.794645) (xy 65.629776 -101.827303) (xy 65.581949 -101.85342)
			(xy 65.530891 -101.872465) (xy 65.477643 -101.884049) (xy 65.423288 -101.887937) (xy 65.368933 -101.884049)
			(xy 65.315685 -101.872465) (xy 65.264627 -101.85342) (xy 65.2168 -101.827303) (xy 65.173176 -101.794645)
			(xy 65.134645 -101.756111) (xy 65.10199 -101.712485) (xy 65.075876 -101.664655) (xy 65.056835 -101.613596)
			(xy 65.045255 -101.560347) (xy 65.041371 -101.505992) (xy 63.541597 -101.505992) (xy 63.551381 -101.550951)
			(xy 63.555273 -101.605306) (xy 63.551389 -101.659661) (xy 63.539809 -101.71291) (xy 63.520768 -101.763969)
			(xy 63.494654 -101.811799) (xy 63.461999 -101.855425) (xy 63.423468 -101.893959) (xy 63.379844 -101.926617)
			(xy 63.332017 -101.952734) (xy 63.280959 -101.971779) (xy 63.227711 -101.983363) (xy 63.173356 -101.987251)
			(xy 63.119001 -101.983363) (xy 63.065753 -101.971779) (xy 63.014695 -101.952734) (xy 62.966868 -101.926617)
			(xy 62.923244 -101.893959) (xy 62.884713 -101.855425) (xy 62.852058 -101.811799) (xy 62.825944 -101.763969)
			(xy 62.806903 -101.71291) (xy 62.795323 -101.659661) (xy 62.791439 -101.605306) (xy 61.274806 -101.605306)
			(xy 61.273517 -101.623339) (xy 61.261937 -101.676588) (xy 61.242896 -101.727647) (xy 61.216782 -101.775477)
			(xy 61.184127 -101.819103) (xy 61.145596 -101.857637) (xy 61.101972 -101.890295) (xy 61.054145 -101.916412)
			(xy 61.003087 -101.935457) (xy 60.949839 -101.947041) (xy 60.895484 -101.950929) (xy 60.841129 -101.947041)
			(xy 60.787881 -101.935457) (xy 60.736823 -101.916412) (xy 60.688996 -101.890295) (xy 60.645372 -101.857637)
			(xy 60.606841 -101.819103) (xy 60.574186 -101.775477) (xy 60.548072 -101.727647) (xy 60.529031 -101.676588)
			(xy 60.517451 -101.623339) (xy 60.513567 -101.568984) (xy 44.136564 -101.568984) (xy 44.136564 -102.057704)
			(xy 86.43542 -102.057704) (xy 86.43542 -101.997768) (xy 86.443243 -101.938346) (xy 86.458756 -101.880453)
			(xy 86.481692 -101.82508) (xy 86.511659 -101.773174) (xy 86.548146 -101.725624) (xy 86.590526 -101.683244)
			(xy 86.638076 -101.646757) (xy 86.689982 -101.61679) (xy 86.745355 -101.593854) (xy 86.803248 -101.578341)
			(xy 86.86267 -101.570518) (xy 86.922606 -101.570518) (xy 86.982028 -101.578341) (xy 87.039921 -101.593854)
			(xy 87.095294 -101.61679) (xy 87.1472 -101.646757) (xy 87.19475 -101.683244) (xy 87.23713 -101.725624)
			(xy 87.273617 -101.773174) (xy 87.303584 -101.82508) (xy 87.32652 -101.880453) (xy 87.342033 -101.938346)
			(xy 87.349856 -101.997768) (xy 87.350346 -102.027736) (xy 87.349856 -102.057704) (xy 87.347047 -102.07904)
			(xy 91.954332 -102.07904) (xy 91.954332 -102.019104) (xy 91.962155 -101.959682) (xy 91.977668 -101.901789)
			(xy 92.000604 -101.846416) (xy 92.030571 -101.79451) (xy 92.067058 -101.74696) (xy 92.109438 -101.70458)
			(xy 92.156988 -101.668093) (xy 92.208894 -101.638126) (xy 92.264267 -101.61519) (xy 92.32216 -101.599677)
			(xy 92.381582 -101.591854) (xy 92.441518 -101.591854) (xy 92.50094 -101.599677) (xy 92.558833 -101.61519)
			(xy 92.614206 -101.638126) (xy 92.666112 -101.668093) (xy 92.713662 -101.70458) (xy 92.756042 -101.74696)
			(xy 92.792529 -101.79451) (xy 92.822496 -101.846416) (xy 92.845432 -101.901789) (xy 92.85985 -101.955596)
			(xy 94.67645 -101.955596) (xy 94.67645 -101.89566) (xy 94.684273 -101.836238) (xy 94.699786 -101.778345)
			(xy 94.722722 -101.722972) (xy 94.752689 -101.671066) (xy 94.789176 -101.623516) (xy 94.831556 -101.581136)
			(xy 94.879106 -101.544649) (xy 94.931012 -101.514682) (xy 94.986385 -101.491746) (xy 95.044278 -101.476233)
			(xy 95.1037 -101.46841) (xy 95.163636 -101.46841) (xy 95.223058 -101.476233) (xy 95.280951 -101.491746)
			(xy 95.336324 -101.514682) (xy 95.38823 -101.544649) (xy 95.43578 -101.581136) (xy 95.47816 -101.623516)
			(xy 95.514647 -101.671066) (xy 95.544614 -101.722972) (xy 95.56755 -101.778345) (xy 95.583063 -101.836238)
			(xy 95.590886 -101.89566) (xy 95.591376 -101.925628) (xy 95.590886 -101.955596) (xy 95.583063 -102.015018)
			(xy 95.56755 -102.072911) (xy 95.544614 -102.128284) (xy 95.514647 -102.18019) (xy 95.47816 -102.22774)
			(xy 95.43578 -102.27012) (xy 95.38823 -102.306607) (xy 95.336324 -102.336574) (xy 95.280951 -102.35951)
			(xy 95.223058 -102.375023) (xy 95.163636 -102.382846) (xy 95.1037 -102.382846) (xy 95.044278 -102.375023)
			(xy 94.986385 -102.35951) (xy 94.931012 -102.336574) (xy 94.879106 -102.306607) (xy 94.831556 -102.27012)
			(xy 94.789176 -102.22774) (xy 94.752689 -102.18019) (xy 94.722722 -102.128284) (xy 94.699786 -102.072911)
			(xy 94.684273 -102.015018) (xy 94.67645 -101.955596) (xy 92.85985 -101.955596) (xy 92.860945 -101.959682)
			(xy 92.868768 -102.019104) (xy 92.869258 -102.049072) (xy 92.868768 -102.07904) (xy 92.860945 -102.138462)
			(xy 92.845432 -102.196355) (xy 92.822496 -102.251728) (xy 92.792529 -102.303634) (xy 92.756042 -102.351184)
			(xy 92.713662 -102.393564) (xy 92.666112 -102.430051) (xy 92.614206 -102.460018) (xy 92.558833 -102.482954)
			(xy 92.50094 -102.498467) (xy 92.441518 -102.50629) (xy 92.381582 -102.50629) (xy 92.32216 -102.498467)
			(xy 92.264267 -102.482954) (xy 92.208894 -102.460018) (xy 92.156988 -102.430051) (xy 92.109438 -102.393564)
			(xy 92.067058 -102.351184) (xy 92.030571 -102.303634) (xy 92.000604 -102.251728) (xy 91.977668 -102.196355)
			(xy 91.962155 -102.138462) (xy 91.954332 -102.07904) (xy 87.347047 -102.07904) (xy 87.342033 -102.117126)
			(xy 87.32652 -102.175019) (xy 87.303584 -102.230392) (xy 87.273617 -102.282298) (xy 87.23713 -102.329848)
			(xy 87.19475 -102.372228) (xy 87.1472 -102.408715) (xy 87.095294 -102.438682) (xy 87.039921 -102.461618)
			(xy 86.982028 -102.477131) (xy 86.922606 -102.484954) (xy 86.86267 -102.484954) (xy 86.803248 -102.477131)
			(xy 86.745355 -102.461618) (xy 86.689982 -102.438682) (xy 86.638076 -102.408715) (xy 86.590526 -102.372228)
			(xy 86.548146 -102.329848) (xy 86.511659 -102.282298) (xy 86.481692 -102.230392) (xy 86.458756 -102.175019)
			(xy 86.443243 -102.117126) (xy 86.43542 -102.057704) (xy 44.136564 -102.057704) (xy 44.136564 -102.65435)
			(xy 84.76537 -102.65435) (xy 84.76537 -102.594414) (xy 84.773193 -102.534992) (xy 84.788706 -102.477099)
			(xy 84.811642 -102.421726) (xy 84.841609 -102.36982) (xy 84.878096 -102.32227) (xy 84.920476 -102.27989)
			(xy 84.968026 -102.243403) (xy 85.019932 -102.213436) (xy 85.075305 -102.1905) (xy 85.133198 -102.174987)
			(xy 85.19262 -102.167164) (xy 85.252556 -102.167164) (xy 85.311978 -102.174987) (xy 85.369871 -102.1905)
			(xy 85.425244 -102.213436) (xy 85.47715 -102.243403) (xy 85.5247 -102.27989) (xy 85.56708 -102.32227)
			(xy 85.603567 -102.36982) (xy 85.633534 -102.421726) (xy 85.65647 -102.477099) (xy 85.671983 -102.534992)
			(xy 85.679806 -102.594414) (xy 85.680296 -102.624382) (xy 85.679806 -102.65435) (xy 85.671983 -102.713772)
			(xy 85.669189 -102.7242) (xy 93.24516 -102.7242) (xy 93.24516 -102.664264) (xy 93.252983 -102.604842)
			(xy 93.268496 -102.546949) (xy 93.291432 -102.491576) (xy 93.321399 -102.43967) (xy 93.357886 -102.39212)
			(xy 93.400266 -102.34974) (xy 93.447816 -102.313253) (xy 93.499722 -102.283286) (xy 93.555095 -102.26035)
			(xy 93.612988 -102.244837) (xy 93.67241 -102.237014) (xy 93.732346 -102.237014) (xy 93.791768 -102.244837)
			(xy 93.849661 -102.26035) (xy 93.905034 -102.283286) (xy 93.95694 -102.313253) (xy 94.00449 -102.34974)
			(xy 94.04687 -102.39212) (xy 94.083357 -102.43967) (xy 94.113324 -102.491576) (xy 94.13626 -102.546949)
			(xy 94.151773 -102.604842) (xy 94.159596 -102.664264) (xy 94.160086 -102.694232) (xy 94.159596 -102.7242)
			(xy 94.151773 -102.783622) (xy 94.13626 -102.841515) (xy 94.113324 -102.896888) (xy 94.083357 -102.948794)
			(xy 94.04687 -102.996344) (xy 94.00449 -103.038724) (xy 93.95694 -103.075211) (xy 93.905034 -103.105178)
			(xy 93.849661 -103.128114) (xy 93.791768 -103.143627) (xy 93.732346 -103.15145) (xy 93.67241 -103.15145)
			(xy 93.612988 -103.143627) (xy 93.555095 -103.128114) (xy 93.499722 -103.105178) (xy 93.447816 -103.075211)
			(xy 93.400266 -103.038724) (xy 93.357886 -102.996344) (xy 93.321399 -102.948794) (xy 93.291432 -102.896888)
			(xy 93.268496 -102.841515) (xy 93.252983 -102.783622) (xy 93.24516 -102.7242) (xy 85.669189 -102.7242)
			(xy 85.65647 -102.771665) (xy 85.633534 -102.827038) (xy 85.603567 -102.878944) (xy 85.56708 -102.926494)
			(xy 85.5247 -102.968874) (xy 85.47715 -103.005361) (xy 85.425244 -103.035328) (xy 85.369871 -103.058264)
			(xy 85.311978 -103.073777) (xy 85.252556 -103.0816) (xy 85.19262 -103.0816) (xy 85.133198 -103.073777)
			(xy 85.075305 -103.058264) (xy 85.019932 -103.035328) (xy 84.968026 -103.005361) (xy 84.920476 -102.968874)
			(xy 84.878096 -102.926494) (xy 84.841609 -102.878944) (xy 84.811642 -102.827038) (xy 84.788706 -102.771665)
			(xy 84.773193 -102.713772) (xy 84.76537 -102.65435) (xy 44.136564 -102.65435) (xy 44.136564 -104.239794)
			(xy 60.513567 -104.239794) (xy 60.517459 -104.185439) (xy 60.529047 -104.132192) (xy 60.548095 -104.081136)
			(xy 60.574216 -104.03331) (xy 60.590176 -104.011222) (xy 60.603752 -103.992197) (xy 60.624489 -103.950317)
			(xy 60.637218 -103.905352) (xy 60.641512 -103.858818) (xy 60.637224 -103.812283) (xy 60.624501 -103.767316)
			(xy 60.603771 -103.725434) (xy 60.590176 -103.706422) (xy 60.574216 -103.684334) (xy 60.548095 -103.636508)
			(xy 60.529047 -103.585452) (xy 60.517459 -103.532205) (xy 60.513567 -103.47785) (xy 60.517451 -103.423495)
			(xy 60.529031 -103.370246) (xy 60.548072 -103.319187) (xy 60.574186 -103.271357) (xy 60.606841 -103.227731)
			(xy 60.645372 -103.189197) (xy 60.688996 -103.156539) (xy 60.736823 -103.130422) (xy 60.787881 -103.111377)
			(xy 60.841129 -103.099793) (xy 60.895484 -103.095905) (xy 60.949839 -103.099793) (xy 61.003087 -103.111377)
			(xy 61.054145 -103.130422) (xy 61.101972 -103.156539) (xy 61.145596 -103.189197) (xy 61.184127 -103.227731)
			(xy 61.216782 -103.271357) (xy 61.242896 -103.319187) (xy 61.261937 -103.370246) (xy 61.273517 -103.423495)
			(xy 61.277401 -103.47785) (xy 61.273509 -103.532205) (xy 61.261921 -103.585452) (xy 61.242873 -103.636508)
			(xy 61.216752 -103.684334) (xy 61.200792 -103.706422) (xy 61.187176 -103.72542) (xy 61.166446 -103.767307)
			(xy 61.153723 -103.812279) (xy 61.149436 -103.858818) (xy 61.15373 -103.905356) (xy 61.166459 -103.950325)
			(xy 61.187195 -103.99221) (xy 61.200792 -104.011222) (xy 61.216752 -104.03331) (xy 61.242873 -104.081136)
			(xy 61.261921 -104.132192) (xy 61.273509 -104.185439) (xy 61.277401 -104.239794) (xy 61.274806 -104.276116)
			(xy 62.791439 -104.276116) (xy 62.795331 -104.221761) (xy 62.806919 -104.168514) (xy 62.825967 -104.117458)
			(xy 62.852088 -104.069632) (xy 62.868048 -104.047544) (xy 62.8816 -104.028503) (xy 62.902332 -103.986626)
			(xy 62.915061 -103.941665) (xy 62.919356 -103.895135) (xy 62.915074 -103.848604) (xy 62.902358 -103.803639)
			(xy 62.881637 -103.761757) (xy 62.868048 -103.742744) (xy 62.852088 -103.720656) (xy 62.825967 -103.67283)
			(xy 62.806919 -103.621774) (xy 62.795331 -103.568527) (xy 62.791439 -103.514172) (xy 62.795323 -103.459817)
			(xy 62.806903 -103.406568) (xy 62.825944 -103.355509) (xy 62.852058 -103.307679) (xy 62.884713 -103.264053)
			(xy 62.923244 -103.225519) (xy 62.966868 -103.192861) (xy 63.014695 -103.166744) (xy 63.065753 -103.147699)
			(xy 63.119001 -103.136115) (xy 63.173356 -103.132227) (xy 63.227711 -103.136115) (xy 63.280959 -103.147699)
			(xy 63.332017 -103.166744) (xy 63.379844 -103.192861) (xy 63.423468 -103.225519) (xy 63.461999 -103.264053)
			(xy 63.494654 -103.307679) (xy 63.520768 -103.355509) (xy 63.539809 -103.406568) (xy 63.551389 -103.459817)
			(xy 63.555273 -103.514172) (xy 63.551381 -103.568527) (xy 63.539793 -103.621774) (xy 63.520745 -103.67283)
			(xy 63.494624 -103.720656) (xy 63.478664 -103.742744) (xy 63.465029 -103.761729) (xy 63.444303 -103.80362)
			(xy 63.431584 -103.848594) (xy 63.427301 -103.895135) (xy 63.431597 -103.941675) (xy 63.444329 -103.986646)
			(xy 63.465066 -104.028531) (xy 63.478664 -104.047544) (xy 63.494624 -104.069632) (xy 63.520745 -104.117458)
			(xy 63.539793 -104.168514) (xy 63.541597 -104.176802) (xy 65.041371 -104.176802) (xy 65.045263 -104.122447)
			(xy 65.056851 -104.0692) (xy 65.075899 -104.018144) (xy 65.10202 -103.970318) (xy 65.11798 -103.94823)
			(xy 65.131549 -103.929199) (xy 65.152285 -103.887321) (xy 65.165015 -103.842357) (xy 65.16931 -103.795824)
			(xy 65.165024 -103.74929) (xy 65.152302 -103.704324) (xy 65.131574 -103.662442) (xy 65.11798 -103.64343)
			(xy 65.10202 -103.621342) (xy 65.075899 -103.573516) (xy 65.056851 -103.52246) (xy 65.045263 -103.469213)
			(xy 65.041371 -103.414858) (xy 65.045255 -103.360503) (xy 65.056835 -103.307254) (xy 65.075876 -103.256195)
			(xy 65.10199 -103.208365) (xy 65.134645 -103.164739) (xy 65.173176 -103.126205) (xy 65.2168 -103.093547)
			(xy 65.264627 -103.06743) (xy 65.315685 -103.048385) (xy 65.368933 -103.036801) (xy 65.423288 -103.032913)
			(xy 65.477643 -103.036801) (xy 65.530891 -103.048385) (xy 65.581949 -103.06743) (xy 65.629776 -103.093547)
			(xy 65.6734 -103.126205) (xy 65.711931 -103.164739) (xy 65.744586 -103.208365) (xy 65.7707 -103.256195)
			(xy 65.789741 -103.307254) (xy 65.801321 -103.360503) (xy 65.805205 -103.414858) (xy 65.801313 -103.469213)
			(xy 65.789725 -103.52246) (xy 65.770677 -103.573516) (xy 65.744556 -103.621342) (xy 65.728596 -103.64343)
			(xy 65.714973 -103.662423) (xy 65.694243 -103.704312) (xy 65.681521 -103.749284) (xy 65.677235 -103.795824)
			(xy 65.68153 -103.842363) (xy 65.69426 -103.887333) (xy 65.714998 -103.929218) (xy 65.728596 -103.94823)
			(xy 65.744556 -103.970318) (xy 65.770677 -104.018144) (xy 65.789725 -104.0692) (xy 65.801313 -104.122447)
			(xy 65.805205 -104.176802) (xy 65.805187 -104.177056) (xy 67.192243 -104.177056) (xy 67.196135 -104.122701)
			(xy 67.207723 -104.069454) (xy 67.226771 -104.018398) (xy 67.252892 -103.970572) (xy 67.268852 -103.948484)
			(xy 67.282465 -103.929483) (xy 67.3032 -103.887598) (xy 67.315926 -103.842627) (xy 67.320215 -103.796087)
			(xy 67.315922 -103.749548) (xy 67.303191 -103.704578) (xy 67.282451 -103.662695) (xy 67.268852 -103.643684)
			(xy 67.252892 -103.621596) (xy 67.226771 -103.57377) (xy 67.207723 -103.522714) (xy 67.196135 -103.469467)
			(xy 67.192243 -103.415112) (xy 67.196127 -103.360757) (xy 67.207707 -103.307508) (xy 67.226748 -103.256449)
			(xy 67.252862 -103.208619) (xy 67.285517 -103.164993) (xy 67.324048 -103.126459) (xy 67.367672 -103.093801)
			(xy 67.415499 -103.067684) (xy 67.466557 -103.048639) (xy 67.519805 -103.037055) (xy 67.57416 -103.033167)
			(xy 67.628515 -103.037055) (xy 67.681763 -103.048639) (xy 67.732821 -103.067684) (xy 67.780648 -103.093801)
			(xy 67.824272 -103.126459) (xy 67.862803 -103.164993) (xy 67.895458 -103.208619) (xy 67.921572 -103.256449)
			(xy 67.940613 -103.307508) (xy 67.952193 -103.360757) (xy 67.956077 -103.415112) (xy 67.952185 -103.469467)
			(xy 67.940597 -103.522714) (xy 67.921549 -103.57377) (xy 67.895428 -103.621596) (xy 67.879468 -103.643684)
			(xy 67.865889 -103.662707) (xy 67.845158 -103.704588) (xy 67.832432 -103.749553) (xy 67.82814 -103.796087)
			(xy 67.832427 -103.842622) (xy 67.845148 -103.887588) (xy 67.865875 -103.929471) (xy 67.879468 -103.948484)
			(xy 67.895428 -103.970572) (xy 67.921549 -104.018398) (xy 67.940597 -104.069454) (xy 67.952185 -104.122701)
			(xy 67.956077 -104.177056) (xy 67.953482 -104.213378) (xy 69.348957 -104.213378) (xy 69.352849 -104.159023)
			(xy 69.364437 -104.105776) (xy 69.383485 -104.05472) (xy 69.409606 -104.006894) (xy 69.425566 -103.984806)
			(xy 69.439158 -103.965791) (xy 69.459893 -103.923909) (xy 69.472622 -103.878941) (xy 69.476913 -103.832405)
			(xy 69.472623 -103.785868) (xy 69.459897 -103.7409) (xy 69.439163 -103.699017) (xy 69.425566 -103.680006)
			(xy 69.409606 -103.657918) (xy 69.383485 -103.610092) (xy 69.364437 -103.559036) (xy 69.352849 -103.505789)
			(xy 69.348957 -103.451434) (xy 69.352841 -103.397079) (xy 69.364421 -103.34383) (xy 69.383462 -103.292771)
			(xy 69.409576 -103.244941) (xy 69.442231 -103.201315) (xy 69.480762 -103.162781) (xy 69.524386 -103.130123)
			(xy 69.572213 -103.104006) (xy 69.623271 -103.084961) (xy 69.676519 -103.073377) (xy 69.730874 -103.069489)
			(xy 69.785229 -103.073377) (xy 69.838477 -103.084961) (xy 69.889535 -103.104006) (xy 69.937362 -103.130123)
			(xy 69.980986 -103.162781) (xy 70.019517 -103.201315) (xy 70.052172 -103.244941) (xy 70.078286 -103.292771)
			(xy 70.097327 -103.34383) (xy 70.103376 -103.371646) (xy 94.65105 -103.371646) (xy 94.65105 -103.31171)
			(xy 94.658873 -103.252288) (xy 94.674386 -103.194395) (xy 94.697322 -103.139022) (xy 94.727289 -103.087116)
			(xy 94.763776 -103.039566) (xy 94.806156 -102.997186) (xy 94.853706 -102.960699) (xy 94.905612 -102.930732)
			(xy 94.960985 -102.907796) (xy 95.018878 -102.892283) (xy 95.0783 -102.88446) (xy 95.138236 -102.88446)
			(xy 95.197658 -102.892283) (xy 95.255551 -102.907796) (xy 95.310924 -102.930732) (xy 95.36283 -102.960699)
			(xy 95.41038 -102.997186) (xy 95.45276 -103.039566) (xy 95.489247 -103.087116) (xy 95.519214 -103.139022)
			(xy 95.54215 -103.194395) (xy 95.557663 -103.252288) (xy 95.565486 -103.31171) (xy 95.565976 -103.341678)
			(xy 95.565486 -103.371646) (xy 95.557663 -103.431068) (xy 95.54215 -103.488961) (xy 95.519214 -103.544334)
			(xy 95.489247 -103.59624) (xy 95.45276 -103.64379) (xy 95.41038 -103.68617) (xy 95.36283 -103.722657)
			(xy 95.310924 -103.752624) (xy 95.255551 -103.77556) (xy 95.197658 -103.791073) (xy 95.138236 -103.798896)
			(xy 95.0783 -103.798896) (xy 95.018878 -103.791073) (xy 94.960985 -103.77556) (xy 94.905612 -103.752624)
			(xy 94.853706 -103.722657) (xy 94.806156 -103.68617) (xy 94.763776 -103.64379) (xy 94.727289 -103.59624)
			(xy 94.697322 -103.544334) (xy 94.674386 -103.488961) (xy 94.658873 -103.431068) (xy 94.65105 -103.371646)
			(xy 70.103376 -103.371646) (xy 70.108907 -103.397079) (xy 70.112791 -103.451434) (xy 70.108899 -103.505789)
			(xy 70.097311 -103.559036) (xy 70.078263 -103.610092) (xy 70.052142 -103.657918) (xy 70.036182 -103.680006)
			(xy 70.022582 -103.699015) (xy 70.001851 -103.740899) (xy 69.989127 -103.785868) (xy 69.984838 -103.832405)
			(xy 69.989129 -103.878942) (xy 70.001855 -103.92391) (xy 70.022587 -103.965794) (xy 70.02619 -103.970832)
			(xy 83.096082 -103.970832) (xy 83.096082 -103.910896) (xy 83.103905 -103.851474) (xy 83.119418 -103.793581)
			(xy 83.142354 -103.738208) (xy 83.172321 -103.686302) (xy 83.208808 -103.638752) (xy 83.251188 -103.596372)
			(xy 83.298738 -103.559885) (xy 83.350644 -103.529918) (xy 83.406017 -103.506982) (xy 83.46391 -103.491469)
			(xy 83.523332 -103.483646) (xy 83.583268 -103.483646) (xy 83.64269 -103.491469) (xy 83.700583 -103.506982)
			(xy 83.755956 -103.529918) (xy 83.807862 -103.559885) (xy 83.855412 -103.596372) (xy 83.897792 -103.638752)
			(xy 83.934279 -103.686302) (xy 83.964246 -103.738208) (xy 83.987182 -103.793581) (xy 84.002695 -103.851474)
			(xy 84.010518 -103.910896) (xy 84.011008 -103.940864) (xy 84.010518 -103.970832) (xy 84.002695 -104.030254)
			(xy 83.987182 -104.088147) (xy 83.964246 -104.14352) (xy 83.934279 -104.195426) (xy 83.897792 -104.242976)
			(xy 83.855412 -104.285356) (xy 83.807862 -104.321843) (xy 83.755956 -104.35181) (xy 83.700583 -104.374746)
			(xy 83.64269 -104.390259) (xy 83.583268 -104.398082) (xy 83.523332 -104.398082) (xy 83.46391 -104.390259)
			(xy 83.406017 -104.374746) (xy 83.350644 -104.35181) (xy 83.298738 -104.321843) (xy 83.251188 -104.285356)
			(xy 83.208808 -104.242976) (xy 83.172321 -104.195426) (xy 83.142354 -104.14352) (xy 83.119418 -104.088147)
			(xy 83.103905 -104.030254) (xy 83.096082 -103.970832) (xy 70.02619 -103.970832) (xy 70.036182 -103.984806)
			(xy 70.052142 -104.006894) (xy 70.078263 -104.05472) (xy 70.097311 -104.105776) (xy 70.108899 -104.159023)
			(xy 70.112791 -104.213378) (xy 70.108907 -104.267733) (xy 70.097327 -104.320982) (xy 70.078286 -104.372041)
			(xy 70.052172 -104.419871) (xy 70.019517 -104.463497) (xy 69.980986 -104.502031) (xy 69.937362 -104.534689)
			(xy 69.889535 -104.560806) (xy 69.838477 -104.579851) (xy 69.785229 -104.591435) (xy 69.730874 -104.595323)
			(xy 69.676519 -104.591435) (xy 69.623271 -104.579851) (xy 69.572213 -104.560806) (xy 69.524386 -104.534689)
			(xy 69.480762 -104.502031) (xy 69.442231 -104.463497) (xy 69.409576 -104.419871) (xy 69.383462 -104.372041)
			(xy 69.364421 -104.320982) (xy 69.352841 -104.267733) (xy 69.348957 -104.213378) (xy 67.953482 -104.213378)
			(xy 67.952193 -104.231411) (xy 67.940613 -104.28466) (xy 67.921572 -104.335719) (xy 67.895458 -104.383549)
			(xy 67.862803 -104.427175) (xy 67.824272 -104.465709) (xy 67.780648 -104.498367) (xy 67.732821 -104.524484)
			(xy 67.681763 -104.543529) (xy 67.628515 -104.555113) (xy 67.57416 -104.559001) (xy 67.519805 -104.555113)
			(xy 67.466557 -104.543529) (xy 67.415499 -104.524484) (xy 67.367672 -104.498367) (xy 67.324048 -104.465709)
			(xy 67.285517 -104.427175) (xy 67.252862 -104.383549) (xy 67.226748 -104.335719) (xy 67.207707 -104.28466)
			(xy 67.196127 -104.231411) (xy 67.192243 -104.177056) (xy 65.805187 -104.177056) (xy 65.801321 -104.231157)
			(xy 65.789741 -104.284406) (xy 65.7707 -104.335465) (xy 65.744586 -104.383295) (xy 65.711931 -104.426921)
			(xy 65.6734 -104.465455) (xy 65.629776 -104.498113) (xy 65.581949 -104.52423) (xy 65.530891 -104.543275)
			(xy 65.477643 -104.554859) (xy 65.423288 -104.558747) (xy 65.368933 -104.554859) (xy 65.315685 -104.543275)
			(xy 65.264627 -104.52423) (xy 65.2168 -104.498113) (xy 65.173176 -104.465455) (xy 65.134645 -104.426921)
			(xy 65.10199 -104.383295) (xy 65.075876 -104.335465) (xy 65.056835 -104.284406) (xy 65.045255 -104.231157)
			(xy 65.041371 -104.176802) (xy 63.541597 -104.176802) (xy 63.551381 -104.221761) (xy 63.555273 -104.276116)
			(xy 63.551389 -104.330471) (xy 63.539809 -104.38372) (xy 63.520768 -104.434779) (xy 63.494654 -104.482609)
			(xy 63.461999 -104.526235) (xy 63.423468 -104.564769) (xy 63.379844 -104.597427) (xy 63.332017 -104.623544)
			(xy 63.280959 -104.642589) (xy 63.227711 -104.654173) (xy 63.173356 -104.658061) (xy 63.119001 -104.654173)
			(xy 63.065753 -104.642589) (xy 63.014695 -104.623544) (xy 62.966868 -104.597427) (xy 62.923244 -104.564769)
			(xy 62.884713 -104.526235) (xy 62.852058 -104.482609) (xy 62.825944 -104.434779) (xy 62.806903 -104.38372)
			(xy 62.795323 -104.330471) (xy 62.791439 -104.276116) (xy 61.274806 -104.276116) (xy 61.273517 -104.294149)
			(xy 61.261937 -104.347398) (xy 61.242896 -104.398457) (xy 61.216782 -104.446287) (xy 61.184127 -104.489913)
			(xy 61.145596 -104.528447) (xy 61.101972 -104.561105) (xy 61.054145 -104.587222) (xy 61.003087 -104.606267)
			(xy 60.949839 -104.617851) (xy 60.895484 -104.621739) (xy 60.841129 -104.617851) (xy 60.787881 -104.606267)
			(xy 60.736823 -104.587222) (xy 60.688996 -104.561105) (xy 60.645372 -104.528447) (xy 60.606841 -104.489913)
			(xy 60.574186 -104.446287) (xy 60.548072 -104.398457) (xy 60.529031 -104.347398) (xy 60.517451 -104.294149)
			(xy 60.513567 -104.239794) (xy 44.136564 -104.239794) (xy 44.136564 -105.181396) (xy 82.396566 -105.181396)
			(xy 82.396566 -105.12146) (xy 82.404389 -105.062038) (xy 82.419902 -105.004145) (xy 82.442838 -104.948772)
			(xy 82.472805 -104.896866) (xy 82.509292 -104.849316) (xy 82.551672 -104.806936) (xy 82.599222 -104.770449)
			(xy 82.651128 -104.740482) (xy 82.706501 -104.717546) (xy 82.764394 -104.702033) (xy 82.823816 -104.69421)
			(xy 82.883752 -104.69421) (xy 82.943174 -104.702033) (xy 83.001067 -104.717546) (xy 83.05644 -104.740482)
			(xy 83.108346 -104.770449) (xy 83.155896 -104.806936) (xy 83.198276 -104.849316) (xy 83.234763 -104.896866)
			(xy 83.26473 -104.948772) (xy 83.287666 -105.004145) (xy 83.303179 -105.062038) (xy 83.311002 -105.12146)
			(xy 83.311492 -105.151428) (xy 83.311002 -105.181396) (xy 83.303179 -105.240818) (xy 83.287666 -105.298711)
			(xy 83.26473 -105.354084) (xy 83.234763 -105.40599) (xy 83.198276 -105.45354) (xy 83.155896 -105.49592)
			(xy 83.108346 -105.532407) (xy 83.05644 -105.562374) (xy 83.001067 -105.58531) (xy 82.943174 -105.600823)
			(xy 82.883752 -105.608646) (xy 82.823816 -105.608646) (xy 82.764394 -105.600823) (xy 82.706501 -105.58531)
			(xy 82.651128 -105.562374) (xy 82.599222 -105.532407) (xy 82.551672 -105.49592) (xy 82.509292 -105.45354)
			(xy 82.472805 -105.40599) (xy 82.442838 -105.354084) (xy 82.419902 -105.298711) (xy 82.404389 -105.240818)
			(xy 82.396566 -105.181396) (xy 44.136564 -105.181396) (xy 44.136564 -106.29392) (xy 50.87366 -106.29392)
			(xy 52.525168 -106.29392) (xy 52.525168 -106.908064) (xy 60.513567 -106.908064) (xy 60.517459 -106.853709)
			(xy 60.529047 -106.800462) (xy 60.548095 -106.749406) (xy 60.574216 -106.70158) (xy 60.590176 -106.679492)
			(xy 60.60378 -106.660485) (xy 60.624514 -106.618601) (xy 60.63724 -106.573632) (xy 60.64153 -106.527094)
			(xy 60.637238 -106.480556) (xy 60.624509 -106.435587) (xy 60.603773 -106.393704) (xy 60.590176 -106.374692)
			(xy 60.574216 -106.352604) (xy 60.548095 -106.304778) (xy 60.529047 -106.253722) (xy 60.517459 -106.200475)
			(xy 60.513567 -106.14612) (xy 60.517451 -106.091765) (xy 60.529031 -106.038516) (xy 60.548072 -105.987457)
			(xy 60.574186 -105.939627) (xy 60.606841 -105.896001) (xy 60.645372 -105.857467) (xy 60.688996 -105.824809)
			(xy 60.736823 -105.798692) (xy 60.787881 -105.779647) (xy 60.841129 -105.768063) (xy 60.895484 -105.764175)
			(xy 60.949839 -105.768063) (xy 61.003087 -105.779647) (xy 61.054145 -105.798692) (xy 61.101972 -105.824809)
			(xy 61.145596 -105.857467) (xy 61.184127 -105.896001) (xy 61.216782 -105.939627) (xy 61.242896 -105.987457)
			(xy 61.261937 -106.038516) (xy 61.273517 -106.091765) (xy 61.277401 -106.14612) (xy 61.273509 -106.200475)
			(xy 61.261921 -106.253722) (xy 61.242873 -106.304778) (xy 61.216752 -106.352604) (xy 61.200792 -106.374692)
			(xy 61.187204 -106.393709) (xy 61.166472 -106.435591) (xy 61.153745 -106.480558) (xy 61.149454 -106.527094)
			(xy 61.153743 -106.573629) (xy 61.166467 -106.618597) (xy 61.187198 -106.66048) (xy 61.200792 -106.679492)
			(xy 61.216752 -106.70158) (xy 61.242873 -106.749406) (xy 61.261921 -106.800462) (xy 61.273509 -106.853709)
			(xy 61.277401 -106.908064) (xy 61.274806 -106.944386) (xy 62.791439 -106.944386) (xy 62.795331 -106.890031)
			(xy 62.806919 -106.836784) (xy 62.825967 -106.785728) (xy 62.852088 -106.737902) (xy 62.868048 -106.715814)
			(xy 62.881628 -106.696792) (xy 62.902358 -106.65491) (xy 62.915083 -106.609945) (xy 62.919374 -106.563411)
			(xy 62.915087 -106.516877) (xy 62.902366 -106.471911) (xy 62.88164 -106.430027) (xy 62.868048 -106.411014)
			(xy 62.852088 -106.388926) (xy 62.825967 -106.3411) (xy 62.806919 -106.290044) (xy 62.795331 -106.236797)
			(xy 62.791439 -106.182442) (xy 62.795323 -106.128087) (xy 62.806903 -106.074838) (xy 62.825944 -106.023779)
			(xy 62.852058 -105.975949) (xy 62.884713 -105.932323) (xy 62.923244 -105.893789) (xy 62.966868 -105.861131)
			(xy 63.014695 -105.835014) (xy 63.065753 -105.815969) (xy 63.119001 -105.804385) (xy 63.173356 -105.800497)
			(xy 63.227711 -105.804385) (xy 63.280959 -105.815969) (xy 63.332017 -105.835014) (xy 63.379844 -105.861131)
			(xy 63.423468 -105.893789) (xy 63.461999 -105.932323) (xy 63.494654 -105.975949) (xy 63.520768 -106.023779)
			(xy 63.539809 -106.074838) (xy 63.551389 -106.128087) (xy 63.555273 -106.182442) (xy 63.551381 -106.236797)
			(xy 63.539793 -106.290044) (xy 63.520745 -106.3411) (xy 63.494624 -106.388926) (xy 63.478664 -106.411014)
			(xy 63.465057 -106.430018) (xy 63.444329 -106.471904) (xy 63.431606 -106.516874) (xy 63.427319 -106.563411)
			(xy 63.43161 -106.609948) (xy 63.444337 -106.654917) (xy 63.465069 -106.696801) (xy 63.478664 -106.715814)
			(xy 63.494624 -106.737902) (xy 63.520745 -106.785728) (xy 63.539793 -106.836784) (xy 63.541597 -106.845072)
			(xy 65.041371 -106.845072) (xy 65.045263 -106.790717) (xy 65.056851 -106.73747) (xy 65.075899 -106.686414)
			(xy 65.10202 -106.638588) (xy 65.11798 -106.6165) (xy 65.131577 -106.597488) (xy 65.152311 -106.555605)
			(xy 65.165038 -106.510637) (xy 65.169328 -106.4641) (xy 65.165038 -106.417563) (xy 65.152311 -106.372595)
			(xy 65.131577 -106.330712) (xy 65.11798 -106.3117) (xy 65.10202 -106.289612) (xy 65.075899 -106.241786)
			(xy 65.056851 -106.19073) (xy 65.045263 -106.137483) (xy 65.041371 -106.083128) (xy 65.045255 -106.028773)
			(xy 65.056835 -105.975524) (xy 65.075876 -105.924465) (xy 65.10199 -105.876635) (xy 65.134645 -105.833009)
			(xy 65.173176 -105.794475) (xy 65.2168 -105.761817) (xy 65.264627 -105.7357) (xy 65.315685 -105.716655)
			(xy 65.368933 -105.705071) (xy 65.423288 -105.701183) (xy 65.477643 -105.705071) (xy 65.530891 -105.716655)
			(xy 65.581949 -105.7357) (xy 65.629776 -105.761817) (xy 65.6734 -105.794475) (xy 65.711931 -105.833009)
			(xy 65.744586 -105.876635) (xy 65.7707 -105.924465) (xy 65.789741 -105.975524) (xy 65.801321 -106.028773)
			(xy 65.805205 -106.083128) (xy 65.801313 -106.137483) (xy 65.789725 -106.19073) (xy 65.770677 -106.241786)
			(xy 65.744556 -106.289612) (xy 65.728596 -106.3117) (xy 65.715001 -106.330712) (xy 65.694268 -106.372596)
			(xy 65.681543 -106.417563) (xy 65.677253 -106.4641) (xy 65.681543 -106.510637) (xy 65.694268 -106.555604)
			(xy 65.715001 -106.597488) (xy 65.728596 -106.6165) (xy 65.744556 -106.638588) (xy 65.770677 -106.686414)
			(xy 65.789725 -106.73747) (xy 65.801313 -106.790717) (xy 65.805205 -106.845072) (xy 65.805187 -106.845326)
			(xy 67.192243 -106.845326) (xy 67.196135 -106.790971) (xy 67.207723 -106.737724) (xy 67.226771 -106.686668)
			(xy 67.252892 -106.638842) (xy 67.268852 -106.616754) (xy 67.282493 -106.597772) (xy 67.303225 -106.555882)
			(xy 67.315948 -106.510906) (xy 67.320233 -106.464363) (xy 67.315935 -106.417821) (xy 67.303199 -106.37285)
			(xy 67.282454 -106.330965) (xy 67.268852 -106.311954) (xy 67.252892 -106.289866) (xy 67.226771 -106.24204)
			(xy 67.207723 -106.190984) (xy 67.196135 -106.137737) (xy 67.192243 -106.083382) (xy 67.196127 -106.029027)
			(xy 67.207707 -105.975778) (xy 67.226748 -105.924719) (xy 67.252862 -105.876889) (xy 67.285517 -105.833263)
			(xy 67.324048 -105.794729) (xy 67.367672 -105.762071) (xy 67.415499 -105.735954) (xy 67.466557 -105.716909)
			(xy 67.519805 -105.705325) (xy 67.57416 -105.701437) (xy 67.628515 -105.705325) (xy 67.681763 -105.716909)
			(xy 67.732821 -105.735954) (xy 67.780648 -105.762071) (xy 67.824272 -105.794729) (xy 67.862803 -105.833263)
			(xy 67.895458 -105.876889) (xy 67.921572 -105.924719) (xy 67.940613 -105.975778) (xy 67.952193 -106.029027)
			(xy 67.956077 -106.083382) (xy 67.952185 -106.137737) (xy 67.940597 -106.190984) (xy 67.921549 -106.24204)
			(xy 67.895428 -106.289866) (xy 67.879468 -106.311954) (xy 67.865917 -106.330996) (xy 67.845183 -106.372872)
			(xy 67.832454 -106.417833) (xy 67.828158 -106.464363) (xy 67.83244 -106.510895) (xy 67.845157 -106.555859)
			(xy 67.865878 -106.597741) (xy 67.879468 -106.616754) (xy 67.895428 -106.638842) (xy 67.921549 -106.686668)
			(xy 67.940597 -106.737724) (xy 67.952185 -106.790971) (xy 67.956077 -106.845326) (xy 67.953482 -106.881648)
			(xy 69.348957 -106.881648) (xy 69.352849 -106.827293) (xy 69.364437 -106.774046) (xy 69.383485 -106.72299)
			(xy 69.409606 -106.675164) (xy 69.425566 -106.653076) (xy 69.439186 -106.63408) (xy 69.459919 -106.592193)
			(xy 69.472644 -106.547221) (xy 69.476931 -106.500681) (xy 69.472637 -106.454141) (xy 69.459905 -106.409171)
			(xy 69.439165 -106.367287) (xy 69.425566 -106.348276) (xy 69.409606 -106.326188) (xy 69.383485 -106.278362)
			(xy 69.364437 -106.227306) (xy 69.352849 -106.174059) (xy 69.348957 -106.119704) (xy 69.352841 -106.065349)
			(xy 69.364421 -106.0121) (xy 69.383462 -105.961041) (xy 69.409576 -105.913211) (xy 69.442231 -105.869585)
			(xy 69.480762 -105.831051) (xy 69.524386 -105.798393) (xy 69.572213 -105.772276) (xy 69.623271 -105.753231)
			(xy 69.676519 -105.741647) (xy 69.730874 -105.737759) (xy 69.785229 -105.741647) (xy 69.838477 -105.753231)
			(xy 69.889535 -105.772276) (xy 69.937362 -105.798393) (xy 69.980986 -105.831051) (xy 70.019517 -105.869585)
			(xy 70.052172 -105.913211) (xy 70.078286 -105.961041) (xy 70.097327 -106.0121) (xy 70.108907 -106.065349)
			(xy 70.112791 -106.119704) (xy 70.108899 -106.174059) (xy 70.097311 -106.227306) (xy 70.078263 -106.278362)
			(xy 70.076566 -106.28147) (xy 81.664284 -106.28147) (xy 81.664284 -106.221534) (xy 81.672107 -106.162112)
			(xy 81.68762 -106.104219) (xy 81.710556 -106.048846) (xy 81.740523 -105.99694) (xy 81.77701 -105.94939)
			(xy 81.81939 -105.90701) (xy 81.86694 -105.870523) (xy 81.918846 -105.840556) (xy 81.974219 -105.81762)
			(xy 82.032112 -105.802107) (xy 82.091534 -105.794284) (xy 82.15147 -105.794284) (xy 82.210892 -105.802107)
			(xy 82.268785 -105.81762) (xy 82.324158 -105.840556) (xy 82.376064 -105.870523) (xy 82.423614 -105.90701)
			(xy 82.465994 -105.94939) (xy 82.502481 -105.99694) (xy 82.532448 -106.048846) (xy 82.555384 -106.104219)
			(xy 82.570897 -106.162112) (xy 82.57872 -106.221534) (xy 82.57921 -106.251502) (xy 82.57872 -106.28147)
			(xy 82.570897 -106.340892) (xy 82.555384 -106.398785) (xy 82.532448 -106.454158) (xy 82.502481 -106.506064)
			(xy 82.465994 -106.553614) (xy 82.423614 -106.595994) (xy 82.376064 -106.632481) (xy 82.324158 -106.662448)
			(xy 82.268785 -106.685384) (xy 82.210892 -106.700897) (xy 82.15147 -106.70872) (xy 82.091534 -106.70872)
			(xy 82.032112 -106.700897) (xy 81.974219 -106.685384) (xy 81.918846 -106.662448) (xy 81.86694 -106.632481)
			(xy 81.81939 -106.595994) (xy 81.77701 -106.553614) (xy 81.740523 -106.506064) (xy 81.710556 -106.454158)
			(xy 81.68762 -106.398785) (xy 81.672107 -106.340892) (xy 81.664284 -106.28147) (xy 70.076566 -106.28147)
			(xy 70.052142 -106.326188) (xy 70.036182 -106.348276) (xy 70.02261 -106.367304) (xy 70.001877 -106.409183)
			(xy 69.989149 -106.454148) (xy 69.984856 -106.500681) (xy 69.989142 -106.547215) (xy 70.001863 -106.592181)
			(xy 70.02259 -106.634064) (xy 70.036182 -106.653076) (xy 70.052142 -106.675164) (xy 70.078263 -106.72299)
			(xy 70.097311 -106.774046) (xy 70.108899 -106.827293) (xy 70.112791 -106.881648) (xy 70.108907 -106.936003)
			(xy 70.097327 -106.989252) (xy 70.078286 -107.040311) (xy 70.052172 -107.088141) (xy 70.019517 -107.131767)
			(xy 69.980986 -107.170301) (xy 69.937362 -107.202959) (xy 69.889535 -107.229076) (xy 69.838477 -107.248121)
			(xy 69.785229 -107.259705) (xy 69.730874 -107.263593) (xy 69.676519 -107.259705) (xy 69.623271 -107.248121)
			(xy 69.572213 -107.229076) (xy 69.524386 -107.202959) (xy 69.480762 -107.170301) (xy 69.442231 -107.131767)
			(xy 69.409576 -107.088141) (xy 69.383462 -107.040311) (xy 69.364421 -106.989252) (xy 69.352841 -106.936003)
			(xy 69.348957 -106.881648) (xy 67.953482 -106.881648) (xy 67.952193 -106.899681) (xy 67.940613 -106.95293)
			(xy 67.921572 -107.003989) (xy 67.895458 -107.051819) (xy 67.862803 -107.095445) (xy 67.824272 -107.133979)
			(xy 67.780648 -107.166637) (xy 67.732821 -107.192754) (xy 67.681763 -107.211799) (xy 67.628515 -107.223383)
			(xy 67.57416 -107.227271) (xy 67.519805 -107.223383) (xy 67.466557 -107.211799) (xy 67.415499 -107.192754)
			(xy 67.367672 -107.166637) (xy 67.324048 -107.133979) (xy 67.285517 -107.095445) (xy 67.252862 -107.051819)
			(xy 67.226748 -107.003989) (xy 67.207707 -106.95293) (xy 67.196127 -106.899681) (xy 67.192243 -106.845326)
			(xy 65.805187 -106.845326) (xy 65.801321 -106.899427) (xy 65.789741 -106.952676) (xy 65.7707 -107.003735)
			(xy 65.744586 -107.051565) (xy 65.711931 -107.095191) (xy 65.6734 -107.133725) (xy 65.629776 -107.166383)
			(xy 65.581949 -107.1925) (xy 65.530891 -107.211545) (xy 65.477643 -107.223129) (xy 65.423288 -107.227017)
			(xy 65.368933 -107.223129) (xy 65.315685 -107.211545) (xy 65.264627 -107.1925) (xy 65.2168 -107.166383)
			(xy 65.173176 -107.133725) (xy 65.134645 -107.095191) (xy 65.10199 -107.051565) (xy 65.075876 -107.003735)
			(xy 65.056835 -106.952676) (xy 65.045255 -106.899427) (xy 65.041371 -106.845072) (xy 63.541597 -106.845072)
			(xy 63.551381 -106.890031) (xy 63.555273 -106.944386) (xy 63.551389 -106.998741) (xy 63.539809 -107.05199)
			(xy 63.520768 -107.103049) (xy 63.494654 -107.150879) (xy 63.461999 -107.194505) (xy 63.423468 -107.233039)
			(xy 63.379844 -107.265697) (xy 63.332017 -107.291814) (xy 63.280959 -107.310859) (xy 63.227711 -107.322443)
			(xy 63.173356 -107.326331) (xy 63.119001 -107.322443) (xy 63.065753 -107.310859) (xy 63.014695 -107.291814)
			(xy 62.966868 -107.265697) (xy 62.923244 -107.233039) (xy 62.884713 -107.194505) (xy 62.852058 -107.150879)
			(xy 62.825944 -107.103049) (xy 62.806903 -107.05199) (xy 62.795323 -106.998741) (xy 62.791439 -106.944386)
			(xy 61.274806 -106.944386) (xy 61.273517 -106.962419) (xy 61.261937 -107.015668) (xy 61.242896 -107.066727)
			(xy 61.216782 -107.114557) (xy 61.184127 -107.158183) (xy 61.145596 -107.196717) (xy 61.101972 -107.229375)
			(xy 61.054145 -107.255492) (xy 61.003087 -107.274537) (xy 60.949839 -107.286121) (xy 60.895484 -107.290009)
			(xy 60.841129 -107.286121) (xy 60.787881 -107.274537) (xy 60.736823 -107.255492) (xy 60.688996 -107.229375)
			(xy 60.645372 -107.196717) (xy 60.606841 -107.158183) (xy 60.574186 -107.114557) (xy 60.548072 -107.066727)
			(xy 60.529031 -107.015668) (xy 60.517451 -106.962419) (xy 60.513567 -106.908064) (xy 52.525168 -106.908064)
			(xy 52.525168 -107.529118) (xy 81.071702 -107.529118) (xy 81.071702 -107.469182) (xy 81.079525 -107.40976)
			(xy 81.095038 -107.351867) (xy 81.117974 -107.296494) (xy 81.147941 -107.244588) (xy 81.184428 -107.197038)
			(xy 81.226808 -107.154658) (xy 81.274358 -107.118171) (xy 81.326264 -107.088204) (xy 81.381637 -107.065268)
			(xy 81.43953 -107.049755) (xy 81.498952 -107.041932) (xy 81.558888 -107.041932) (xy 81.61831 -107.049755)
			(xy 81.676203 -107.065268) (xy 81.731576 -107.088204) (xy 81.783482 -107.118171) (xy 81.831032 -107.154658)
			(xy 81.873412 -107.197038) (xy 81.909899 -107.244588) (xy 81.939866 -107.296494) (xy 81.962802 -107.351867)
			(xy 81.978315 -107.40976) (xy 81.986138 -107.469182) (xy 81.986628 -107.49915) (xy 81.986138 -107.529118)
			(xy 81.978315 -107.58854) (xy 81.962802 -107.646433) (xy 81.939866 -107.701806) (xy 81.909899 -107.753712)
			(xy 81.873412 -107.801262) (xy 81.831032 -107.843642) (xy 81.783482 -107.880129) (xy 81.731576 -107.910096)
			(xy 81.676203 -107.933032) (xy 81.61831 -107.948545) (xy 81.558888 -107.956368) (xy 81.498952 -107.956368)
			(xy 81.43953 -107.948545) (xy 81.381637 -107.933032) (xy 81.326264 -107.910096) (xy 81.274358 -107.880129)
			(xy 81.226808 -107.843642) (xy 81.184428 -107.801262) (xy 81.147941 -107.753712) (xy 81.117974 -107.701806)
			(xy 81.095038 -107.646433) (xy 81.079525 -107.58854) (xy 81.071702 -107.529118) (xy 52.525168 -107.529118)
			(xy 52.525168 -107.945936) (xy 50.87366 -107.945936) (xy 50.87366 -106.29392) (xy 44.136564 -106.29392)
			(xy 44.136564 -107.160483) (xy 47.373784 -107.160483) (xy 47.373784 -107.079373) (xy 47.381734 -106.998654)
			(xy 47.397557 -106.919103) (xy 47.421102 -106.841487) (xy 47.452141 -106.766551) (xy 47.490376 -106.695019)
			(xy 47.535438 -106.627579) (xy 47.586893 -106.56488) (xy 47.644246 -106.507527) (xy 47.706945 -106.456072)
			(xy 47.774385 -106.41101) (xy 47.845917 -106.372775) (xy 47.920853 -106.341736) (xy 47.998469 -106.318191)
			(xy 48.07802 -106.302368) (xy 48.158739 -106.294418) (xy 48.239849 -106.294418) (xy 48.320568 -106.302368)
			(xy 48.400119 -106.318191) (xy 48.477735 -106.341736) (xy 48.552671 -106.372775) (xy 48.624203 -106.41101)
			(xy 48.691643 -106.456072) (xy 48.754342 -106.507527) (xy 48.811695 -106.56488) (xy 48.86315 -106.627579)
			(xy 48.908212 -106.695019) (xy 48.946447 -106.766551) (xy 48.977486 -106.841487) (xy 49.001031 -106.919103)
			(xy 49.016854 -106.998654) (xy 49.024804 -107.079373) (xy 49.025302 -107.119928) (xy 49.024804 -107.160483)
			(xy 49.016854 -107.241202) (xy 49.001031 -107.320753) (xy 48.977486 -107.398369) (xy 48.946447 -107.473305)
			(xy 48.908212 -107.544837) (xy 48.86315 -107.612277) (xy 48.811695 -107.674976) (xy 48.754342 -107.732329)
			(xy 48.691643 -107.783784) (xy 48.624203 -107.828846) (xy 48.552671 -107.867081) (xy 48.477735 -107.89812)
			(xy 48.400119 -107.921665) (xy 48.320568 -107.937488) (xy 48.239849 -107.945438) (xy 48.158739 -107.945438)
			(xy 48.07802 -107.937488) (xy 47.998469 -107.921665) (xy 47.920853 -107.89812) (xy 47.845917 -107.867081)
			(xy 47.774385 -107.828846) (xy 47.706945 -107.783784) (xy 47.644246 -107.732329) (xy 47.586893 -107.674976)
			(xy 47.535438 -107.612277) (xy 47.490376 -107.544837) (xy 47.452141 -107.473305) (xy 47.421102 -107.398369)
			(xy 47.397557 -107.320753) (xy 47.381734 -107.241202) (xy 47.373784 -107.160483) (xy 44.136564 -107.160483)
			(xy 44.136564 -108.91012) (xy 86.39887 -108.91012) (xy 86.402874 -108.710022) (xy 86.414881 -108.510244)
			(xy 86.434872 -108.311107) (xy 86.462814 -108.112929) (xy 86.498662 -107.916027) (xy 86.54236 -107.720718)
			(xy 86.593837 -107.527313) (xy 86.653011 -107.336123) (xy 86.719787 -107.147453) (xy 86.794059 -106.961606)
			(xy 86.875706 -106.778879) (xy 86.964599 -106.599566) (xy 87.060595 -106.423952) (xy 87.16354 -106.25232)
			(xy 87.27327 -106.084944) (xy 87.389608 -105.922093) (xy 87.512369 -105.764026) (xy 87.641356 -105.610998)
			(xy 87.776363 -105.463253) (xy 87.917172 -105.321027) (xy 88.063559 -105.18455) (xy 88.215289 -105.054038)
			(xy 88.37212 -104.929702) (xy 88.533799 -104.81174) (xy 88.700069 -104.700341) (xy 88.870662 -104.595684)
			(xy 89.045306 -104.497936) (xy 89.223722 -104.407253) (xy 89.405622 -104.323782) (xy 89.590717 -104.247655)
			(xy 89.778709 -104.178995) (xy 89.969298 -104.117911) (xy 90.162178 -104.064501) (xy 90.35704 -104.018852)
			(xy 90.553573 -103.981035) (xy 90.751462 -103.951111) (xy 90.950389 -103.929129) (xy 91.150037 -103.915124)
			(xy 91.350085 -103.909118) (xy 91.550213 -103.91112) (xy 91.750101 -103.921128) (xy 91.949428 -103.939125)
			(xy 92.147876 -103.965083) (xy 92.345126 -103.99896) (xy 92.540863 -104.040702) (xy 92.734773 -104.090241)
			(xy 92.926546 -104.147499) (xy 93.115875 -104.212384) (xy 93.302455 -104.284792) (xy 93.48599 -104.364608)
			(xy 93.666184 -104.451702) (xy 93.842749 -104.545936) (xy 94.015402 -104.647159) (xy 94.183867 -104.755209)
			(xy 94.347875 -104.869912) (xy 94.507162 -104.991086) (xy 94.661473 -105.118535) (xy 94.810561 -105.252056)
			(xy 94.954188 -105.391436) (xy 95.092124 -105.53645) (xy 95.224147 -105.686867) (xy 95.350046 -105.842445)
			(xy 95.46962 -106.002937) (xy 95.582676 -106.168083) (xy 95.689035 -106.337621) (xy 95.788526 -106.511279)
			(xy 95.880989 -106.688778) (xy 95.966276 -106.869834) (xy 96.044251 -107.054158) (xy 96.114788 -107.241454)
			(xy 96.177776 -107.431422) (xy 96.233113 -107.623758) (xy 96.28071 -107.818154) (xy 96.320491 -108.014299)
			(xy 96.352393 -108.211878) (xy 96.376364 -108.410575) (xy 96.392366 -108.610073) (xy 96.400373 -108.810051)
			(xy 96.400874 -108.91012) (xy 96.400373 -109.010189) (xy 96.392366 -109.210167) (xy 96.376364 -109.409665)
			(xy 96.352393 -109.608362) (xy 96.320491 -109.805941) (xy 96.28071 -110.002086) (xy 96.233113 -110.196482)
			(xy 96.177776 -110.388818) (xy 96.114788 -110.578786) (xy 96.044251 -110.766082) (xy 95.966276 -110.950406)
			(xy 95.880989 -111.131462) (xy 95.788526 -111.308961) (xy 95.689035 -111.482619) (xy 95.582676 -111.652157)
			(xy 95.46962 -111.817303) (xy 95.350046 -111.977795) (xy 95.224147 -112.133373) (xy 95.092124 -112.28379)
			(xy 94.954188 -112.428804) (xy 94.810561 -112.568184) (xy 94.661473 -112.701705) (xy 94.507162 -112.829154)
			(xy 94.347875 -112.950328) (xy 94.183867 -113.065031) (xy 94.015402 -113.173081) (xy 93.842749 -113.274304)
			(xy 93.666184 -113.368538) (xy 93.48599 -113.455632) (xy 93.302455 -113.535448) (xy 93.115875 -113.607856)
			(xy 92.926546 -113.672741) (xy 92.734773 -113.729999) (xy 92.540863 -113.779538) (xy 92.345126 -113.82128)
			(xy 92.147876 -113.855157) (xy 91.949428 -113.881115) (xy 91.750101 -113.899112) (xy 91.550213 -113.90912)
			(xy 91.350085 -113.911122) (xy 91.150037 -113.905116) (xy 90.950389 -113.891111) (xy 90.751462 -113.869129)
			(xy 90.553573 -113.839205) (xy 90.35704 -113.801388) (xy 90.162178 -113.755739) (xy 89.969298 -113.702329)
			(xy 89.778709 -113.641245) (xy 89.590717 -113.572585) (xy 89.405622 -113.496458) (xy 89.223722 -113.412987)
			(xy 89.045306 -113.322304) (xy 88.870662 -113.224556) (xy 88.700069 -113.119899) (xy 88.533799 -113.0085)
			(xy 88.37212 -112.890538) (xy 88.215289 -112.766202) (xy 88.063559 -112.63569) (xy 87.917172 -112.499213)
			(xy 87.776363 -112.356987) (xy 87.641356 -112.209242) (xy 87.512369 -112.056214) (xy 87.389608 -111.898147)
			(xy 87.27327 -111.735296) (xy 87.16354 -111.56792) (xy 87.060595 -111.396288) (xy 86.964599 -111.220674)
			(xy 86.875706 -111.041361) (xy 86.794059 -110.858634) (xy 86.719787 -110.672787) (xy 86.653011 -110.484117)
			(xy 86.593837 -110.292927) (xy 86.54236 -110.099522) (xy 86.498662 -109.904213) (xy 86.462814 -109.707311)
			(xy 86.434872 -109.509133) (xy 86.414881 -109.309996) (xy 86.402874 -109.110218) (xy 86.39887 -108.91012)
			(xy 44.136564 -108.91012) (xy 44.136564 -112.515142) (xy 38.99383 -117.657876) (xy 67.03617 -117.657876)
			(xy 67.03617 -117.59794) (xy 67.043993 -117.538518) (xy 67.059506 -117.480625) (xy 67.082442 -117.425252)
			(xy 67.112409 -117.373346) (xy 67.148896 -117.325796) (xy 67.191276 -117.283416) (xy 67.238826 -117.246929)
			(xy 67.290732 -117.216962) (xy 67.346105 -117.194026) (xy 67.403998 -117.178513) (xy 67.46342 -117.17069)
			(xy 67.523356 -117.17069) (xy 67.582778 -117.178513) (xy 67.640671 -117.194026) (xy 67.696044 -117.216962)
			(xy 67.74795 -117.246929) (xy 67.7955 -117.283416) (xy 67.83788 -117.325796) (xy 67.874367 -117.373346)
			(xy 67.904334 -117.425252) (xy 67.92727 -117.480625) (xy 67.942783 -117.538518) (xy 67.950606 -117.59794)
			(xy 67.951096 -117.627908) (xy 67.950606 -117.657876) (xy 67.942783 -117.717298) (xy 67.92727 -117.775191)
			(xy 67.904334 -117.830564) (xy 67.874367 -117.88247) (xy 67.83788 -117.93002) (xy 67.7955 -117.9724)
			(xy 67.74795 -118.008887) (xy 67.696044 -118.038854) (xy 67.640671 -118.06179) (xy 67.582778 -118.077303)
			(xy 67.523356 -118.085126) (xy 67.46342 -118.085126) (xy 67.403998 -118.077303) (xy 67.346105 -118.06179)
			(xy 67.290732 -118.038854) (xy 67.238826 -118.008887) (xy 67.191276 -117.9724) (xy 67.148896 -117.93002)
			(xy 67.112409 -117.88247) (xy 67.082442 -117.830564) (xy 67.059506 -117.775191) (xy 67.043993 -117.717298)
			(xy 67.03617 -117.657876) (xy 38.99383 -117.657876) (xy 38.882066 -117.76964) (xy 30.3403 -117.76964)
			(xy 29.820108 -118.289832) (xy 29.820108 -120.344688) (xy 67.03998 -120.344688) (xy 67.03998 -120.284752)
			(xy 67.047803 -120.22533) (xy 67.063316 -120.167437) (xy 67.086252 -120.112064) (xy 67.116219 -120.060158)
			(xy 67.152706 -120.012608) (xy 67.195086 -119.970228) (xy 67.242636 -119.933741) (xy 67.294542 -119.903774)
			(xy 67.349915 -119.880838) (xy 67.407808 -119.865325) (xy 67.46723 -119.857502) (xy 67.527166 -119.857502)
			(xy 67.586588 -119.865325) (xy 67.644481 -119.880838) (xy 67.699854 -119.903774) (xy 67.75176 -119.933741)
			(xy 67.79931 -119.970228) (xy 67.84169 -120.012608) (xy 67.878177 -120.060158) (xy 67.908144 -120.112064)
			(xy 67.93108 -120.167437) (xy 67.946593 -120.22533) (xy 67.954416 -120.284752) (xy 67.954906 -120.31472)
			(xy 67.954416 -120.344688) (xy 67.946593 -120.40411) (xy 67.93108 -120.462003) (xy 67.908144 -120.517376)
			(xy 67.878177 -120.569282) (xy 67.84169 -120.616832) (xy 67.79931 -120.659212) (xy 67.75176 -120.695699)
			(xy 67.699854 -120.725666) (xy 67.644481 -120.748602) (xy 67.586588 -120.764115) (xy 67.527166 -120.771938)
			(xy 67.46723 -120.771938) (xy 67.407808 -120.764115) (xy 67.349915 -120.748602) (xy 67.294542 -120.725666)
			(xy 67.242636 -120.695699) (xy 67.195086 -120.659212) (xy 67.152706 -120.616832) (xy 67.116219 -120.569282)
			(xy 67.086252 -120.517376) (xy 67.063316 -120.462003) (xy 67.047803 -120.40411) (xy 67.03998 -120.344688)
			(xy 29.820108 -120.344688) (xy 29.820108 -121.19991) (xy 72.998592 -121.19991) (xy 73.002596 -120.999802)
			(xy 73.014604 -120.800014) (xy 73.034596 -120.600866) (xy 73.062539 -120.402678) (xy 73.098389 -120.205767)
			(xy 73.14209 -120.010447) (xy 73.193569 -119.817033) (xy 73.252746 -119.625833) (xy 73.319526 -119.437153)
			(xy 73.393801 -119.251297) (xy 73.475452 -119.068561) (xy 73.56435 -118.889238) (xy 73.66035 -118.713616)
			(xy 73.763301 -118.541975) (xy 73.873036 -118.374591) (xy 73.989381 -118.211731) (xy 74.112148 -118.053656)
			(xy 74.241141 -117.90062) (xy 74.376154 -117.752868) (xy 74.516971 -117.610635) (xy 74.663365 -117.474151)
			(xy 74.815103 -117.343632) (xy 74.971942 -117.21929) (xy 75.133629 -117.101322) (xy 75.299908 -116.989917)
			(xy 75.47051 -116.885255) (xy 75.645163 -116.787502) (xy 75.823587 -116.696815) (xy 76.005497 -116.613339)
			(xy 76.190601 -116.537208) (xy 76.378603 -116.468544) (xy 76.569201 -116.407457) (xy 76.762091 -116.354045)
			(xy 76.956963 -116.308393) (xy 77.153506 -116.270574) (xy 77.351405 -116.24065) (xy 77.550342 -116.218666)
			(xy 77.75 -116.20466) (xy 77.950058 -116.198654) (xy 78.150197 -116.200656) (xy 78.350095 -116.210665)
			(xy 78.549432 -116.228663) (xy 78.74789 -116.254622) (xy 78.94515 -116.2885) (xy 79.140897 -116.330244)
			(xy 79.334817 -116.379786) (xy 79.5266 -116.437047) (xy 79.715938 -116.501936) (xy 79.902528 -116.574348)
			(xy 80.086072 -116.654167) (xy 80.266275 -116.741266) (xy 80.442849 -116.835504) (xy 80.615511 -116.936733)
			(xy 80.783985 -117.044788) (xy 80.948001 -117.159497) (xy 81.107296 -117.280677) (xy 81.261615 -117.408132)
			(xy 81.410711 -117.541661) (xy 81.554345 -117.681047) (xy 81.692287 -117.826069) (xy 81.824317 -117.976493)
			(xy 81.950223 -118.13208) (xy 82.069802 -118.292579) (xy 82.182865 -118.457734) (xy 82.289229 -118.627281)
			(xy 82.388725 -118.800947) (xy 82.481192 -118.978455) (xy 82.566484 -119.159521) (xy 82.644463 -119.343854)
			(xy 82.715004 -119.531159) (xy 82.777995 -119.721137) (xy 82.833334 -119.913483) (xy 82.880934 -120.107888)
			(xy 82.920717 -120.304043) (xy 82.95262 -120.501633) (xy 82.976592 -120.70034) (xy 82.992595 -120.899848)
			(xy 83.000603 -121.099836) (xy 83.001104 -121.19991) (xy 83.000603 -121.299984) (xy 82.992595 -121.499972)
			(xy 82.976592 -121.69948) (xy 82.95262 -121.898187) (xy 82.920717 -122.095777) (xy 82.880934 -122.291932)
			(xy 82.833334 -122.486337) (xy 82.777995 -122.678683) (xy 82.715004 -122.868661) (xy 82.644463 -123.055966)
			(xy 82.566484 -123.240299) (xy 82.481192 -123.421365) (xy 82.388725 -123.598873) (xy 82.289229 -123.772539)
			(xy 82.182865 -123.942086) (xy 82.069802 -124.107241) (xy 81.950223 -124.26774) (xy 81.824317 -124.423327)
			(xy 81.692287 -124.573751) (xy 81.554345 -124.718773) (xy 81.410711 -124.858159) (xy 81.261615 -124.991688)
			(xy 81.107296 -125.119143) (xy 80.948001 -125.240323) (xy 80.783985 -125.355032) (xy 80.615511 -125.463087)
			(xy 80.442849 -125.564316) (xy 80.266275 -125.658554) (xy 80.086072 -125.745653) (xy 79.902528 -125.825472)
			(xy 79.715938 -125.897884) (xy 79.5266 -125.962773) (xy 79.334817 -126.020034) (xy 79.140897 -126.069576)
			(xy 78.94515 -126.11132) (xy 78.74789 -126.145198) (xy 78.549432 -126.171157) (xy 78.350095 -126.189155)
			(xy 78.150197 -126.199164) (xy 77.950058 -126.201166) (xy 77.75 -126.19516) (xy 77.550342 -126.181154)
			(xy 77.351405 -126.15917) (xy 77.153506 -126.129246) (xy 76.956963 -126.091427) (xy 76.762091 -126.045775)
			(xy 76.569201 -125.992363) (xy 76.378603 -125.931276) (xy 76.190601 -125.862612) (xy 76.005497 -125.786481)
			(xy 75.823587 -125.703005) (xy 75.645163 -125.612318) (xy 75.47051 -125.514565) (xy 75.299908 -125.409903)
			(xy 75.133629 -125.298498) (xy 74.971942 -125.18053) (xy 74.815103 -125.056188) (xy 74.663365 -124.925669)
			(xy 74.516971 -124.789185) (xy 74.376154 -124.646952) (xy 74.241141 -124.4992) (xy 74.112148 -124.346164)
			(xy 73.989381 -124.188089) (xy 73.873036 -124.025229) (xy 73.763301 -123.857845) (xy 73.66035 -123.686204)
			(xy 73.56435 -123.510582) (xy 73.475452 -123.331259) (xy 73.393801 -123.148523) (xy 73.319526 -122.962667)
			(xy 73.252746 -122.773987) (xy 73.193569 -122.582787) (xy 73.14209 -122.389373) (xy 73.098389 -122.194053)
			(xy 73.062539 -121.997142) (xy 73.034596 -121.798954) (xy 73.014604 -121.599806) (xy 73.002596 -121.400018)
			(xy 72.998592 -121.19991) (xy 29.820108 -121.19991) (xy 29.820108 -127.829564) (xy 51.074828 -127.829564)
			(xy 52.726336 -127.829564) (xy 52.726336 -129.481072) (xy 51.074828 -129.481072) (xy 51.074828 -127.829564)
			(xy 29.820108 -127.829564) (xy 29.820108 -128.695873) (xy 47.574952 -128.695873) (xy 47.574952 -128.614763)
			(xy 47.582902 -128.534044) (xy 47.598725 -128.454493) (xy 47.62227 -128.376877) (xy 47.653309 -128.301941)
			(xy 47.691544 -128.230409) (xy 47.736606 -128.162969) (xy 47.788061 -128.10027) (xy 47.845414 -128.042917)
			(xy 47.908113 -127.991462) (xy 47.975553 -127.9464) (xy 48.047085 -127.908165) (xy 48.122021 -127.877126)
			(xy 48.199637 -127.853581) (xy 48.279188 -127.837758) (xy 48.359907 -127.829808) (xy 48.441017 -127.829808)
			(xy 48.521736 -127.837758) (xy 48.601287 -127.853581) (xy 48.678903 -127.877126) (xy 48.753839 -127.908165)
			(xy 48.825371 -127.9464) (xy 48.892811 -127.991462) (xy 48.95551 -128.042917) (xy 49.012863 -128.10027)
			(xy 49.064318 -128.162969) (xy 49.10938 -128.230409) (xy 49.147615 -128.301941) (xy 49.178654 -128.376877)
			(xy 49.202199 -128.454493) (xy 49.218022 -128.534044) (xy 49.225972 -128.614763) (xy 49.22647 -128.655318)
			(xy 49.225972 -128.695873) (xy 49.218022 -128.776592) (xy 49.202199 -128.856143) (xy 49.178654 -128.933759)
			(xy 49.147615 -129.008695) (xy 49.10938 -129.080227) (xy 49.064318 -129.147667) (xy 49.012863 -129.210366)
			(xy 48.95551 -129.267719) (xy 48.892811 -129.319174) (xy 48.825371 -129.364236) (xy 48.753839 -129.402471)
			(xy 48.678903 -129.43351) (xy 48.601287 -129.457055) (xy 48.521736 -129.472878) (xy 48.441017 -129.480828)
			(xy 48.359907 -129.480828) (xy 48.279188 -129.472878) (xy 48.199637 -129.457055) (xy 48.122021 -129.43351)
			(xy 48.047085 -129.402471) (xy 47.975553 -129.364236) (xy 47.908113 -129.319174) (xy 47.845414 -129.267719)
			(xy 47.788061 -129.210366) (xy 47.736606 -129.147667) (xy 47.691544 -129.080227) (xy 47.653309 -129.008695)
			(xy 47.62227 -128.933759) (xy 47.598725 -128.856143) (xy 47.582902 -128.776592) (xy 47.574952 -128.695873)
			(xy 29.820108 -128.695873) (xy 29.820108 -131.215082) (xy 73.168592 -131.215082) (xy 73.172482 -131.160727)
			(xy 73.184069 -131.107479) (xy 73.203117 -131.056423) (xy 73.229237 -131.008597) (xy 73.261898 -130.964975)
			(xy 73.300435 -130.926446) (xy 73.344063 -130.893794) (xy 73.391894 -130.867684) (xy 73.442955 -130.848647)
			(xy 73.496205 -130.837071) (xy 73.550561 -130.833192) (xy 73.604915 -130.837088) (xy 73.658162 -130.848681)
			(xy 73.709216 -130.867734) (xy 73.757039 -130.89386) (xy 73.779126 -130.909822) (xy 73.798138 -130.923418)
			(xy 73.840021 -130.94415) (xy 73.884989 -130.956876) (xy 73.931526 -130.961166) (xy 73.978063 -130.956876)
			(xy 74.023031 -130.94415) (xy 74.064914 -130.923418) (xy 74.083926 -130.909822) (xy 74.105985 -130.893824)
			(xy 74.153811 -130.867703) (xy 74.204867 -130.848655) (xy 74.258114 -130.837067) (xy 74.312469 -130.833175)
			(xy 74.366824 -130.837058) (xy 74.420073 -130.848638) (xy 74.471132 -130.867677) (xy 74.518962 -130.89379)
			(xy 74.562589 -130.926444) (xy 74.601124 -130.964974) (xy 74.633783 -131.008597) (xy 74.659902 -131.056423)
			(xy 74.678949 -131.10748) (xy 74.686571 -131.142508) (xy 75.192473 -131.142508) (xy 75.19636 -131.088152)
			(xy 75.207943 -131.034902) (xy 75.226987 -130.983843) (xy 75.253104 -130.936014) (xy 75.285762 -130.892388)
			(xy 75.324296 -130.853855) (xy 75.367922 -130.821198) (xy 75.415752 -130.795083) (xy 75.466812 -130.77604)
			(xy 75.520062 -130.764459) (xy 75.574419 -130.760573) (xy 75.628775 -130.764464) (xy 75.682024 -130.776051)
			(xy 75.733082 -130.795098) (xy 75.780909 -130.821218) (xy 75.802998 -130.837178) (xy 75.82201 -130.850774)
			(xy 75.863893 -130.871506) (xy 75.908861 -130.884232) (xy 75.955398 -130.888522) (xy 76.001935 -130.884232)
			(xy 76.046903 -130.871506) (xy 76.088786 -130.850774) (xy 76.107798 -130.837178) (xy 76.129899 -130.821237)
			(xy 76.177724 -130.795118) (xy 76.228779 -130.776071) (xy 76.282026 -130.764484) (xy 76.336379 -130.760593)
			(xy 76.390733 -130.764478) (xy 76.443981 -130.776059) (xy 76.495038 -130.7951) (xy 76.542866 -130.821214)
			(xy 76.58649 -130.853869) (xy 76.625023 -130.892401) (xy 76.657679 -130.936024) (xy 76.683795 -130.983851)
			(xy 76.702837 -131.034907) (xy 76.71442 -131.088155) (xy 76.718307 -131.142508) (xy 76.716312 -131.170384)
			(xy 77.079526 -131.170384) (xy 77.083415 -131.116038) (xy 77.094999 -131.062797) (xy 77.114042 -131.011748)
			(xy 77.140157 -130.963928) (xy 77.172811 -130.920311) (xy 77.211341 -130.881786) (xy 77.25496 -130.849136)
			(xy 77.302783 -130.823026) (xy 77.353835 -130.803988) (xy 77.407076 -130.79241) (xy 77.461423 -130.788526)
			(xy 77.51577 -130.792416) (xy 77.56901 -130.804001) (xy 77.620059 -130.823046) (xy 77.667879 -130.849161)
			(xy 77.689964 -130.865118) (xy 77.708976 -130.878714) (xy 77.750859 -130.899446) (xy 77.795827 -130.912172)
			(xy 77.842364 -130.916462) (xy 77.888901 -130.912172) (xy 77.933869 -130.899446) (xy 77.975752 -130.878714)
			(xy 77.994764 -130.865118) (xy 78.016829 -130.84912) (xy 78.064658 -130.82299) (xy 78.11572 -130.803934)
			(xy 78.168974 -130.792339) (xy 78.223336 -130.788441) (xy 78.277699 -130.79232) (xy 78.330957 -130.803898)
			(xy 78.382025 -130.822937) (xy 78.429863 -130.849051) (xy 78.473498 -130.881707) (xy 78.512041 -130.920242)
			(xy 78.544706 -130.963869) (xy 78.57083 -131.011702) (xy 78.58988 -131.062766) (xy 78.601468 -131.116022)
			(xy 78.605359 -131.170384) (xy 78.601473 -131.224747) (xy 78.597548 -131.24279) (xy 79.320988 -131.24279)
			(xy 79.324877 -131.188435) (xy 79.336463 -131.135187) (xy 79.355509 -131.08413) (xy 79.381627 -131.036304)
			(xy 79.414287 -130.992681) (xy 79.452823 -130.954151) (xy 79.49645 -130.921498) (xy 79.544281 -130.895386)
			(xy 79.59534 -130.876347) (xy 79.64859 -130.864769) (xy 79.702946 -130.860888) (xy 79.7573 -130.864782)
			(xy 79.810547 -130.876373) (xy 79.861602 -130.895424) (xy 79.909427 -130.921547) (xy 79.931514 -130.937508)
			(xy 79.950526 -130.951104) (xy 79.992409 -130.971836) (xy 80.037377 -130.984562) (xy 80.083914 -130.988852)
			(xy 80.130451 -130.984562) (xy 80.175419 -130.971836) (xy 80.217302 -130.951104) (xy 80.236314 -130.937508)
			(xy 80.258387 -130.921528) (xy 80.306212 -130.895407) (xy 80.357268 -130.876359) (xy 80.410516 -130.864771)
			(xy 80.46487 -130.860879) (xy 80.519225 -130.864763) (xy 80.572475 -130.876342) (xy 80.623534 -130.895382)
			(xy 80.671363 -130.921496) (xy 80.714989 -130.95415) (xy 80.753524 -130.992681) (xy 80.786183 -131.036304)
			(xy 80.812301 -131.084131) (xy 80.831347 -131.135188) (xy 80.842932 -131.188436) (xy 80.845511 -131.224483)
			(xy 81.441402 -131.224483) (xy 81.445292 -131.170131) (xy 81.456878 -131.116885) (xy 81.475924 -131.065831)
			(xy 81.502042 -131.018007) (xy 81.534701 -130.974387) (xy 81.573236 -130.935859) (xy 81.616861 -130.903207)
			(xy 81.66469 -130.877097) (xy 81.715748 -130.85806) (xy 81.768995 -130.846483) (xy 81.823348 -130.842602)
			(xy 81.8777 -130.846497) (xy 81.930945 -130.858087) (xy 81.981998 -130.877137) (xy 82.02982 -130.903259)
			(xy 82.051906 -130.91922) (xy 82.070918 -130.932816) (xy 82.112801 -130.953548) (xy 82.157769 -130.966274)
			(xy 82.204306 -130.970564) (xy 82.250843 -130.966274) (xy 82.295811 -130.953548) (xy 82.337694 -130.932816)
			(xy 82.356706 -130.91922) (xy 82.378768 -130.903223) (xy 82.426595 -130.877099) (xy 82.477652 -130.858049)
			(xy 82.530902 -130.846458) (xy 82.585259 -130.842565) (xy 82.639616 -130.846447) (xy 82.692868 -130.858025)
			(xy 82.74393 -130.877065) (xy 82.791763 -130.903178) (xy 82.835392 -130.935833) (xy 82.873929 -130.974364)
			(xy 82.906591 -131.017988) (xy 82.932711 -131.065817) (xy 82.951758 -131.116876) (xy 82.963345 -131.170126)
			(xy 82.967235 -131.224483) (xy 82.96335 -131.278841) (xy 82.951768 -131.332092) (xy 82.932725 -131.383152)
			(xy 82.906609 -131.430983) (xy 82.873951 -131.47461) (xy 82.835417 -131.513145) (xy 82.791791 -131.545804)
			(xy 82.743961 -131.571921) (xy 82.6929 -131.590965) (xy 82.63965 -131.602549) (xy 82.585292 -131.606435)
			(xy 82.530935 -131.602546) (xy 82.477685 -131.590961) (xy 82.426625 -131.571915) (xy 82.378796 -131.545795)
			(xy 82.356706 -131.529836) (xy 82.337694 -131.51624) (xy 82.295811 -131.495508) (xy 82.250843 -131.482782)
			(xy 82.204306 -131.478492) (xy 82.157769 -131.482782) (xy 82.112801 -131.495508) (xy 82.070918 -131.51624)
			(xy 82.051906 -131.529836) (xy 82.029791 -131.545759) (xy 81.981967 -131.571877) (xy 81.930913 -131.590922)
			(xy 81.877667 -131.602508) (xy 81.823315 -131.606398) (xy 81.768962 -131.602512) (xy 81.715716 -131.590931)
			(xy 81.664659 -131.571889) (xy 81.616833 -131.545775) (xy 81.57321 -131.513119) (xy 81.534679 -131.474588)
			(xy 81.502024 -131.430965) (xy 81.47591 -131.383139) (xy 81.456869 -131.332082) (xy 81.445287 -131.278836)
			(xy 81.441402 -131.224483) (xy 80.845511 -131.224483) (xy 80.846821 -131.24279) (xy 80.842935 -131.297145)
			(xy 80.831352 -131.350394) (xy 80.812309 -131.401452) (xy 80.786194 -131.44928) (xy 80.753537 -131.492905)
			(xy 80.715004 -131.531437) (xy 80.671379 -131.564094) (xy 80.623551 -131.59021) (xy 80.572493 -131.609252)
			(xy 80.519244 -131.620835) (xy 80.46489 -131.624721) (xy 80.410535 -131.620832) (xy 80.357287 -131.609246)
			(xy 80.30623 -131.590201) (xy 80.258403 -131.564083) (xy 80.236314 -131.548124) (xy 80.217302 -131.534528)
			(xy 80.175419 -131.513796) (xy 80.130451 -131.50107) (xy 80.083914 -131.49678) (xy 80.037377 -131.50107)
			(xy 79.992409 -131.513796) (xy 79.950526 -131.534528) (xy 79.931514 -131.548124) (xy 79.90941 -131.564064)
			(xy 79.861585 -131.590184) (xy 79.810529 -131.609233) (xy 79.757281 -131.620821) (xy 79.702926 -131.624712)
			(xy 79.648571 -131.620828) (xy 79.595322 -131.609248) (xy 79.544263 -131.590206) (xy 79.496434 -131.564092)
			(xy 79.452808 -131.531436) (xy 79.414275 -131.492904) (xy 79.381617 -131.44928) (xy 79.355501 -131.401452)
			(xy 79.336457 -131.350394) (xy 79.324874 -131.297145) (xy 79.320988 -131.24279) (xy 78.597548 -131.24279)
			(xy 78.589889 -131.278004) (xy 78.570843 -131.329069) (xy 78.544723 -131.376904) (xy 78.512061 -131.420535)
			(xy 78.473522 -131.459072) (xy 78.42989 -131.491733) (xy 78.382054 -131.51785) (xy 78.330987 -131.536894)
			(xy 78.27773 -131.548475) (xy 78.223367 -131.552359) (xy 78.169005 -131.548466) (xy 78.11575 -131.536875)
			(xy 78.064687 -131.517823) (xy 78.016855 -131.491697) (xy 77.994764 -131.475734) (xy 77.975752 -131.462138)
			(xy 77.933869 -131.441406) (xy 77.888901 -131.42868) (xy 77.842364 -131.42439) (xy 77.795827 -131.42868)
			(xy 77.750859 -131.441406) (xy 77.708976 -131.462138) (xy 77.689964 -131.475734) (xy 77.667852 -131.491656)
			(xy 77.620031 -131.517767) (xy 77.56898 -131.536807) (xy 77.515739 -131.548388) (xy 77.461392 -131.552274)
			(xy 77.407045 -131.548386) (xy 77.353805 -131.536803) (xy 77.302755 -131.517761) (xy 77.254934 -131.491647)
			(xy 77.211317 -131.458994) (xy 77.172791 -131.420465) (xy 77.14014 -131.376846) (xy 77.114029 -131.329024)
			(xy 77.09499 -131.277973) (xy 77.083411 -131.224732) (xy 77.079526 -131.170384) (xy 76.716312 -131.170384)
			(xy 76.714418 -131.196862) (xy 76.702833 -131.250109) (xy 76.683788 -131.301165) (xy 76.65767 -131.34899)
			(xy 76.625011 -131.392612) (xy 76.586477 -131.431142) (xy 76.542852 -131.463795) (xy 76.495023 -131.489907)
			(xy 76.443965 -131.508946) (xy 76.390716 -131.520524) (xy 76.336362 -131.524407) (xy 76.282009 -131.520514)
			(xy 76.228763 -131.508925) (xy 76.177709 -131.489875) (xy 76.129885 -131.463754) (xy 76.107798 -131.447794)
			(xy 76.088786 -131.434198) (xy 76.046903 -131.413466) (xy 76.001935 -131.40074) (xy 75.955398 -131.39645)
			(xy 75.908861 -131.40074) (xy 75.863893 -131.413466) (xy 75.82201 -131.434198) (xy 75.802998 -131.447794)
			(xy 75.780923 -131.463773) (xy 75.733097 -131.489895) (xy 75.68204 -131.508944) (xy 75.628791 -131.520534)
			(xy 75.574435 -131.524427) (xy 75.520079 -131.520544) (xy 75.466828 -131.508964) (xy 75.415767 -131.489924)
			(xy 75.367936 -131.463811) (xy 75.324309 -131.431156) (xy 75.285773 -131.392624) (xy 75.253113 -131.349)
			(xy 75.226994 -131.301172) (xy 75.207948 -131.250114) (xy 75.196362 -131.196865) (xy 75.192473 -131.142508)
			(xy 74.686571 -131.142508) (xy 74.690535 -131.160727) (xy 74.694425 -131.215082) (xy 74.69054 -131.269437)
			(xy 74.678959 -131.322686) (xy 74.659917 -131.373744) (xy 74.633803 -131.421573) (xy 74.601147 -131.465199)
			(xy 74.562616 -131.503733) (xy 74.518992 -131.536391) (xy 74.471165 -131.562508) (xy 74.420108 -131.581552)
			(xy 74.366859 -131.593137) (xy 74.312505 -131.597025) (xy 74.25815 -131.593138) (xy 74.204902 -131.581555)
			(xy 74.153844 -131.562512) (xy 74.106016 -131.536396) (xy 74.083926 -131.520438) (xy 74.064914 -131.506842)
			(xy 74.023031 -131.48611) (xy 73.978063 -131.473384) (xy 73.931526 -131.469094) (xy 73.884989 -131.473384)
			(xy 73.840021 -131.48611) (xy 73.798138 -131.506842) (xy 73.779126 -131.520438) (xy 73.757009 -131.53636)
			(xy 73.709184 -131.562481) (xy 73.658127 -131.581529) (xy 73.60488 -131.593117) (xy 73.550525 -131.597008)
			(xy 73.49617 -131.593124) (xy 73.44292 -131.581543) (xy 73.391862 -131.562501) (xy 73.344033 -131.536387)
			(xy 73.300407 -131.50373) (xy 73.261874 -131.465198) (xy 73.229217 -131.421573) (xy 73.203102 -131.373745)
			(xy 73.184059 -131.322686) (xy 73.172477 -131.269437) (xy 73.168592 -131.215082) (xy 29.820108 -131.215082)
			(xy 29.820108 -133.177975) (xy 73.168602 -133.177975) (xy 73.172493 -133.123621) (xy 73.18408 -133.070375)
			(xy 73.203128 -133.01932) (xy 73.229249 -132.971496) (xy 73.26191 -132.927876) (xy 73.300446 -132.889349)
			(xy 73.344074 -132.856698) (xy 73.391905 -132.83059) (xy 73.442965 -132.811554) (xy 73.496214 -132.79998)
			(xy 73.550568 -132.796102) (xy 73.604921 -132.799999) (xy 73.658166 -132.811592) (xy 73.709219 -132.830646)
			(xy 73.75704 -132.856772) (xy 73.779126 -132.872734) (xy 73.798138 -132.88633) (xy 73.840021 -132.907062)
			(xy 73.884989 -132.919788) (xy 73.931526 -132.924078) (xy 73.978063 -132.919788) (xy 74.023031 -132.907062)
			(xy 74.064914 -132.88633) (xy 74.083926 -132.872734) (xy 74.105974 -132.85672) (xy 74.1538 -132.830598)
			(xy 74.204857 -132.811548) (xy 74.258106 -132.799959) (xy 74.312462 -132.796065) (xy 74.366818 -132.799948)
			(xy 74.420069 -132.811526) (xy 74.47113 -132.830566) (xy 74.518961 -132.856678) (xy 74.562589 -132.889332)
			(xy 74.601126 -132.927862) (xy 74.633788 -132.971485) (xy 74.659908 -133.019312) (xy 74.678956 -133.07037)
			(xy 74.686579 -133.105401) (xy 75.192483 -133.105401) (xy 75.196371 -133.051046) (xy 75.207954 -132.997798)
			(xy 75.226999 -132.94674) (xy 75.253116 -132.898913) (xy 75.285774 -132.855289) (xy 75.324308 -132.816758)
			(xy 75.367934 -132.784102) (xy 75.415763 -132.757989) (xy 75.466822 -132.738948) (xy 75.520071 -132.727367)
			(xy 75.574426 -132.723483) (xy 75.62878 -132.727374) (xy 75.682028 -132.738962) (xy 75.733084 -132.75801)
			(xy 75.78091 -132.78413) (xy 75.802998 -132.80009) (xy 75.82201 -132.813686) (xy 75.863893 -132.834418)
			(xy 75.908861 -132.847144) (xy 75.955398 -132.851434) (xy 76.001935 -132.847144) (xy 76.046903 -132.834418)
			(xy 76.088786 -132.813686) (xy 76.107798 -132.80009) (xy 76.129888 -132.784133) (xy 76.177714 -132.758012)
			(xy 76.22877 -132.738964) (xy 76.282017 -132.727376) (xy 76.336372 -132.723484) (xy 76.390727 -132.727368)
			(xy 76.443976 -132.738948) (xy 76.495035 -132.757989) (xy 76.542865 -132.784102) (xy 76.586491 -132.816757)
			(xy 76.625025 -132.855289) (xy 76.657683 -132.898913) (xy 76.6838 -132.94674) (xy 76.702845 -132.997798)
			(xy 76.714429 -133.051046) (xy 76.718316 -133.105401) (xy 76.716322 -133.133277) (xy 77.079535 -133.133277)
			(xy 77.083426 -133.078932) (xy 77.09501 -133.025693) (xy 77.114054 -132.974645) (xy 77.140169 -132.926827)
			(xy 77.172823 -132.883212) (xy 77.211352 -132.844688) (xy 77.254972 -132.81204) (xy 77.302793 -132.785932)
			(xy 77.353844 -132.766896) (xy 77.407084 -132.755318) (xy 77.46143 -132.751435) (xy 77.515776 -132.755327)
			(xy 77.569014 -132.766913) (xy 77.620062 -132.785957) (xy 77.667879 -132.812073) (xy 77.689964 -132.82803)
			(xy 77.708976 -132.841626) (xy 77.750859 -132.862358) (xy 77.795827 -132.875084) (xy 77.842364 -132.879374)
			(xy 77.888901 -132.875084) (xy 77.933869 -132.862358) (xy 77.975752 -132.841626) (xy 77.994764 -132.82803)
			(xy 78.016817 -132.812016) (xy 78.064648 -132.785884) (xy 78.11571 -132.766826) (xy 78.168965 -132.75523)
			(xy 78.223329 -132.751331) (xy 78.277694 -132.75521) (xy 78.330953 -132.766786) (xy 78.382023 -132.785825)
			(xy 78.429863 -132.811939) (xy 78.473499 -132.844595) (xy 78.512043 -132.88313) (xy 78.54471 -132.926758)
			(xy 78.570836 -132.974592) (xy 78.589887 -133.025657) (xy 78.601477 -133.078913) (xy 78.605369 -133.133277)
			(xy 78.601483 -133.187642) (xy 78.597559 -133.205683) (xy 79.320997 -133.205683) (xy 79.324888 -133.15133)
			(xy 79.336474 -133.098083) (xy 79.35552 -133.047028) (xy 79.381639 -132.999203) (xy 79.414299 -132.955582)
			(xy 79.452835 -132.917053) (xy 79.496461 -132.884402) (xy 79.544291 -132.858291) (xy 79.59535 -132.839254)
			(xy 79.648599 -132.827678) (xy 79.702953 -132.823798) (xy 79.757306 -132.827693) (xy 79.810551 -132.839284)
			(xy 79.861605 -132.858335) (xy 79.909428 -132.884459) (xy 79.931514 -132.90042) (xy 79.950526 -132.914016)
			(xy 79.992409 -132.934748) (xy 80.037377 -132.947474) (xy 80.083914 -132.951764) (xy 80.130451 -132.947474)
			(xy 80.175419 -132.934748) (xy 80.217302 -132.914016) (xy 80.236314 -132.90042) (xy 80.258376 -132.884423)
			(xy 80.306202 -132.858301) (xy 80.357259 -132.839252) (xy 80.410507 -132.827662) (xy 80.464863 -132.823769)
			(xy 80.51922 -132.827652) (xy 80.57247 -132.839231) (xy 80.623531 -132.858271) (xy 80.671362 -132.884384)
			(xy 80.71499 -132.917038) (xy 80.753527 -132.955569) (xy 80.786187 -132.999192) (xy 80.812307 -133.04702)
			(xy 80.831354 -133.098078) (xy 80.84294 -133.151327) (xy 80.845521 -133.187376) (xy 81.441412 -133.187376)
			(xy 81.445303 -133.133025) (xy 81.456889 -133.079781) (xy 81.475936 -133.028728) (xy 81.502054 -132.980906)
			(xy 81.534713 -132.937288) (xy 81.573248 -132.898761) (xy 81.616873 -132.866111) (xy 81.664701 -132.840003)
			(xy 81.715757 -132.820967) (xy 81.769004 -132.809391) (xy 81.823355 -132.805512) (xy 81.877706 -132.809407)
			(xy 81.930949 -132.820998) (xy 81.982 -132.840049) (xy 82.029821 -132.866171) (xy 82.051906 -132.882132)
			(xy 82.070918 -132.895728) (xy 82.112801 -132.91646) (xy 82.157769 -132.929186) (xy 82.204306 -132.933476)
			(xy 82.250843 -132.929186) (xy 82.295811 -132.91646) (xy 82.337694 -132.895728) (xy 82.356706 -132.882132)
			(xy 82.378757 -132.866119) (xy 82.426584 -132.839994) (xy 82.477643 -132.820941) (xy 82.530893 -132.80935)
			(xy 82.585251 -132.805455) (xy 82.639611 -132.809336) (xy 82.692864 -132.820914) (xy 82.743928 -132.839953)
			(xy 82.791762 -132.866066) (xy 82.835392 -132.898721) (xy 82.873932 -132.937253) (xy 82.906595 -132.980877)
			(xy 82.932717 -133.028706) (xy 82.951765 -133.079766) (xy 82.963354 -133.133018) (xy 82.967245 -133.187376)
			(xy 82.96336 -133.241735) (xy 82.951779 -133.294988) (xy 82.932737 -133.34605) (xy 82.906621 -133.393882)
			(xy 82.873963 -133.437511) (xy 82.835429 -133.476048) (xy 82.791802 -133.508708) (xy 82.743971 -133.534827)
			(xy 82.69291 -133.553872) (xy 82.639658 -133.565457) (xy 82.585299 -133.569345) (xy 82.530941 -133.565457)
			(xy 82.477689 -133.553872) (xy 82.426628 -133.534826) (xy 82.378797 -133.508707) (xy 82.356706 -133.492748)
			(xy 82.337694 -133.479152) (xy 82.295811 -133.45842) (xy 82.250843 -133.445694) (xy 82.204306 -133.441404)
			(xy 82.157769 -133.445694) (xy 82.112801 -133.45842) (xy 82.070918 -133.479152) (xy 82.051906 -133.492748)
			(xy 82.02978 -133.508655) (xy 81.981957 -133.534771) (xy 81.930903 -133.553815) (xy 81.877659 -133.5654)
			(xy 81.823307 -133.569288) (xy 81.768956 -133.565402) (xy 81.715711 -133.553819) (xy 81.664657 -133.534777)
			(xy 81.616832 -133.508663) (xy 81.573211 -133.476007) (xy 81.534682 -133.437476) (xy 81.502028 -133.393854)
			(xy 81.475916 -133.346028) (xy 81.456876 -133.294973) (xy 81.445296 -133.241727) (xy 81.441412 -133.187376)
			(xy 80.845521 -133.187376) (xy 80.846831 -133.205683) (xy 80.842945 -133.26004) (xy 80.831363 -133.31329)
			(xy 80.812321 -133.364349) (xy 80.786206 -133.412179) (xy 80.753549 -133.455806) (xy 80.715016 -133.49434)
			(xy 80.671391 -133.526998) (xy 80.623562 -133.553115) (xy 80.572503 -133.57216) (xy 80.519253 -133.583743)
			(xy 80.464897 -133.587631) (xy 80.410541 -133.583742) (xy 80.357291 -133.572158) (xy 80.306232 -133.553113)
			(xy 80.258404 -133.526995) (xy 80.236314 -133.511036) (xy 80.217302 -133.49744) (xy 80.175419 -133.476708)
			(xy 80.130451 -133.463982) (xy 80.083914 -133.459692) (xy 80.037377 -133.463982) (xy 79.992409 -133.476708)
			(xy 79.950526 -133.49744) (xy 79.931514 -133.511036) (xy 79.909399 -133.526959) (xy 79.861574 -133.553079)
			(xy 79.810519 -133.572126) (xy 79.757273 -133.583712) (xy 79.702919 -133.587602) (xy 79.648565 -133.583718)
			(xy 79.595318 -133.572136) (xy 79.544261 -133.553095) (xy 79.496433 -133.52698) (xy 79.452809 -133.494325)
			(xy 79.414277 -133.455793) (xy 79.381621 -133.412169) (xy 79.355506 -133.364342) (xy 79.336464 -133.313285)
			(xy 79.324883 -133.260037) (xy 79.320997 -133.205683) (xy 78.597559 -133.205683) (xy 78.5899 -133.2409)
			(xy 78.570855 -133.291967) (xy 78.544735 -133.339803) (xy 78.512073 -133.383436) (xy 78.473533 -133.421975)
			(xy 78.429901 -133.454637) (xy 78.382064 -133.480756) (xy 78.330997 -133.499801) (xy 78.277739 -133.511384)
			(xy 78.223374 -133.515269) (xy 78.16901 -133.511376) (xy 78.115754 -133.499786) (xy 78.064689 -133.480735)
			(xy 78.016856 -133.454609) (xy 77.994764 -133.438646) (xy 77.975752 -133.42505) (xy 77.933869 -133.404318)
			(xy 77.888901 -133.391592) (xy 77.842364 -133.387302) (xy 77.795827 -133.391592) (xy 77.750859 -133.404318)
			(xy 77.708976 -133.42505) (xy 77.689964 -133.438646) (xy 77.667841 -133.454552) (xy 77.62002 -133.480662)
			(xy 77.56897 -133.4997) (xy 77.515731 -133.51128) (xy 77.461385 -133.515165) (xy 77.407039 -133.511275)
			(xy 77.3538 -133.499692) (xy 77.302752 -133.480649) (xy 77.254933 -133.454535) (xy 77.211318 -133.421882)
			(xy 77.172793 -133.383353) (xy 77.140144 -133.339735) (xy 77.114035 -133.291913) (xy 77.094998 -133.240863)
			(xy 77.083419 -133.187623) (xy 77.079535 -133.133277) (xy 76.716322 -133.133277) (xy 76.714428 -133.159756)
			(xy 76.702844 -133.213004) (xy 76.683799 -133.264062) (xy 76.657682 -133.311889) (xy 76.625023 -133.355513)
			(xy 76.586489 -133.394044) (xy 76.542863 -133.426699) (xy 76.495033 -133.452812) (xy 76.443974 -133.471853)
			(xy 76.390725 -133.483433) (xy 76.33637 -133.487316) (xy 76.282015 -133.483424) (xy 76.228768 -133.471836)
			(xy 76.177711 -133.452787) (xy 76.129886 -133.426666) (xy 76.107798 -133.410706) (xy 76.088786 -133.39711)
			(xy 76.046903 -133.376378) (xy 76.001935 -133.363652) (xy 75.955398 -133.359362) (xy 75.908861 -133.363652)
			(xy 75.863893 -133.376378) (xy 75.82201 -133.39711) (xy 75.802998 -133.410706) (xy 75.780912 -133.426668)
			(xy 75.733086 -133.452789) (xy 75.68203 -133.471837) (xy 75.628783 -133.483425) (xy 75.574428 -133.487317)
			(xy 75.520073 -133.483433) (xy 75.466824 -133.471853) (xy 75.415765 -133.452812) (xy 75.367936 -133.426699)
			(xy 75.32431 -133.394044) (xy 75.285775 -133.355513) (xy 75.253117 -133.311889) (xy 75.227 -133.264062)
			(xy 75.207955 -133.213004) (xy 75.196371 -133.159756) (xy 75.192483 -133.105401) (xy 74.686579 -133.105401)
			(xy 74.690543 -133.123619) (xy 74.694435 -133.177975) (xy 74.69055 -133.232331) (xy 74.67897 -133.285582)
			(xy 74.659929 -133.336642) (xy 74.633815 -133.384472) (xy 74.601159 -133.428099) (xy 74.562628 -133.466635)
			(xy 74.519004 -133.499295) (xy 74.471176 -133.525413) (xy 74.420117 -133.544459) (xy 74.366868 -133.556045)
			(xy 74.312512 -133.559935) (xy 74.258156 -133.556049) (xy 74.204906 -133.544466) (xy 74.153846 -133.525423)
			(xy 74.106017 -133.499308) (xy 74.083926 -133.48335) (xy 74.064914 -133.469754) (xy 74.023031 -133.449022)
			(xy 73.978063 -133.436296) (xy 73.931526 -133.432006) (xy 73.884989 -133.436296) (xy 73.840021 -133.449022)
			(xy 73.798138 -133.469754) (xy 73.779126 -133.48335) (xy 73.756998 -133.499256) (xy 73.709173 -133.525375)
			(xy 73.658118 -133.544422) (xy 73.604871 -133.556008) (xy 73.550518 -133.559898) (xy 73.496164 -133.556013)
			(xy 73.442916 -133.544432) (xy 73.391859 -133.52539) (xy 73.344032 -133.499275) (xy 73.300408 -133.466618)
			(xy 73.261877 -133.428086) (xy 73.229221 -133.384462) (xy 73.203107 -133.336634) (xy 73.184066 -133.285577)
			(xy 73.172486 -133.232329) (xy 73.168602 -133.177975) (xy 29.820108 -133.177975) (xy 29.820108 -135.321471)
			(xy 73.168606 -135.321471) (xy 73.172498 -135.267118) (xy 73.184086 -135.213873) (xy 73.203134 -135.162819)
			(xy 73.229255 -135.114995) (xy 73.261916 -135.071376) (xy 73.300452 -135.03285) (xy 73.34408 -135.0002)
			(xy 73.39191 -134.974092) (xy 73.442969 -134.955058) (xy 73.496218 -134.943484) (xy 73.550572 -134.939606)
			(xy 73.604924 -134.943504) (xy 73.658168 -134.955098) (xy 73.70922 -134.974152) (xy 73.757041 -135.000278)
			(xy 73.779126 -135.01624) (xy 73.798138 -135.029836) (xy 73.840021 -135.050568) (xy 73.884989 -135.063294)
			(xy 73.931526 -135.067584) (xy 73.978063 -135.063294) (xy 74.023031 -135.050568) (xy 74.064914 -135.029836)
			(xy 74.083926 -135.01624) (xy 74.105969 -135.000218) (xy 74.153795 -134.974095) (xy 74.204853 -134.955044)
			(xy 74.258102 -134.943454) (xy 74.312458 -134.939561) (xy 74.366815 -134.943442) (xy 74.420067 -134.955021)
			(xy 74.471128 -134.97406) (xy 74.518961 -135.000172) (xy 74.56259 -135.032826) (xy 74.601128 -135.071357)
			(xy 74.63379 -135.11498) (xy 74.659911 -135.162807) (xy 74.678959 -135.213865) (xy 74.686583 -135.248898)
			(xy 75.192488 -135.248898) (xy 75.196376 -135.194543) (xy 75.20796 -135.141296) (xy 75.227005 -135.090239)
			(xy 75.253122 -135.042412) (xy 75.28578 -134.99879) (xy 75.324314 -134.960259) (xy 75.367939 -134.927605)
			(xy 75.415768 -134.901491) (xy 75.466826 -134.882451) (xy 75.520075 -134.870871) (xy 75.574429 -134.866988)
			(xy 75.628783 -134.87088) (xy 75.68203 -134.882468) (xy 75.733085 -134.901516) (xy 75.78091 -134.927636)
			(xy 75.802998 -134.943596) (xy 75.82201 -134.957192) (xy 75.863893 -134.977924) (xy 75.908861 -134.99065)
			(xy 75.955398 -134.99494) (xy 76.001935 -134.99065) (xy 76.046903 -134.977924) (xy 76.088786 -134.957192)
			(xy 76.107798 -134.943596) (xy 76.129882 -134.92763) (xy 76.177708 -134.901509) (xy 76.228765 -134.88246)
			(xy 76.282013 -134.870871) (xy 76.336368 -134.866979) (xy 76.390724 -134.870862) (xy 76.443974 -134.882442)
			(xy 76.495034 -134.901483) (xy 76.542864 -134.927596) (xy 76.586491 -134.960251) (xy 76.625026 -134.998783)
			(xy 76.657685 -135.042407) (xy 76.683803 -135.090235) (xy 76.702848 -135.141293) (xy 76.714433 -135.194542)
			(xy 76.718321 -135.248898) (xy 76.716327 -135.276774) (xy 77.07954 -135.276774) (xy 77.083431 -135.222429)
			(xy 77.095016 -135.169191) (xy 77.11406 -135.118144) (xy 77.140175 -135.070327) (xy 77.172829 -135.026713)
			(xy 77.211358 -134.98819) (xy 77.254977 -134.955542) (xy 77.302799 -134.929435) (xy 77.353849 -134.910399)
			(xy 77.407089 -134.898822) (xy 77.461434 -134.89494) (xy 77.515779 -134.898832) (xy 77.569016 -134.910418)
			(xy 77.620063 -134.929463) (xy 77.66788 -134.955579) (xy 77.689964 -134.971536) (xy 77.708976 -134.985132)
			(xy 77.750859 -135.005864) (xy 77.795827 -135.01859) (xy 77.842364 -135.02288) (xy 77.888901 -135.01859)
			(xy 77.933869 -135.005864) (xy 77.975752 -134.985132) (xy 77.994764 -134.971536) (xy 78.016812 -134.955514)
			(xy 78.064642 -134.929381) (xy 78.115705 -134.910323) (xy 78.168961 -134.898726) (xy 78.223325 -134.894827)
			(xy 78.277691 -134.898705) (xy 78.330951 -134.910281) (xy 78.382021 -134.929319) (xy 78.429862 -134.955433)
			(xy 78.473499 -134.988089) (xy 78.512044 -135.026624) (xy 78.544713 -135.070253) (xy 78.570839 -135.118086)
			(xy 78.589891 -135.169152) (xy 78.601481 -135.222409) (xy 78.605373 -135.276774) (xy 78.601489 -135.331139)
			(xy 78.597565 -135.34918) (xy 79.321002 -135.34918) (xy 79.324893 -135.294827) (xy 79.336479 -135.241581)
			(xy 79.355526 -135.190526) (xy 79.381645 -135.142702) (xy 79.414305 -135.099082) (xy 79.45284 -135.060555)
			(xy 79.496467 -135.027904) (xy 79.544296 -135.001794) (xy 79.595355 -134.982758) (xy 79.648603 -134.971182)
			(xy 79.702956 -134.967302) (xy 79.757309 -134.971198) (xy 79.810553 -134.98279) (xy 79.861606 -135.001841)
			(xy 79.909428 -135.027965) (xy 79.931514 -135.043926) (xy 79.950526 -135.057522) (xy 79.992409 -135.078254)
			(xy 80.037377 -135.09098) (xy 80.083914 -135.09527) (xy 80.130451 -135.09098) (xy 80.175419 -135.078254)
			(xy 80.217302 -135.057522) (xy 80.236314 -135.043926) (xy 80.25837 -135.027921) (xy 80.306197 -135.001798)
			(xy 80.357254 -134.982748) (xy 80.410503 -134.971158) (xy 80.46486 -134.967265) (xy 80.519217 -134.971147)
			(xy 80.572468 -134.982725) (xy 80.62353 -135.001765) (xy 80.671362 -135.027878) (xy 80.714991 -135.060532)
			(xy 80.753528 -135.099063) (xy 80.786189 -135.142687) (xy 80.81231 -135.190515) (xy 80.831358 -135.241573)
			(xy 80.842945 -135.294823) (xy 80.845525 -135.330872) (xy 81.441417 -135.330872) (xy 81.445308 -135.276522)
			(xy 81.456895 -135.223279) (xy 81.475942 -135.172227) (xy 81.50206 -135.124405) (xy 81.534719 -135.080788)
			(xy 81.573253 -135.042263) (xy 81.616878 -135.009614) (xy 81.664706 -134.983506) (xy 81.715762 -134.964471)
			(xy 81.769008 -134.952896) (xy 81.823359 -134.949017) (xy 81.877709 -134.952913) (xy 81.930951 -134.964504)
			(xy 81.982002 -134.983555) (xy 82.029821 -135.009677) (xy 82.051906 -135.025638) (xy 82.070918 -135.039234)
			(xy 82.112801 -135.059966) (xy 82.157769 -135.072692) (xy 82.204306 -135.076982) (xy 82.250843 -135.072692)
			(xy 82.295811 -135.059966) (xy 82.337694 -135.039234) (xy 82.356706 -135.025638) (xy 82.378751 -135.009617)
			(xy 82.426579 -134.983491) (xy 82.477638 -134.964438) (xy 82.530889 -134.952846) (xy 82.585248 -134.94895)
			(xy 82.639608 -134.952831) (xy 82.692862 -134.964408) (xy 82.743926 -134.983447) (xy 82.791761 -135.00956)
			(xy 82.835393 -135.042215) (xy 82.873933 -135.080747) (xy 82.906597 -135.124372) (xy 82.932719 -135.172201)
			(xy 82.951769 -135.223262) (xy 82.963358 -135.276513) (xy 82.96725 -135.330872) (xy 82.963366 -135.385232)
			(xy 82.951785 -135.438485) (xy 82.932742 -135.489549) (xy 82.906627 -135.537382) (xy 82.873969 -135.581011)
			(xy 82.835435 -135.619549) (xy 82.791808 -135.65221) (xy 82.743976 -135.67833) (xy 82.692915 -135.697376)
			(xy 82.639662 -135.708961) (xy 82.585303 -135.71285) (xy 82.530944 -135.708962) (xy 82.477691 -135.697378)
			(xy 82.426629 -135.678332) (xy 82.378797 -135.652213) (xy 82.356706 -135.636254) (xy 82.337694 -135.622658)
			(xy 82.295811 -135.601926) (xy 82.250843 -135.5892) (xy 82.204306 -135.58491) (xy 82.157769 -135.5892)
			(xy 82.112801 -135.601926) (xy 82.070918 -135.622658) (xy 82.051906 -135.636254) (xy 82.029775 -135.652152)
			(xy 81.981951 -135.678268) (xy 81.930898 -135.697312) (xy 81.877654 -135.708895) (xy 81.823304 -135.712783)
			(xy 81.768953 -135.708896) (xy 81.715709 -135.697314) (xy 81.664656 -135.678271) (xy 81.616832 -135.652157)
			(xy 81.573212 -135.619501) (xy 81.534683 -135.58097) (xy 81.502031 -135.537348) (xy 81.475919 -135.489523)
			(xy 81.456879 -135.438468) (xy 81.4453 -135.385223) (xy 81.441417 -135.330872) (xy 80.845525 -135.330872)
			(xy 80.846835 -135.34918) (xy 80.84295 -135.403537) (xy 80.831369 -135.456788) (xy 80.812327 -135.507848)
			(xy 80.786212 -135.555679) (xy 80.753555 -135.599306) (xy 80.715022 -135.637841) (xy 80.671396 -135.6705)
			(xy 80.623567 -135.696618) (xy 80.572507 -135.715663) (xy 80.519257 -135.727247) (xy 80.4649 -135.731135)
			(xy 80.410543 -135.727248) (xy 80.357293 -135.715663) (xy 80.306234 -135.696618) (xy 80.258404 -135.670501)
			(xy 80.236314 -135.654542) (xy 80.217302 -135.640946) (xy 80.175419 -135.620214) (xy 80.130451 -135.607488)
			(xy 80.083914 -135.603198) (xy 80.037377 -135.607488) (xy 79.992409 -135.620214) (xy 79.950526 -135.640946)
			(xy 79.931514 -135.654542) (xy 79.909394 -135.670457) (xy 79.861569 -135.696576) (xy 79.810514 -135.715622)
			(xy 79.757268 -135.727208) (xy 79.702916 -135.731098) (xy 79.648562 -135.727212) (xy 79.595316 -135.715631)
			(xy 79.544259 -135.696589) (xy 79.496433 -135.670474) (xy 79.45281 -135.637819) (xy 79.414278 -135.599287)
			(xy 79.381623 -135.555663) (xy 79.355509 -135.507836) (xy 79.336468 -135.45678) (xy 79.324887 -135.403533)
			(xy 79.321002 -135.34918) (xy 78.597565 -135.34918) (xy 78.589906 -135.384397) (xy 78.570861 -135.435465)
			(xy 78.544741 -135.483303) (xy 78.512079 -135.526936) (xy 78.473539 -135.565476) (xy 78.429907 -135.598139)
			(xy 78.382069 -135.624259) (xy 78.331002 -135.643304) (xy 78.277743 -135.654888) (xy 78.223378 -135.658773)
			(xy 78.169013 -135.654882) (xy 78.115756 -135.643292) (xy 78.06469 -135.62424) (xy 78.016856 -135.598115)
			(xy 77.994764 -135.582152) (xy 77.975752 -135.568556) (xy 77.933869 -135.547824) (xy 77.888901 -135.535098)
			(xy 77.842364 -135.530808) (xy 77.795827 -135.535098) (xy 77.750859 -135.547824) (xy 77.708976 -135.568556)
			(xy 77.689964 -135.582152) (xy 77.667835 -135.59805) (xy 77.620015 -135.624159) (xy 77.568966 -135.643197)
			(xy 77.515726 -135.654776) (xy 77.461381 -135.65866) (xy 77.407036 -135.65477) (xy 77.353798 -135.643186)
			(xy 77.302751 -135.624143) (xy 77.254933 -135.598029) (xy 77.211318 -135.565376) (xy 77.172795 -135.526848)
			(xy 77.140146 -135.483229) (xy 77.114038 -135.435408) (xy 77.095001 -135.384358) (xy 77.083423 -135.331119)
			(xy 77.07954 -135.276774) (xy 76.716327 -135.276774) (xy 76.714433 -135.303253) (xy 76.70285 -135.356502)
			(xy 76.683805 -135.407561) (xy 76.657688 -135.455389) (xy 76.625029 -135.499013) (xy 76.586495 -135.537545)
			(xy 76.542868 -135.570201) (xy 76.495039 -135.596315) (xy 76.443979 -135.615356) (xy 76.390729 -135.626937)
			(xy 76.336373 -135.630821) (xy 76.282018 -135.626929) (xy 76.22877 -135.615341) (xy 76.177713 -135.596293)
			(xy 76.129887 -135.570172) (xy 76.107798 -135.554212) (xy 76.088786 -135.540616) (xy 76.046903 -135.519884)
			(xy 76.001935 -135.507158) (xy 75.955398 -135.502868) (xy 75.908861 -135.507158) (xy 75.863893 -135.519884)
			(xy 75.82201 -135.540616) (xy 75.802998 -135.554212) (xy 75.780906 -135.570166) (xy 75.733081 -135.596286)
			(xy 75.682025 -135.615334) (xy 75.628778 -135.626921) (xy 75.574425 -135.630812) (xy 75.52007 -135.626928)
			(xy 75.466822 -135.615348) (xy 75.415764 -135.596307) (xy 75.367935 -135.570193) (xy 75.32431 -135.537538)
			(xy 75.285777 -135.499007) (xy 75.253119 -135.455383) (xy 75.227003 -135.407557) (xy 75.207959 -135.356499)
			(xy 75.196375 -135.303252) (xy 75.192488 -135.248898) (xy 74.686583 -135.248898) (xy 74.690548 -135.267115)
			(xy 74.694439 -135.321471) (xy 74.690556 -135.375828) (xy 74.678976 -135.429079) (xy 74.659935 -135.48014)
			(xy 74.633821 -135.527972) (xy 74.601165 -135.5716) (xy 74.562633 -135.610136) (xy 74.519009 -135.642797)
			(xy 74.471181 -135.668916) (xy 74.420122 -135.687963) (xy 74.366872 -135.699549) (xy 74.312516 -135.703439)
			(xy 74.258159 -135.699554) (xy 74.204908 -135.687972) (xy 74.153848 -135.668929) (xy 74.106017 -135.642814)
			(xy 74.083926 -135.626856) (xy 74.064914 -135.61326) (xy 74.023031 -135.592528) (xy 73.978063 -135.579802)
			(xy 73.931526 -135.575512) (xy 73.884989 -135.579802) (xy 73.840021 -135.592528) (xy 73.798138 -135.61326)
			(xy 73.779126 -135.626856) (xy 73.756992 -135.642753) (xy 73.709168 -135.668872) (xy 73.658113 -135.687918)
			(xy 73.604867 -135.699504) (xy 73.550514 -135.703394) (xy 73.496161 -135.699508) (xy 73.442914 -135.687926)
			(xy 73.391858 -135.668884) (xy 73.344031 -135.642769) (xy 73.300409 -135.610112) (xy 73.261878 -135.57158)
			(xy 73.229223 -135.527956) (xy 73.20311 -135.480129) (xy 73.18407 -135.429072) (xy 73.17249 -135.375824)
			(xy 73.168606 -135.321471) (xy 29.820108 -135.321471) (xy 29.820108 -140.254228) (xy 39.818818 -140.254228)
			(xy 39.819523 -140.195605) (xy 39.828091 -140.078667) (xy 39.844787 -139.962611) (xy 39.86953 -139.848001)
			(xy 39.902199 -139.735393) (xy 39.942635 -139.625335) (xy 39.990642 -139.518363) (xy 40.045986 -139.414996)
			(xy 40.108399 -139.315737) (xy 40.177577 -139.221068) (xy 40.253183 -139.13145) (xy 40.334851 -139.047318)
			(xy 40.422182 -138.969081) (xy 40.514753 -138.89712) (xy 40.612113 -138.831784) (xy 40.713789 -138.773392)
			(xy 40.819288 -138.722226) (xy 40.928095 -138.678537) (xy 41.039682 -138.642535) (xy 41.153506 -138.614397)
			(xy 41.269014 -138.594259) (xy 41.385645 -138.582218) (xy 41.502832 -138.578334) (xy 41.620004 -138.582625)
			(xy 41.736593 -138.595071) (xy 41.85203 -138.615611) (xy 41.965756 -138.644144) (xy 42.077217 -138.680533)
			(xy 42.185872 -138.724601) (xy 42.291192 -138.776133) (xy 42.392665 -138.834878) (xy 42.489797 -138.900552)
			(xy 42.501941 -138.91006) (xy 63.647831 -138.91006) (xy 63.651866 -138.834356) (xy 63.663925 -138.759511)
			(xy 63.683871 -138.68637) (xy 63.711478 -138.615765) (xy 63.746434 -138.548494) (xy 63.788342 -138.485319)
			(xy 63.836728 -138.426957) (xy 63.891044 -138.374069) (xy 63.950673 -138.327254) (xy 64.014941 -138.287042)
			(xy 64.083118 -138.25389) (xy 64.154434 -138.228172) (xy 64.228079 -138.21018) (xy 64.303219 -138.200118)
			(xy 64.379003 -138.198099) (xy 64.454573 -138.204148) (xy 64.529071 -138.218195) (xy 64.601654 -138.240081)
			(xy 64.6715 -138.269558) (xy 64.737817 -138.306293) (xy 64.799853 -138.349868) (xy 64.856906 -138.39979)
			(xy 64.90833 -138.455494) (xy 64.953541 -138.516349) (xy 64.992028 -138.581664) (xy 65.023354 -138.6507)
			(xy 65.047164 -138.722675) (xy 65.063189 -138.796773) (xy 65.071248 -138.872154) (xy 65.071752 -138.91006)
			(xy 66.187831 -138.91006) (xy 66.191866 -138.834356) (xy 66.203925 -138.759511) (xy 66.223871 -138.68637)
			(xy 66.251478 -138.615765) (xy 66.286434 -138.548494) (xy 66.328342 -138.485319) (xy 66.376728 -138.426957)
			(xy 66.431044 -138.374069) (xy 66.490673 -138.327254) (xy 66.554941 -138.287042) (xy 66.623118 -138.25389)
			(xy 66.694434 -138.228172) (xy 66.768079 -138.21018) (xy 66.843219 -138.200118) (xy 66.919003 -138.198099)
			(xy 66.994573 -138.204148) (xy 67.069071 -138.218195) (xy 67.141654 -138.240081) (xy 67.2115 -138.269558)
			(xy 67.277817 -138.306293) (xy 67.339853 -138.349868) (xy 67.396906 -138.39979) (xy 67.44833 -138.455494)
			(xy 67.493541 -138.516349) (xy 67.532028 -138.581664) (xy 67.563354 -138.6507) (xy 67.587164 -138.722675)
			(xy 67.603189 -138.796773) (xy 67.611248 -138.872154) (xy 67.611752 -138.91006) (xy 68.727831 -138.91006)
			(xy 68.731866 -138.834356) (xy 68.743925 -138.759511) (xy 68.763871 -138.68637) (xy 68.791478 -138.615765)
			(xy 68.826434 -138.548494) (xy 68.868342 -138.485319) (xy 68.916728 -138.426957) (xy 68.971044 -138.374069)
			(xy 69.030673 -138.327254) (xy 69.094941 -138.287042) (xy 69.163118 -138.25389) (xy 69.234434 -138.228172)
			(xy 69.308079 -138.21018) (xy 69.383219 -138.200118) (xy 69.459003 -138.198099) (xy 69.534573 -138.204148)
			(xy 69.609071 -138.218195) (xy 69.681654 -138.240081) (xy 69.7515 -138.269558) (xy 69.817817 -138.306293)
			(xy 69.879853 -138.349868) (xy 69.936906 -138.39979) (xy 69.98833 -138.455494) (xy 70.033541 -138.516349)
			(xy 70.072028 -138.581664) (xy 70.103354 -138.6507) (xy 70.127164 -138.722675) (xy 70.143189 -138.796773)
			(xy 70.151248 -138.872154) (xy 70.151752 -138.91006) (xy 71.267831 -138.91006) (xy 71.271866 -138.834356)
			(xy 71.283925 -138.759511) (xy 71.303871 -138.68637) (xy 71.331478 -138.615765) (xy 71.366434 -138.548494)
			(xy 71.408342 -138.485319) (xy 71.456728 -138.426957) (xy 71.511044 -138.374069) (xy 71.570673 -138.327254)
			(xy 71.634941 -138.287042) (xy 71.703118 -138.25389) (xy 71.774434 -138.228172) (xy 71.848079 -138.21018)
			(xy 71.923219 -138.200118) (xy 71.999003 -138.198099) (xy 72.074573 -138.204148) (xy 72.149071 -138.218195)
			(xy 72.221654 -138.240081) (xy 72.2915 -138.269558) (xy 72.357817 -138.306293) (xy 72.419853 -138.349868)
			(xy 72.476906 -138.39979) (xy 72.52833 -138.455494) (xy 72.573541 -138.516349) (xy 72.612028 -138.581664)
			(xy 72.643354 -138.6507) (xy 72.667164 -138.722675) (xy 72.683189 -138.796773) (xy 72.691248 -138.872154)
			(xy 72.691752 -138.91006) (xy 73.807831 -138.91006) (xy 73.811866 -138.834356) (xy 73.823925 -138.759511)
			(xy 73.843871 -138.68637) (xy 73.871478 -138.615765) (xy 73.906434 -138.548494) (xy 73.948342 -138.485319)
			(xy 73.996728 -138.426957) (xy 74.051044 -138.374069) (xy 74.110673 -138.327254) (xy 74.174941 -138.287042)
			(xy 74.243118 -138.25389) (xy 74.314434 -138.228172) (xy 74.388079 -138.21018) (xy 74.463219 -138.200118)
			(xy 74.539003 -138.198099) (xy 74.614573 -138.204148) (xy 74.689071 -138.218195) (xy 74.761654 -138.240081)
			(xy 74.8315 -138.269558) (xy 74.897817 -138.306293) (xy 74.959853 -138.349868) (xy 75.016906 -138.39979)
			(xy 75.06833 -138.455494) (xy 75.113541 -138.516349) (xy 75.152028 -138.581664) (xy 75.183354 -138.6507)
			(xy 75.207164 -138.722675) (xy 75.223189 -138.796773) (xy 75.231248 -138.872154) (xy 75.231752 -138.91006)
			(xy 76.347831 -138.91006) (xy 76.351866 -138.834356) (xy 76.363925 -138.759511) (xy 76.383871 -138.68637)
			(xy 76.411478 -138.615765) (xy 76.446434 -138.548494) (xy 76.488342 -138.485319) (xy 76.536728 -138.426957)
			(xy 76.591044 -138.374069) (xy 76.650673 -138.327254) (xy 76.714941 -138.287042) (xy 76.783118 -138.25389)
			(xy 76.854434 -138.228172) (xy 76.928079 -138.21018) (xy 77.003219 -138.200118) (xy 77.079003 -138.198099)
			(xy 77.154573 -138.204148) (xy 77.229071 -138.218195) (xy 77.301654 -138.240081) (xy 77.3715 -138.269558)
			(xy 77.437817 -138.306293) (xy 77.499853 -138.349868) (xy 77.556906 -138.39979) (xy 77.60833 -138.455494)
			(xy 77.653541 -138.516349) (xy 77.692028 -138.581664) (xy 77.723354 -138.6507) (xy 77.747164 -138.722675)
			(xy 77.763189 -138.796773) (xy 77.771248 -138.872154) (xy 77.771752 -138.91006) (xy 78.887831 -138.91006)
			(xy 78.891866 -138.834356) (xy 78.903925 -138.759511) (xy 78.923871 -138.68637) (xy 78.951478 -138.615765)
			(xy 78.986434 -138.548494) (xy 79.028342 -138.485319) (xy 79.076728 -138.426957) (xy 79.131044 -138.374069)
			(xy 79.190673 -138.327254) (xy 79.254941 -138.287042) (xy 79.323118 -138.25389) (xy 79.394434 -138.228172)
			(xy 79.468079 -138.21018) (xy 79.543219 -138.200118) (xy 79.619003 -138.198099) (xy 79.694573 -138.204148)
			(xy 79.769071 -138.218195) (xy 79.841654 -138.240081) (xy 79.9115 -138.269558) (xy 79.977817 -138.306293)
			(xy 80.039853 -138.349868) (xy 80.096906 -138.39979) (xy 80.14833 -138.455494) (xy 80.193541 -138.516349)
			(xy 80.232028 -138.581664) (xy 80.263354 -138.6507) (xy 80.287164 -138.722675) (xy 80.303189 -138.796773)
			(xy 80.311248 -138.872154) (xy 80.311752 -138.91006) (xy 81.427831 -138.91006) (xy 81.431866 -138.834356)
			(xy 81.443925 -138.759511) (xy 81.463871 -138.68637) (xy 81.491478 -138.615765) (xy 81.526434 -138.548494)
			(xy 81.568342 -138.485319) (xy 81.616728 -138.426957) (xy 81.671044 -138.374069) (xy 81.730673 -138.327254)
			(xy 81.794941 -138.287042) (xy 81.863118 -138.25389) (xy 81.934434 -138.228172) (xy 82.008079 -138.21018)
			(xy 82.083219 -138.200118) (xy 82.159003 -138.198099) (xy 82.234573 -138.204148) (xy 82.309071 -138.218195)
			(xy 82.381654 -138.240081) (xy 82.4515 -138.269558) (xy 82.517817 -138.306293) (xy 82.579853 -138.349868)
			(xy 82.585798 -138.35507) (xy 86.197951 -138.35507) (xy 86.201986 -138.279366) (xy 86.214045 -138.204521)
			(xy 86.233991 -138.13138) (xy 86.261598 -138.060775) (xy 86.296554 -137.993504) (xy 86.338462 -137.930329)
			(xy 86.386848 -137.871967) (xy 86.441164 -137.819079) (xy 86.500793 -137.772264) (xy 86.565061 -137.732052)
			(xy 86.633238 -137.6989) (xy 86.704554 -137.673182) (xy 86.778199 -137.65519) (xy 86.853339 -137.645128)
			(xy 86.929123 -137.643109) (xy 87.004693 -137.649158) (xy 87.079191 -137.663205) (xy 87.151774 -137.685091)
			(xy 87.22162 -137.714568) (xy 87.287937 -137.751303) (xy 87.349973 -137.794878) (xy 87.407026 -137.8448)
			(xy 87.45845 -137.900504) (xy 87.503661 -137.961359) (xy 87.542148 -138.026674) (xy 87.573474 -138.09571)
			(xy 87.597284 -138.167685) (xy 87.613309 -138.241783) (xy 87.621368 -138.317164) (xy 87.621872 -138.35507)
			(xy 87.621368 -138.392976) (xy 87.613309 -138.468357) (xy 87.597284 -138.542455) (xy 87.573474 -138.61443)
			(xy 87.542148 -138.683466) (xy 87.503661 -138.748781) (xy 87.45845 -138.809636) (xy 87.407026 -138.86534)
			(xy 87.349973 -138.915262) (xy 87.287937 -138.958837) (xy 87.22162 -138.995572) (xy 87.151774 -139.025049)
			(xy 87.079191 -139.046935) (xy 87.004693 -139.060982) (xy 86.929123 -139.067031) (xy 86.853339 -139.065012)
			(xy 86.778199 -139.05495) (xy 86.704554 -139.036958) (xy 86.633238 -139.01124) (xy 86.565061 -138.978088)
			(xy 86.500793 -138.937876) (xy 86.441164 -138.891061) (xy 86.386848 -138.838173) (xy 86.338462 -138.779811)
			(xy 86.296554 -138.716636) (xy 86.261598 -138.649365) (xy 86.233991 -138.57876) (xy 86.214045 -138.505619)
			(xy 86.201986 -138.430774) (xy 86.197951 -138.35507) (xy 82.585798 -138.35507) (xy 82.636906 -138.39979)
			(xy 82.68833 -138.455494) (xy 82.733541 -138.516349) (xy 82.772028 -138.581664) (xy 82.803354 -138.6507)
			(xy 82.827164 -138.722675) (xy 82.843189 -138.796773) (xy 82.851248 -138.872154) (xy 82.851752 -138.91006)
			(xy 82.851248 -138.947966) (xy 82.843189 -139.023347) (xy 82.827164 -139.097445) (xy 82.803354 -139.16942)
			(xy 82.772028 -139.238456) (xy 82.733541 -139.303771) (xy 82.68833 -139.364626) (xy 82.636906 -139.42033)
			(xy 82.579853 -139.470252) (xy 82.517817 -139.513827) (xy 82.4515 -139.550562) (xy 82.381654 -139.580039)
			(xy 82.309071 -139.601925) (xy 82.234573 -139.615972) (xy 82.159003 -139.622021) (xy 82.083219 -139.620002)
			(xy 82.008079 -139.60994) (xy 81.934434 -139.591948) (xy 81.863118 -139.56623) (xy 81.794941 -139.533078)
			(xy 81.730673 -139.492866) (xy 81.671044 -139.446051) (xy 81.616728 -139.393163) (xy 81.568342 -139.334801)
			(xy 81.526434 -139.271626) (xy 81.491478 -139.204355) (xy 81.463871 -139.13375) (xy 81.443925 -139.060609)
			(xy 81.431866 -138.985764) (xy 81.427831 -138.91006) (xy 80.311752 -138.91006) (xy 80.311248 -138.947966)
			(xy 80.303189 -139.023347) (xy 80.287164 -139.097445) (xy 80.263354 -139.16942) (xy 80.232028 -139.238456)
			(xy 80.193541 -139.303771) (xy 80.14833 -139.364626) (xy 80.096906 -139.42033) (xy 80.039853 -139.470252)
			(xy 79.977817 -139.513827) (xy 79.9115 -139.550562) (xy 79.841654 -139.580039) (xy 79.769071 -139.601925)
			(xy 79.694573 -139.615972) (xy 79.619003 -139.622021) (xy 79.543219 -139.620002) (xy 79.468079 -139.60994)
			(xy 79.394434 -139.591948) (xy 79.323118 -139.56623) (xy 79.254941 -139.533078) (xy 79.190673 -139.492866)
			(xy 79.131044 -139.446051) (xy 79.076728 -139.393163) (xy 79.028342 -139.334801) (xy 78.986434 -139.271626)
			(xy 78.951478 -139.204355) (xy 78.923871 -139.13375) (xy 78.903925 -139.060609) (xy 78.891866 -138.985764)
			(xy 78.887831 -138.91006) (xy 77.771752 -138.91006) (xy 77.771248 -138.947966) (xy 77.763189 -139.023347)
			(xy 77.747164 -139.097445) (xy 77.723354 -139.16942) (xy 77.692028 -139.238456) (xy 77.653541 -139.303771)
			(xy 77.60833 -139.364626) (xy 77.556906 -139.42033) (xy 77.499853 -139.470252) (xy 77.437817 -139.513827)
			(xy 77.3715 -139.550562) (xy 77.301654 -139.580039) (xy 77.229071 -139.601925) (xy 77.154573 -139.615972)
			(xy 77.079003 -139.622021) (xy 77.003219 -139.620002) (xy 76.928079 -139.60994) (xy 76.854434 -139.591948)
			(xy 76.783118 -139.56623) (xy 76.714941 -139.533078) (xy 76.650673 -139.492866) (xy 76.591044 -139.446051)
			(xy 76.536728 -139.393163) (xy 76.488342 -139.334801) (xy 76.446434 -139.271626) (xy 76.411478 -139.204355)
			(xy 76.383871 -139.13375) (xy 76.363925 -139.060609) (xy 76.351866 -138.985764) (xy 76.347831 -138.91006)
			(xy 75.231752 -138.91006) (xy 75.231248 -138.947966) (xy 75.223189 -139.023347) (xy 75.207164 -139.097445)
			(xy 75.183354 -139.16942) (xy 75.152028 -139.238456) (xy 75.113541 -139.303771) (xy 75.06833 -139.364626)
			(xy 75.016906 -139.42033) (xy 74.959853 -139.470252) (xy 74.897817 -139.513827) (xy 74.8315 -139.550562)
			(xy 74.761654 -139.580039) (xy 74.689071 -139.601925) (xy 74.614573 -139.615972) (xy 74.539003 -139.622021)
			(xy 74.463219 -139.620002) (xy 74.388079 -139.60994) (xy 74.314434 -139.591948) (xy 74.243118 -139.56623)
			(xy 74.174941 -139.533078) (xy 74.110673 -139.492866) (xy 74.051044 -139.446051) (xy 73.996728 -139.393163)
			(xy 73.948342 -139.334801) (xy 73.906434 -139.271626) (xy 73.871478 -139.204355) (xy 73.843871 -139.13375)
			(xy 73.823925 -139.060609) (xy 73.811866 -138.985764) (xy 73.807831 -138.91006) (xy 72.691752 -138.91006)
			(xy 72.691248 -138.947966) (xy 72.683189 -139.023347) (xy 72.667164 -139.097445) (xy 72.643354 -139.16942)
			(xy 72.612028 -139.238456) (xy 72.573541 -139.303771) (xy 72.52833 -139.364626) (xy 72.476906 -139.42033)
			(xy 72.419853 -139.470252) (xy 72.357817 -139.513827) (xy 72.2915 -139.550562) (xy 72.221654 -139.580039)
			(xy 72.149071 -139.601925) (xy 72.074573 -139.615972) (xy 71.999003 -139.622021) (xy 71.923219 -139.620002)
			(xy 71.848079 -139.60994) (xy 71.774434 -139.591948) (xy 71.703118 -139.56623) (xy 71.634941 -139.533078)
			(xy 71.570673 -139.492866) (xy 71.511044 -139.446051) (xy 71.456728 -139.393163) (xy 71.408342 -139.334801)
			(xy 71.366434 -139.271626) (xy 71.331478 -139.204355) (xy 71.303871 -139.13375) (xy 71.283925 -139.060609)
			(xy 71.271866 -138.985764) (xy 71.267831 -138.91006) (xy 70.151752 -138.91006) (xy 70.151248 -138.947966)
			(xy 70.143189 -139.023347) (xy 70.127164 -139.097445) (xy 70.103354 -139.16942) (xy 70.072028 -139.238456)
			(xy 70.033541 -139.303771) (xy 69.98833 -139.364626) (xy 69.936906 -139.42033) (xy 69.879853 -139.470252)
			(xy 69.817817 -139.513827) (xy 69.7515 -139.550562) (xy 69.681654 -139.580039) (xy 69.609071 -139.601925)
			(xy 69.534573 -139.615972) (xy 69.459003 -139.622021) (xy 69.383219 -139.620002) (xy 69.308079 -139.60994)
			(xy 69.234434 -139.591948) (xy 69.163118 -139.56623) (xy 69.094941 -139.533078) (xy 69.030673 -139.492866)
			(xy 68.971044 -139.446051) (xy 68.916728 -139.393163) (xy 68.868342 -139.334801) (xy 68.826434 -139.271626)
			(xy 68.791478 -139.204355) (xy 68.763871 -139.13375) (xy 68.743925 -139.060609) (xy 68.731866 -138.985764)
			(xy 68.727831 -138.91006) (xy 67.611752 -138.91006) (xy 67.611248 -138.947966) (xy 67.603189 -139.023347)
			(xy 67.587164 -139.097445) (xy 67.563354 -139.16942) (xy 67.532028 -139.238456) (xy 67.493541 -139.303771)
			(xy 67.44833 -139.364626) (xy 67.396906 -139.42033) (xy 67.339853 -139.470252) (xy 67.277817 -139.513827)
			(xy 67.2115 -139.550562) (xy 67.141654 -139.580039) (xy 67.069071 -139.601925) (xy 66.994573 -139.615972)
			(xy 66.919003 -139.622021) (xy 66.843219 -139.620002) (xy 66.768079 -139.60994) (xy 66.694434 -139.591948)
			(xy 66.623118 -139.56623) (xy 66.554941 -139.533078) (xy 66.490673 -139.492866) (xy 66.431044 -139.446051)
			(xy 66.376728 -139.393163) (xy 66.328342 -139.334801) (xy 66.286434 -139.271626) (xy 66.251478 -139.204355)
			(xy 66.223871 -139.13375) (xy 66.203925 -139.060609) (xy 66.191866 -138.985764) (xy 66.187831 -138.91006)
			(xy 65.071752 -138.91006) (xy 65.071248 -138.947966) (xy 65.063189 -139.023347) (xy 65.047164 -139.097445)
			(xy 65.023354 -139.16942) (xy 64.992028 -139.238456) (xy 64.953541 -139.303771) (xy 64.90833 -139.364626)
			(xy 64.856906 -139.42033) (xy 64.799853 -139.470252) (xy 64.737817 -139.513827) (xy 64.6715 -139.550562)
			(xy 64.601654 -139.580039) (xy 64.529071 -139.601925) (xy 64.454573 -139.615972) (xy 64.379003 -139.622021)
			(xy 64.303219 -139.620002) (xy 64.228079 -139.60994) (xy 64.154434 -139.591948) (xy 64.083118 -139.56623)
			(xy 64.014941 -139.533078) (xy 63.950673 -139.492866) (xy 63.891044 -139.446051) (xy 63.836728 -139.393163)
			(xy 63.788342 -139.334801) (xy 63.746434 -139.271626) (xy 63.711478 -139.204355) (xy 63.683871 -139.13375)
			(xy 63.663925 -139.060609) (xy 63.651866 -138.985764) (xy 63.647831 -138.91006) (xy 42.501941 -138.91006)
			(xy 42.582117 -138.972834) (xy 42.669176 -139.051374) (xy 42.750551 -139.135789) (xy 42.825845 -139.225669)
			(xy 42.894694 -139.320578) (xy 42.956761 -139.420054) (xy 43.011746 -139.523612) (xy 43.056855 -139.62507)
			(xy 84.927951 -139.62507) (xy 84.931986 -139.549366) (xy 84.944045 -139.474521) (xy 84.963991 -139.40138)
			(xy 84.991598 -139.330775) (xy 85.026554 -139.263504) (xy 85.068462 -139.200329) (xy 85.116848 -139.141967)
			(xy 85.171164 -139.089079) (xy 85.230793 -139.042264) (xy 85.295061 -139.002052) (xy 85.363238 -138.9689)
			(xy 85.434554 -138.943182) (xy 85.508199 -138.92519) (xy 85.583339 -138.915128) (xy 85.659123 -138.913109)
			(xy 85.734693 -138.919158) (xy 85.809191 -138.933205) (xy 85.881774 -138.955091) (xy 85.95162 -138.984568)
			(xy 86.017937 -139.021303) (xy 86.079973 -139.064878) (xy 86.137026 -139.1148) (xy 86.18845 -139.170504)
			(xy 86.233661 -139.231359) (xy 86.272148 -139.296674) (xy 86.303474 -139.36571) (xy 86.327284 -139.437685)
			(xy 86.343309 -139.511783) (xy 86.351368 -139.587164) (xy 86.351872 -139.62507) (xy 86.351368 -139.662976)
			(xy 86.343309 -139.738357) (xy 86.327284 -139.812455) (xy 86.303474 -139.88443) (xy 86.272148 -139.953466)
			(xy 86.233661 -140.018781) (xy 86.18845 -140.079636) (xy 86.137026 -140.13534) (xy 86.079973 -140.185262)
			(xy 86.017937 -140.228837) (xy 85.95162 -140.265572) (xy 85.881774 -140.295049) (xy 85.809191 -140.316935)
			(xy 85.734693 -140.330982) (xy 85.659123 -140.337031) (xy 85.583339 -140.335012) (xy 85.508199 -140.32495)
			(xy 85.434554 -140.306958) (xy 85.363238 -140.28124) (xy 85.295061 -140.248088) (xy 85.230793 -140.207876)
			(xy 85.171164 -140.161061) (xy 85.116848 -140.108173) (xy 85.068462 -140.049811) (xy 85.026554 -139.986636)
			(xy 84.991598 -139.919365) (xy 84.963991 -139.84876) (xy 84.944045 -139.775619) (xy 84.931986 -139.700774)
			(xy 84.927951 -139.62507) (xy 43.056855 -139.62507) (xy 43.059381 -139.630751) (xy 43.099434 -139.740948)
			(xy 43.131712 -139.853669) (xy 43.156056 -139.968365) (xy 43.172348 -140.084478) (xy 43.18051 -140.201445)
			(xy 43.181016 -140.26007) (xy 43.180861 -140.290833) (xy 43.178574 -140.352316) (xy 43.176444 -140.383006)
			(xy 43.175682 -140.392404) (xy 43.170622 -140.450806) (xy 43.153396 -140.566771) (xy 43.12813 -140.681253)
			(xy 43.094949 -140.793697) (xy 43.054014 -140.903555) (xy 43.005523 -141.010294) (xy 42.949712 -141.113395)
			(xy 42.886853 -141.212356) (xy 42.817252 -141.306696) (xy 42.741246 -141.395958) (xy 42.659204 -141.479706)
			(xy 42.571527 -141.557535) (xy 42.503292 -141.61008) (xy 63.647831 -141.61008) (xy 63.651866 -141.534376)
			(xy 63.663925 -141.459531) (xy 63.683871 -141.38639) (xy 63.711478 -141.315785) (xy 63.746434 -141.248514)
			(xy 63.788342 -141.185339) (xy 63.836728 -141.126977) (xy 63.891044 -141.074089) (xy 63.950673 -141.027274)
			(xy 64.014941 -140.987062) (xy 64.083118 -140.95391) (xy 64.154434 -140.928192) (xy 64.228079 -140.9102)
			(xy 64.303219 -140.900138) (xy 64.379003 -140.898119) (xy 64.454573 -140.904168) (xy 64.529071 -140.918215)
			(xy 64.601654 -140.940101) (xy 64.6715 -140.969578) (xy 64.737817 -141.006313) (xy 64.799853 -141.049888)
			(xy 64.856906 -141.09981) (xy 64.90833 -141.155514) (xy 64.953541 -141.216369) (xy 64.992028 -141.281684)
			(xy 65.023354 -141.35072) (xy 65.047164 -141.422695) (xy 65.063189 -141.496793) (xy 65.071248 -141.572174)
			(xy 65.071752 -141.61008) (xy 66.187831 -141.61008) (xy 66.191866 -141.534376) (xy 66.203925 -141.459531)
			(xy 66.223871 -141.38639) (xy 66.251478 -141.315785) (xy 66.286434 -141.248514) (xy 66.328342 -141.185339)
			(xy 66.376728 -141.126977) (xy 66.431044 -141.074089) (xy 66.490673 -141.027274) (xy 66.554941 -140.987062)
			(xy 66.623118 -140.95391) (xy 66.694434 -140.928192) (xy 66.768079 -140.9102) (xy 66.843219 -140.900138)
			(xy 66.919003 -140.898119) (xy 66.994573 -140.904168) (xy 67.069071 -140.918215) (xy 67.141654 -140.940101)
			(xy 67.2115 -140.969578) (xy 67.277817 -141.006313) (xy 67.339853 -141.049888) (xy 67.396906 -141.09981)
			(xy 67.44833 -141.155514) (xy 67.493541 -141.216369) (xy 67.532028 -141.281684) (xy 67.563354 -141.35072)
			(xy 67.587164 -141.422695) (xy 67.603189 -141.496793) (xy 67.611248 -141.572174) (xy 67.611752 -141.61008)
			(xy 68.727831 -141.61008) (xy 68.731866 -141.534376) (xy 68.743925 -141.459531) (xy 68.763871 -141.38639)
			(xy 68.791478 -141.315785) (xy 68.826434 -141.248514) (xy 68.868342 -141.185339) (xy 68.916728 -141.126977)
			(xy 68.971044 -141.074089) (xy 69.030673 -141.027274) (xy 69.094941 -140.987062) (xy 69.163118 -140.95391)
			(xy 69.234434 -140.928192) (xy 69.308079 -140.9102) (xy 69.383219 -140.900138) (xy 69.459003 -140.898119)
			(xy 69.534573 -140.904168) (xy 69.609071 -140.918215) (xy 69.681654 -140.940101) (xy 69.7515 -140.969578)
			(xy 69.817817 -141.006313) (xy 69.879853 -141.049888) (xy 69.936906 -141.09981) (xy 69.98833 -141.155514)
			(xy 70.033541 -141.216369) (xy 70.072028 -141.281684) (xy 70.103354 -141.35072) (xy 70.127164 -141.422695)
			(xy 70.143189 -141.496793) (xy 70.151248 -141.572174) (xy 70.151752 -141.61008) (xy 71.267831 -141.61008)
			(xy 71.271866 -141.534376) (xy 71.283925 -141.459531) (xy 71.303871 -141.38639) (xy 71.331478 -141.315785)
			(xy 71.366434 -141.248514) (xy 71.408342 -141.185339) (xy 71.456728 -141.126977) (xy 71.511044 -141.074089)
			(xy 71.570673 -141.027274) (xy 71.634941 -140.987062) (xy 71.703118 -140.95391) (xy 71.774434 -140.928192)
			(xy 71.848079 -140.9102) (xy 71.923219 -140.900138) (xy 71.999003 -140.898119) (xy 72.074573 -140.904168)
			(xy 72.149071 -140.918215) (xy 72.221654 -140.940101) (xy 72.2915 -140.969578) (xy 72.357817 -141.006313)
			(xy 72.419853 -141.049888) (xy 72.476906 -141.09981) (xy 72.52833 -141.155514) (xy 72.573541 -141.216369)
			(xy 72.612028 -141.281684) (xy 72.643354 -141.35072) (xy 72.667164 -141.422695) (xy 72.683189 -141.496793)
			(xy 72.691248 -141.572174) (xy 72.691752 -141.61008) (xy 73.807831 -141.61008) (xy 73.811866 -141.534376)
			(xy 73.823925 -141.459531) (xy 73.843871 -141.38639) (xy 73.871478 -141.315785) (xy 73.906434 -141.248514)
			(xy 73.948342 -141.185339) (xy 73.996728 -141.126977) (xy 74.051044 -141.074089) (xy 74.110673 -141.027274)
			(xy 74.174941 -140.987062) (xy 74.243118 -140.95391) (xy 74.314434 -140.928192) (xy 74.388079 -140.9102)
			(xy 74.463219 -140.900138) (xy 74.539003 -140.898119) (xy 74.614573 -140.904168) (xy 74.689071 -140.918215)
			(xy 74.761654 -140.940101) (xy 74.8315 -140.969578) (xy 74.897817 -141.006313) (xy 74.959853 -141.049888)
			(xy 75.016906 -141.09981) (xy 75.06833 -141.155514) (xy 75.113541 -141.216369) (xy 75.152028 -141.281684)
			(xy 75.183354 -141.35072) (xy 75.207164 -141.422695) (xy 75.223189 -141.496793) (xy 75.231248 -141.572174)
			(xy 75.231752 -141.61008) (xy 76.347831 -141.61008) (xy 76.351866 -141.534376) (xy 76.363925 -141.459531)
			(xy 76.383871 -141.38639) (xy 76.411478 -141.315785) (xy 76.446434 -141.248514) (xy 76.488342 -141.185339)
			(xy 76.536728 -141.126977) (xy 76.591044 -141.074089) (xy 76.650673 -141.027274) (xy 76.714941 -140.987062)
			(xy 76.783118 -140.95391) (xy 76.854434 -140.928192) (xy 76.928079 -140.9102) (xy 77.003219 -140.900138)
			(xy 77.079003 -140.898119) (xy 77.154573 -140.904168) (xy 77.229071 -140.918215) (xy 77.301654 -140.940101)
			(xy 77.3715 -140.969578) (xy 77.437817 -141.006313) (xy 77.499853 -141.049888) (xy 77.556906 -141.09981)
			(xy 77.60833 -141.155514) (xy 77.653541 -141.216369) (xy 77.692028 -141.281684) (xy 77.723354 -141.35072)
			(xy 77.747164 -141.422695) (xy 77.763189 -141.496793) (xy 77.771248 -141.572174) (xy 77.771752 -141.61008)
			(xy 78.887831 -141.61008) (xy 78.891866 -141.534376) (xy 78.903925 -141.459531) (xy 78.923871 -141.38639)
			(xy 78.951478 -141.315785) (xy 78.986434 -141.248514) (xy 79.028342 -141.185339) (xy 79.076728 -141.126977)
			(xy 79.131044 -141.074089) (xy 79.190673 -141.027274) (xy 79.254941 -140.987062) (xy 79.323118 -140.95391)
			(xy 79.394434 -140.928192) (xy 79.468079 -140.9102) (xy 79.543219 -140.900138) (xy 79.619003 -140.898119)
			(xy 79.694573 -140.904168) (xy 79.769071 -140.918215) (xy 79.841654 -140.940101) (xy 79.9115 -140.969578)
			(xy 79.977817 -141.006313) (xy 80.039853 -141.049888) (xy 80.096906 -141.09981) (xy 80.14833 -141.155514)
			(xy 80.193541 -141.216369) (xy 80.232028 -141.281684) (xy 80.263354 -141.35072) (xy 80.287164 -141.422695)
			(xy 80.303189 -141.496793) (xy 80.311248 -141.572174) (xy 80.311752 -141.61008) (xy 81.427831 -141.61008)
			(xy 81.431866 -141.534376) (xy 81.443925 -141.459531) (xy 81.463871 -141.38639) (xy 81.491478 -141.315785)
			(xy 81.526434 -141.248514) (xy 81.568342 -141.185339) (xy 81.616728 -141.126977) (xy 81.671044 -141.074089)
			(xy 81.730673 -141.027274) (xy 81.794941 -140.987062) (xy 81.863118 -140.95391) (xy 81.934434 -140.928192)
			(xy 82.008079 -140.9102) (xy 82.083219 -140.900138) (xy 82.159003 -140.898119) (xy 82.234573 -140.904168)
			(xy 82.309071 -140.918215) (xy 82.381654 -140.940101) (xy 82.4515 -140.969578) (xy 82.517817 -141.006313)
			(xy 82.579853 -141.049888) (xy 82.636906 -141.09981) (xy 82.68833 -141.155514) (xy 82.733541 -141.216369)
			(xy 82.772028 -141.281684) (xy 82.803354 -141.35072) (xy 82.827164 -141.422695) (xy 82.843189 -141.496793)
			(xy 82.851248 -141.572174) (xy 82.851752 -141.61008) (xy 82.851248 -141.647986) (xy 82.843189 -141.723367)
			(xy 82.827164 -141.797465) (xy 82.803354 -141.86944) (xy 82.772028 -141.938476) (xy 82.733541 -142.003791)
			(xy 82.68833 -142.064646) (xy 82.636906 -142.12035) (xy 82.585798 -142.16507) (xy 84.927951 -142.16507)
			(xy 84.931986 -142.089366) (xy 84.944045 -142.014521) (xy 84.963991 -141.94138) (xy 84.991598 -141.870775)
			(xy 85.026554 -141.803504) (xy 85.068462 -141.740329) (xy 85.116848 -141.681967) (xy 85.171164 -141.629079)
			(xy 85.230793 -141.582264) (xy 85.295061 -141.542052) (xy 85.363238 -141.5089) (xy 85.434554 -141.483182)
			(xy 85.508199 -141.46519) (xy 85.583339 -141.455128) (xy 85.659123 -141.453109) (xy 85.734693 -141.459158)
			(xy 85.809191 -141.473205) (xy 85.881774 -141.495091) (xy 85.95162 -141.524568) (xy 86.017937 -141.561303)
			(xy 86.079973 -141.604878) (xy 86.137026 -141.6548) (xy 86.18845 -141.710504) (xy 86.233661 -141.771359)
			(xy 86.272148 -141.836674) (xy 86.303474 -141.90571) (xy 86.327284 -141.977685) (xy 86.343309 -142.051783)
			(xy 86.351368 -142.127164) (xy 86.351872 -142.16507) (xy 86.351368 -142.202976) (xy 86.343309 -142.278357)
			(xy 86.327284 -142.352455) (xy 86.303474 -142.42443) (xy 86.272148 -142.493466) (xy 86.233661 -142.558781)
			(xy 86.18845 -142.619636) (xy 86.137026 -142.67534) (xy 86.079973 -142.725262) (xy 86.017937 -142.768837)
			(xy 85.95162 -142.805572) (xy 85.881774 -142.835049) (xy 85.809191 -142.856935) (xy 85.734693 -142.870982)
			(xy 85.659123 -142.877031) (xy 85.583339 -142.875012) (xy 85.508199 -142.86495) (xy 85.434554 -142.846958)
			(xy 85.363238 -142.82124) (xy 85.295061 -142.788088) (xy 85.230793 -142.747876) (xy 85.171164 -142.701061)
			(xy 85.116848 -142.648173) (xy 85.068462 -142.589811) (xy 85.026554 -142.526636) (xy 84.991598 -142.459365)
			(xy 84.963991 -142.38876) (xy 84.944045 -142.315619) (xy 84.931986 -142.240774) (xy 84.927951 -142.16507)
			(xy 82.585798 -142.16507) (xy 82.579853 -142.170272) (xy 82.517817 -142.213847) (xy 82.4515 -142.250582)
			(xy 82.381654 -142.280059) (xy 82.309071 -142.301945) (xy 82.234573 -142.315992) (xy 82.159003 -142.322041)
			(xy 82.083219 -142.320022) (xy 82.008079 -142.30996) (xy 81.934434 -142.291968) (xy 81.863118 -142.26625)
			(xy 81.794941 -142.233098) (xy 81.730673 -142.192886) (xy 81.671044 -142.146071) (xy 81.616728 -142.093183)
			(xy 81.568342 -142.034821) (xy 81.526434 -141.971646) (xy 81.491478 -141.904375) (xy 81.463871 -141.83377)
			(xy 81.443925 -141.760629) (xy 81.431866 -141.685784) (xy 81.427831 -141.61008) (xy 80.311752 -141.61008)
			(xy 80.311248 -141.647986) (xy 80.303189 -141.723367) (xy 80.287164 -141.797465) (xy 80.263354 -141.86944)
			(xy 80.232028 -141.938476) (xy 80.193541 -142.003791) (xy 80.14833 -142.064646) (xy 80.096906 -142.12035)
			(xy 80.039853 -142.170272) (xy 79.977817 -142.213847) (xy 79.9115 -142.250582) (xy 79.841654 -142.280059)
			(xy 79.769071 -142.301945) (xy 79.694573 -142.315992) (xy 79.619003 -142.322041) (xy 79.543219 -142.320022)
			(xy 79.468079 -142.30996) (xy 79.394434 -142.291968) (xy 79.323118 -142.26625) (xy 79.254941 -142.233098)
			(xy 79.190673 -142.192886) (xy 79.131044 -142.146071) (xy 79.076728 -142.093183) (xy 79.028342 -142.034821)
			(xy 78.986434 -141.971646) (xy 78.951478 -141.904375) (xy 78.923871 -141.83377) (xy 78.903925 -141.760629)
			(xy 78.891866 -141.685784) (xy 78.887831 -141.61008) (xy 77.771752 -141.61008) (xy 77.771248 -141.647986)
			(xy 77.763189 -141.723367) (xy 77.747164 -141.797465) (xy 77.723354 -141.86944) (xy 77.692028 -141.938476)
			(xy 77.653541 -142.003791) (xy 77.60833 -142.064646) (xy 77.556906 -142.12035) (xy 77.499853 -142.170272)
			(xy 77.437817 -142.213847) (xy 77.3715 -142.250582) (xy 77.301654 -142.280059) (xy 77.229071 -142.301945)
			(xy 77.154573 -142.315992) (xy 77.079003 -142.322041) (xy 77.003219 -142.320022) (xy 76.928079 -142.30996)
			(xy 76.854434 -142.291968) (xy 76.783118 -142.26625) (xy 76.714941 -142.233098) (xy 76.650673 -142.192886)
			(xy 76.591044 -142.146071) (xy 76.536728 -142.093183) (xy 76.488342 -142.034821) (xy 76.446434 -141.971646)
			(xy 76.411478 -141.904375) (xy 76.383871 -141.83377) (xy 76.363925 -141.760629) (xy 76.351866 -141.685784)
			(xy 76.347831 -141.61008) (xy 75.231752 -141.61008) (xy 75.231248 -141.647986) (xy 75.223189 -141.723367)
			(xy 75.207164 -141.797465) (xy 75.183354 -141.86944) (xy 75.152028 -141.938476) (xy 75.113541 -142.003791)
			(xy 75.06833 -142.064646) (xy 75.016906 -142.12035) (xy 74.959853 -142.170272) (xy 74.897817 -142.213847)
			(xy 74.8315 -142.250582) (xy 74.761654 -142.280059) (xy 74.689071 -142.301945) (xy 74.614573 -142.315992)
			(xy 74.539003 -142.322041) (xy 74.463219 -142.320022) (xy 74.388079 -142.30996) (xy 74.314434 -142.291968)
			(xy 74.243118 -142.26625) (xy 74.174941 -142.233098) (xy 74.110673 -142.192886) (xy 74.051044 -142.146071)
			(xy 73.996728 -142.093183) (xy 73.948342 -142.034821) (xy 73.906434 -141.971646) (xy 73.871478 -141.904375)
			(xy 73.843871 -141.83377) (xy 73.823925 -141.760629) (xy 73.811866 -141.685784) (xy 73.807831 -141.61008)
			(xy 72.691752 -141.61008) (xy 72.691248 -141.647986) (xy 72.683189 -141.723367) (xy 72.667164 -141.797465)
			(xy 72.643354 -141.86944) (xy 72.612028 -141.938476) (xy 72.573541 -142.003791) (xy 72.52833 -142.064646)
			(xy 72.476906 -142.12035) (xy 72.419853 -142.170272) (xy 72.357817 -142.213847) (xy 72.2915 -142.250582)
			(xy 72.221654 -142.280059) (xy 72.149071 -142.301945) (xy 72.074573 -142.315992) (xy 71.999003 -142.322041)
			(xy 71.923219 -142.320022) (xy 71.848079 -142.30996) (xy 71.774434 -142.291968) (xy 71.703118 -142.26625)
			(xy 71.634941 -142.233098) (xy 71.570673 -142.192886) (xy 71.511044 -142.146071) (xy 71.456728 -142.093183)
			(xy 71.408342 -142.034821) (xy 71.366434 -141.971646) (xy 71.331478 -141.904375) (xy 71.303871 -141.83377)
			(xy 71.283925 -141.760629) (xy 71.271866 -141.685784) (xy 71.267831 -141.61008) (xy 70.151752 -141.61008)
			(xy 70.151248 -141.647986) (xy 70.143189 -141.723367) (xy 70.127164 -141.797465) (xy 70.103354 -141.86944)
			(xy 70.072028 -141.938476) (xy 70.033541 -142.003791) (xy 69.98833 -142.064646) (xy 69.936906 -142.12035)
			(xy 69.879853 -142.170272) (xy 69.817817 -142.213847) (xy 69.7515 -142.250582) (xy 69.681654 -142.280059)
			(xy 69.609071 -142.301945) (xy 69.534573 -142.315992) (xy 69.459003 -142.322041) (xy 69.383219 -142.320022)
			(xy 69.308079 -142.30996) (xy 69.234434 -142.291968) (xy 69.163118 -142.26625) (xy 69.094941 -142.233098)
			(xy 69.030673 -142.192886) (xy 68.971044 -142.146071) (xy 68.916728 -142.093183) (xy 68.868342 -142.034821)
			(xy 68.826434 -141.971646) (xy 68.791478 -141.904375) (xy 68.763871 -141.83377) (xy 68.743925 -141.760629)
			(xy 68.731866 -141.685784) (xy 68.727831 -141.61008) (xy 67.611752 -141.61008) (xy 67.611248 -141.647986)
			(xy 67.603189 -141.723367) (xy 67.587164 -141.797465) (xy 67.563354 -141.86944) (xy 67.532028 -141.938476)
			(xy 67.493541 -142.003791) (xy 67.44833 -142.064646) (xy 67.396906 -142.12035) (xy 67.339853 -142.170272)
			(xy 67.277817 -142.213847) (xy 67.2115 -142.250582) (xy 67.141654 -142.280059) (xy 67.069071 -142.301945)
			(xy 66.994573 -142.315992) (xy 66.919003 -142.322041) (xy 66.843219 -142.320022) (xy 66.768079 -142.30996)
			(xy 66.694434 -142.291968) (xy 66.623118 -142.26625) (xy 66.554941 -142.233098) (xy 66.490673 -142.192886)
			(xy 66.431044 -142.146071) (xy 66.376728 -142.093183) (xy 66.328342 -142.034821) (xy 66.286434 -141.971646)
			(xy 66.251478 -141.904375) (xy 66.223871 -141.83377) (xy 66.203925 -141.760629) (xy 66.191866 -141.685784)
			(xy 66.187831 -141.61008) (xy 65.071752 -141.61008) (xy 65.071248 -141.647986) (xy 65.063189 -141.723367)
			(xy 65.047164 -141.797465) (xy 65.023354 -141.86944) (xy 64.992028 -141.938476) (xy 64.953541 -142.003791)
			(xy 64.90833 -142.064646) (xy 64.856906 -142.12035) (xy 64.799853 -142.170272) (xy 64.737817 -142.213847)
			(xy 64.6715 -142.250582) (xy 64.601654 -142.280059) (xy 64.529071 -142.301945) (xy 64.454573 -142.315992)
			(xy 64.379003 -142.322041) (xy 64.303219 -142.320022) (xy 64.228079 -142.30996) (xy 64.154434 -142.291968)
			(xy 64.083118 -142.26625) (xy 64.014941 -142.233098) (xy 63.950673 -142.192886) (xy 63.891044 -142.146071)
			(xy 63.836728 -142.093183) (xy 63.788342 -142.034821) (xy 63.746434 -141.971646) (xy 63.711478 -141.904375)
			(xy 63.683871 -141.83377) (xy 63.663925 -141.760629) (xy 63.651866 -141.685784) (xy 63.647831 -141.61008)
			(xy 42.503292 -141.61008) (xy 42.47864 -141.629064) (xy 42.380994 -141.693948) (xy 42.279065 -141.75187)
			(xy 42.173347 -141.802549) (xy 42.064355 -141.845738) (xy 41.952619 -141.881228) (xy 41.838681 -141.908845)
			(xy 41.723096 -141.928457) (xy 41.606425 -141.939967) (xy 41.489236 -141.943319) (xy 41.372098 -141.938497)
			(xy 41.25558 -141.925525) (xy 41.14025 -141.904466) (xy 41.026668 -141.875421) (xy 40.915385 -141.838533)
			(xy 40.806943 -141.79398) (xy 40.70187 -141.74198) (xy 40.600675 -141.682784) (xy 40.50385 -141.616681)
			(xy 40.411868 -141.543992) (xy 40.325173 -141.46507) (xy 40.244189 -141.380299) (xy 40.169308 -141.290091)
			(xy 40.100895 -141.194885) (xy 40.039282 -141.095143) (xy 39.984769 -140.991351) (xy 39.937621 -140.884012)
			(xy 39.898066 -140.773649) (xy 39.866298 -140.660798) (xy 39.842471 -140.546008) (xy 39.826699 -140.429836)
			(xy 39.819061 -140.312848) (xy 39.818818 -140.254228) (xy 29.820108 -140.254228) (xy 29.820108 -142.659608)
			(xy 29.820564 -142.681558) (xy 29.828096 -142.724806) (xy 29.842952 -142.766116) (xy 29.864689 -142.804256)
			(xy 29.89266 -142.838091) (xy 29.926031 -142.866613) (xy 29.96381 -142.888972) (xy 30.00487 -142.904503)
			(xy 30.047989 -142.912744) (xy 30.091883 -142.913448) (xy 30.135244 -142.906594) (xy 30.15615 -142.899892)
			(xy 30.19755 -142.886292) (xy 30.282281 -142.865913) (xy 30.368534 -142.85346) (xy 30.45557 -142.849042)
			(xy 30.542641 -142.852696) (xy 30.629 -142.86439) (xy 30.713907 -142.884025) (xy 30.796633 -142.911432)
			(xy 30.876468 -142.946375) (xy 30.952728 -142.988555) (xy 31.024757 -143.03761) (xy 31.091939 -143.093119)
			(xy 31.153697 -143.154606) (xy 31.209501 -143.221544) (xy 31.258872 -143.293357) (xy 31.301386 -143.369431)
			(xy 31.33668 -143.449112) (xy 31.36445 -143.531717) (xy 31.384457 -143.616536) (xy 31.396531 -143.702843)
			(xy 31.400567 -143.789897) (xy 31.398552 -143.833358) (xy 34.599874 -143.833358) (xy 34.599874 -143.746458)
			(xy 34.607892 -143.659929) (xy 34.62386 -143.574509) (xy 34.647641 -143.490927) (xy 34.679033 -143.409895)
			(xy 34.717767 -143.332106) (xy 34.763514 -143.258222) (xy 34.815883 -143.188875) (xy 34.874427 -143.124655)
			(xy 34.938647 -143.066111) (xy 35.007994 -143.013742) (xy 35.081878 -142.967995) (xy 35.159667 -142.929261)
			(xy 35.240699 -142.897869) (xy 35.324281 -142.874088) (xy 35.409701 -142.85812) (xy 35.49623 -142.850102)
			(xy 35.58313 -142.850102) (xy 35.669659 -142.85812) (xy 35.755079 -142.874088) (xy 35.838661 -142.897869)
			(xy 35.919693 -142.929261) (xy 35.997482 -142.967995) (xy 36.071366 -143.013742) (xy 36.140713 -143.066111)
			(xy 36.204933 -143.124655) (xy 36.263477 -143.188875) (xy 36.315846 -143.258222) (xy 36.361593 -143.332106)
			(xy 36.400327 -143.409895) (xy 36.431719 -143.490927) (xy 36.4555 -143.574509) (xy 36.471468 -143.659929)
			(xy 36.479486 -143.746458) (xy 36.479988 -143.789908) (xy 36.479486 -143.833358) (xy 36.471468 -143.919887)
			(xy 36.4555 -144.005307) (xy 36.431719 -144.088889) (xy 36.400327 -144.169921) (xy 36.361593 -144.24771)
			(xy 36.315846 -144.321594) (xy 36.263477 -144.390941) (xy 36.204933 -144.455161) (xy 36.140713 -144.513705)
			(xy 36.071366 -144.566074) (xy 35.997482 -144.611821) (xy 35.919693 -144.650555) (xy 35.838661 -144.681947)
			(xy 35.755079 -144.705728) (xy 35.669659 -144.721696) (xy 35.58313 -144.729714) (xy 35.49623 -144.729714)
			(xy 35.409701 -144.721696) (xy 35.324281 -144.705728) (xy 35.240699 -144.681947) (xy 35.159667 -144.650555)
			(xy 35.081878 -144.611821) (xy 35.007994 -144.566074) (xy 34.938647 -144.513705) (xy 34.874427 -144.455161)
			(xy 34.815883 -144.390941) (xy 34.763514 -144.321594) (xy 34.717767 -144.24771) (xy 34.679033 -144.169921)
			(xy 34.647641 -144.088889) (xy 34.62386 -144.005307) (xy 34.607892 -143.919887) (xy 34.599874 -143.833358)
			(xy 31.398552 -143.833358) (xy 31.396531 -143.876951) (xy 31.384458 -143.963259) (xy 31.364451 -144.048078)
			(xy 31.336682 -144.130683) (xy 31.301389 -144.210365) (xy 31.258875 -144.286438) (xy 31.209504 -144.358252)
			(xy 31.153701 -144.42519) (xy 31.091943 -144.486678) (xy 31.024762 -144.542187) (xy 30.952732 -144.591243)
			(xy 30.876473 -144.633423) (xy 30.796638 -144.668367) (xy 30.713912 -144.695773) (xy 30.629005 -144.715409)
			(xy 30.542646 -144.727103) (xy 30.455575 -144.730758) (xy 30.368539 -144.72634) (xy 30.282286 -144.713888)
			(xy 30.197555 -144.69351) (xy 30.15615 -144.679924) (xy 30.135234 -144.673273) (xy 30.091882 -144.666443)
			(xy 30.048002 -144.667163) (xy 30.004897 -144.675411) (xy 29.963851 -144.690943) (xy 29.926084 -144.713296)
			(xy 29.892719 -144.741805) (xy 29.864748 -144.775623) (xy 29.843004 -144.813744) (xy 29.828133 -144.855034)
			(xy 29.820577 -144.898265) (xy 29.820108 -144.920208) (xy 29.820108 -145.199608) (xy 29.820564 -145.221558)
			(xy 29.828096 -145.264806) (xy 29.842952 -145.306116) (xy 29.864689 -145.344256) (xy 29.89266 -145.378091)
			(xy 29.926031 -145.406613) (xy 29.96381 -145.428972) (xy 30.00487 -145.444503) (xy 30.047989 -145.452744)
			(xy 30.091883 -145.453448) (xy 30.135244 -145.446594) (xy 30.15615 -145.439892) (xy 30.19755 -145.426292)
			(xy 30.282281 -145.405913) (xy 30.368534 -145.39346) (xy 30.45557 -145.389042) (xy 30.542641 -145.392696)
			(xy 30.629 -145.40439) (xy 30.713907 -145.424025) (xy 30.796633 -145.451432) (xy 30.876468 -145.486375)
			(xy 30.952728 -145.528555) (xy 31.024757 -145.57761) (xy 31.091939 -145.633119) (xy 31.153697 -145.694606)
			(xy 31.209501 -145.761544) (xy 31.258872 -145.833357) (xy 31.301386 -145.909431) (xy 31.33668 -145.989112)
			(xy 31.36445 -146.071717) (xy 31.384457 -146.156536) (xy 31.396531 -146.242843) (xy 31.400567 -146.329897)
			(xy 31.398552 -146.373358) (xy 34.599874 -146.373358) (xy 34.599874 -146.286458) (xy 34.607892 -146.199929)
			(xy 34.62386 -146.114509) (xy 34.647641 -146.030927) (xy 34.679033 -145.949895) (xy 34.717767 -145.872106)
			(xy 34.763514 -145.798222) (xy 34.815883 -145.728875) (xy 34.874427 -145.664655) (xy 34.938647 -145.606111)
			(xy 35.007994 -145.553742) (xy 35.081878 -145.507995) (xy 35.159667 -145.469261) (xy 35.240699 -145.437869)
			(xy 35.324281 -145.414088) (xy 35.409701 -145.39812) (xy 35.49623 -145.390102) (xy 35.58313 -145.390102)
			(xy 35.669659 -145.39812) (xy 35.755079 -145.414088) (xy 35.838661 -145.437869) (xy 35.870739 -145.450296)
			(xy 66.71631 -145.450296) (xy 66.720198 -145.395947) (xy 66.73178 -145.342704) (xy 66.750823 -145.291652)
			(xy 66.776937 -145.243829) (xy 66.809591 -145.20021) (xy 66.848121 -145.161682) (xy 66.891742 -145.129029)
			(xy 66.939565 -145.102917) (xy 66.990619 -145.083876) (xy 67.043862 -145.072295) (xy 67.098211 -145.06841)
			(xy 67.15256 -145.072299) (xy 67.205803 -145.083883) (xy 67.256855 -145.102926) (xy 67.304677 -145.129041)
			(xy 67.326764 -145.144998) (xy 67.345776 -145.158594) (xy 67.387659 -145.179326) (xy 67.432627 -145.192052)
			(xy 67.479164 -145.196342) (xy 67.525701 -145.192052) (xy 67.570669 -145.179326) (xy 67.612552 -145.158594)
			(xy 67.631564 -145.144998) (xy 67.653647 -145.129027) (xy 67.701476 -145.1029) (xy 67.752536 -145.083846)
			(xy 67.805788 -145.072253) (xy 67.860148 -145.068357) (xy 67.914509 -145.072238) (xy 67.967764 -145.083816)
			(xy 68.018829 -145.102856) (xy 68.066665 -145.128971) (xy 68.110297 -145.161627) (xy 68.148836 -145.200161)
			(xy 68.181499 -145.243788) (xy 68.20762 -145.29162) (xy 68.226668 -145.342682) (xy 68.238254 -145.395936)
			(xy 68.242143 -145.450296) (xy 69.707903 -145.450296) (xy 69.711791 -145.395945) (xy 69.723374 -145.342701)
			(xy 69.742417 -145.291647) (xy 69.768532 -145.243823) (xy 69.801188 -145.200203) (xy 69.839719 -145.161674)
			(xy 69.883341 -145.129021) (xy 69.931167 -145.102908) (xy 69.982222 -145.083868) (xy 70.035467 -145.072287)
			(xy 70.089818 -145.068403) (xy 70.144169 -145.072293) (xy 70.197413 -145.083878) (xy 70.248466 -145.102923)
			(xy 70.296289 -145.12904) (xy 70.318376 -145.144998) (xy 70.337388 -145.158594) (xy 70.379271 -145.179326)
			(xy 70.424239 -145.192052) (xy 70.470776 -145.196342) (xy 70.517313 -145.192052) (xy 70.562281 -145.179326)
			(xy 70.604164 -145.158594) (xy 70.623176 -145.144998) (xy 70.645259 -145.129028) (xy 70.693087 -145.102903)
			(xy 70.744146 -145.08385) (xy 70.797396 -145.072259) (xy 70.851755 -145.068364) (xy 70.906114 -145.072246)
			(xy 70.959368 -145.083825) (xy 71.010431 -145.102865) (xy 71.058265 -145.128979) (xy 71.101895 -145.161635)
			(xy 71.140433 -145.200168) (xy 71.173095 -145.243794) (xy 71.199215 -145.291625) (xy 71.218261 -145.342686)
			(xy 71.229847 -145.395938) (xy 71.233736 -145.450296) (xy 71.229848 -145.504655) (xy 71.218264 -145.557908)
			(xy 71.199218 -145.608969) (xy 71.173099 -145.6568) (xy 71.140438 -145.700426) (xy 71.1019 -145.73896)
			(xy 71.058271 -145.771617) (xy 71.010438 -145.797732) (xy 70.959374 -145.816773) (xy 70.906121 -145.828353)
			(xy 70.851762 -145.832236) (xy 70.797403 -145.828342) (xy 70.744152 -145.816752) (xy 70.693093 -145.7977)
			(xy 70.645265 -145.771576) (xy 70.623176 -145.755614) (xy 70.604164 -145.742018) (xy 70.562281 -145.721286)
			(xy 70.517313 -145.70856) (xy 70.470776 -145.70427) (xy 70.424239 -145.70856) (xy 70.379271 -145.721286)
			(xy 70.337388 -145.742018) (xy 70.318376 -145.755614) (xy 70.296283 -145.771564) (xy 70.248459 -145.79768)
			(xy 70.197406 -145.816724) (xy 70.144162 -145.828308) (xy 70.089811 -145.832197) (xy 70.03546 -145.828312)
			(xy 69.982215 -145.81673) (xy 69.93116 -145.797689) (xy 69.883335 -145.771575) (xy 69.839714 -145.738922)
			(xy 69.801183 -145.700392) (xy 69.768528 -145.656771) (xy 69.742414 -145.608946) (xy 69.723372 -145.557892)
			(xy 69.71179 -145.504647) (xy 69.707903 -145.450296) (xy 68.242143 -145.450296) (xy 68.238255 -145.504657)
			(xy 68.22667 -145.557911) (xy 68.207623 -145.608974) (xy 68.181503 -145.656806) (xy 68.148841 -145.700433)
			(xy 68.110302 -145.738968) (xy 68.066671 -145.771626) (xy 68.018836 -145.797741) (xy 67.967771 -145.816782)
			(xy 67.914516 -145.828361) (xy 67.860155 -145.832243) (xy 67.805795 -145.828348) (xy 67.752543 -145.816756)
			(xy 67.701482 -145.797703) (xy 67.653653 -145.771577) (xy 67.631564 -145.755614) (xy 67.612552 -145.742018)
			(xy 67.570669 -145.721286) (xy 67.525701 -145.70856) (xy 67.479164 -145.70427) (xy 67.432627 -145.70856)
			(xy 67.387659 -145.721286) (xy 67.345776 -145.742018) (xy 67.326764 -145.755614) (xy 67.304671 -145.771563)
			(xy 67.256848 -145.797677) (xy 67.205796 -145.816719) (xy 67.152553 -145.828302) (xy 67.098204 -145.83219)
			(xy 67.043855 -145.828304) (xy 66.990612 -145.816722) (xy 66.939559 -145.79768) (xy 66.891736 -145.771567)
			(xy 66.848116 -145.738914) (xy 66.809587 -145.700385) (xy 66.776933 -145.656765) (xy 66.75082 -145.608941)
			(xy 66.731778 -145.557889) (xy 66.720197 -145.504646) (xy 66.71631 -145.450296) (xy 35.870739 -145.450296)
			(xy 35.919693 -145.469261) (xy 35.997482 -145.507995) (xy 36.071366 -145.553742) (xy 36.140713 -145.606111)
			(xy 36.204933 -145.664655) (xy 36.263477 -145.728875) (xy 36.315846 -145.798222) (xy 36.361593 -145.872106)
			(xy 36.400327 -145.949895) (xy 36.431719 -146.030927) (xy 36.4555 -146.114509) (xy 36.471468 -146.199929)
			(xy 36.479486 -146.286458) (xy 36.479988 -146.329908) (xy 36.479486 -146.373358) (xy 36.47158 -146.458682)
			(xy 80.919302 -146.458682) (xy 80.919302 -146.398746) (xy 80.927125 -146.339324) (xy 80.942638 -146.281431)
			(xy 80.965574 -146.226058) (xy 80.995541 -146.174152) (xy 81.032028 -146.126602) (xy 81.074408 -146.084222)
			(xy 81.121958 -146.047735) (xy 81.173864 -146.017768) (xy 81.229237 -145.994832) (xy 81.28713 -145.979319)
			(xy 81.346552 -145.971496) (xy 81.406488 -145.971496) (xy 81.46591 -145.979319) (xy 81.523803 -145.994832)
			(xy 81.579176 -146.017768) (xy 81.631082 -146.047735) (xy 81.678632 -146.084222) (xy 81.721012 -146.126602)
			(xy 81.757499 -146.174152) (xy 81.787466 -146.226058) (xy 81.810402 -146.281431) (xy 81.825915 -146.339324)
			(xy 81.833738 -146.398746) (xy 81.834228 -146.428714) (xy 81.833738 -146.458682) (xy 81.825915 -146.518104)
			(xy 81.810402 -146.575997) (xy 81.787466 -146.63137) (xy 81.757499 -146.683276) (xy 81.721012 -146.730826)
			(xy 81.678632 -146.773206) (xy 81.631082 -146.809693) (xy 81.579176 -146.83966) (xy 81.523803 -146.862596)
			(xy 81.46591 -146.878109) (xy 81.406488 -146.885932) (xy 81.346552 -146.885932) (xy 81.28713 -146.878109)
			(xy 81.229237 -146.862596) (xy 81.173864 -146.83966) (xy 81.121958 -146.809693) (xy 81.074408 -146.773206)
			(xy 81.032028 -146.730826) (xy 80.995541 -146.683276) (xy 80.965574 -146.63137) (xy 80.942638 -146.575997)
			(xy 80.927125 -146.518104) (xy 80.919302 -146.458682) (xy 36.47158 -146.458682) (xy 36.471468 -146.459887)
			(xy 36.4555 -146.545307) (xy 36.431719 -146.628889) (xy 36.400327 -146.709921) (xy 36.361593 -146.78771)
			(xy 36.315846 -146.861594) (xy 36.263477 -146.930941) (xy 36.204933 -146.995161) (xy 36.140713 -147.053705)
			(xy 36.071366 -147.106074) (xy 35.997482 -147.151821) (xy 35.919693 -147.190555) (xy 35.838661 -147.221947)
			(xy 35.755079 -147.245728) (xy 35.669659 -147.261696) (xy 35.58313 -147.269714) (xy 35.49623 -147.269714)
			(xy 35.409701 -147.261696) (xy 35.324281 -147.245728) (xy 35.240699 -147.221947) (xy 35.159667 -147.190555)
			(xy 35.081878 -147.151821) (xy 35.007994 -147.106074) (xy 34.938647 -147.053705) (xy 34.874427 -146.995161)
			(xy 34.815883 -146.930941) (xy 34.763514 -146.861594) (xy 34.717767 -146.78771) (xy 34.679033 -146.709921)
			(xy 34.647641 -146.628889) (xy 34.62386 -146.545307) (xy 34.607892 -146.459887) (xy 34.599874 -146.373358)
			(xy 31.398552 -146.373358) (xy 31.396531 -146.416951) (xy 31.384458 -146.503259) (xy 31.364451 -146.588078)
			(xy 31.336682 -146.670683) (xy 31.301389 -146.750365) (xy 31.258875 -146.826438) (xy 31.209504 -146.898252)
			(xy 31.153701 -146.96519) (xy 31.091943 -147.026678) (xy 31.024762 -147.082187) (xy 30.952732 -147.131243)
			(xy 30.876473 -147.173423) (xy 30.796638 -147.208367) (xy 30.713912 -147.235773) (xy 30.629005 -147.255409)
			(xy 30.542646 -147.267103) (xy 30.455575 -147.270758) (xy 30.368539 -147.26634) (xy 30.282286 -147.253888)
			(xy 30.197555 -147.23351) (xy 30.15615 -147.219924) (xy 30.135234 -147.213273) (xy 30.091882 -147.206443)
			(xy 30.048002 -147.207163) (xy 30.004897 -147.215411) (xy 29.963851 -147.230943) (xy 29.926084 -147.253296)
			(xy 29.892719 -147.281805) (xy 29.864748 -147.315623) (xy 29.843004 -147.353744) (xy 29.828133 -147.395034)
			(xy 29.820577 -147.438265) (xy 29.820108 -147.460208) (xy 29.820108 -147.685824) (xy 66.716273 -147.685824)
			(xy 66.720157 -147.631469) (xy 66.731737 -147.57822) (xy 66.750778 -147.527162) (xy 66.776891 -147.479333)
			(xy 66.809545 -147.435707) (xy 66.848076 -147.397172) (xy 66.891699 -147.364513) (xy 66.939525 -147.338395)
			(xy 66.990582 -147.319349) (xy 67.043829 -147.307763) (xy 67.098184 -147.303873) (xy 67.152538 -147.307758)
			(xy 67.205787 -147.31934) (xy 67.256845 -147.338381) (xy 67.304674 -147.364495) (xy 67.326764 -147.380452)
			(xy 67.345776 -147.394048) (xy 67.387659 -147.41478) (xy 67.432627 -147.427506) (xy 67.479164 -147.431796)
			(xy 67.525701 -147.427506) (xy 67.570669 -147.41478) (xy 67.612552 -147.394048) (xy 67.631564 -147.380452)
			(xy 67.653691 -147.364543) (xy 67.701516 -147.338422) (xy 67.752573 -147.319373) (xy 67.80582 -147.307785)
			(xy 67.860175 -147.303894) (xy 67.914531 -147.307778) (xy 67.96778 -147.319359) (xy 68.018839 -147.338401)
			(xy 68.066668 -147.364516) (xy 68.110293 -147.397173) (xy 68.148827 -147.435706) (xy 68.181483 -147.479331)
			(xy 68.207598 -147.52716) (xy 68.22664 -147.578219) (xy 68.238222 -147.631468) (xy 68.242106 -147.685824)
			(xy 69.707866 -147.685824) (xy 69.71175 -147.631468) (xy 69.723331 -147.578217) (xy 69.742372 -147.527157)
			(xy 69.768486 -147.479327) (xy 69.801142 -147.4357) (xy 69.839674 -147.397164) (xy 69.883298 -147.364505)
			(xy 69.931127 -147.338386) (xy 69.982185 -147.31934) (xy 70.035434 -147.307755) (xy 70.08979 -147.303866)
			(xy 70.144147 -147.307752) (xy 70.197397 -147.319335) (xy 70.248456 -147.338378) (xy 70.296286 -147.364494)
			(xy 70.318376 -147.380452) (xy 70.337388 -147.394048) (xy 70.379271 -147.41478) (xy 70.424239 -147.427506)
			(xy 70.470776 -147.431796) (xy 70.517313 -147.427506) (xy 70.562281 -147.41478) (xy 70.604164 -147.394048)
			(xy 70.623176 -147.380452) (xy 70.645302 -147.364544) (xy 70.693127 -147.338425) (xy 70.744182 -147.319378)
			(xy 70.797429 -147.307791) (xy 70.851782 -147.303901) (xy 70.906136 -147.307786) (xy 70.959384 -147.319368)
			(xy 71.010441 -147.33841) (xy 71.058268 -147.364525) (xy 71.101892 -147.397181) (xy 71.140423 -147.435713)
			(xy 71.173079 -147.479337) (xy 71.199193 -147.527165) (xy 71.218234 -147.578222) (xy 71.229815 -147.63147)
			(xy 71.233699 -147.685824) (xy 71.229808 -147.740177) (xy 71.21822 -147.793424) (xy 71.199173 -147.844479)
			(xy 71.173053 -147.892303) (xy 71.140392 -147.935923) (xy 71.101855 -147.974451) (xy 71.058228 -148.007101)
			(xy 71.010397 -148.03321) (xy 70.959338 -148.052246) (xy 70.906089 -148.063821) (xy 70.851734 -148.067699)
			(xy 70.797381 -148.063802) (xy 70.744136 -148.052209) (xy 70.693083 -148.033155) (xy 70.645262 -148.00703)
			(xy 70.623176 -147.991068) (xy 70.604164 -147.977472) (xy 70.562281 -147.95674) (xy 70.517313 -147.944014)
			(xy 70.470776 -147.939724) (xy 70.424239 -147.944014) (xy 70.379271 -147.95674) (xy 70.337388 -147.977472)
			(xy 70.318376 -147.991068) (xy 70.296326 -148.00708) (xy 70.2485 -148.033202) (xy 70.197443 -148.052252)
			(xy 70.144194 -148.063841) (xy 70.089838 -148.067734) (xy 70.035482 -148.063852) (xy 69.982231 -148.052273)
			(xy 69.93117 -148.033234) (xy 69.883339 -148.007121) (xy 69.83971 -147.974467) (xy 69.801173 -147.935937)
			(xy 69.768512 -147.892314) (xy 69.742392 -147.844487) (xy 69.723344 -147.793429) (xy 69.711757 -147.74018)
			(xy 69.707866 -147.685824) (xy 68.242106 -147.685824) (xy 68.238215 -147.740179) (xy 68.226627 -147.793427)
			(xy 68.207579 -147.844483) (xy 68.181457 -147.892309) (xy 68.148795 -147.93593) (xy 68.110257 -147.974458)
			(xy 68.066628 -148.00711) (xy 68.018796 -148.033219) (xy 67.967734 -148.052254) (xy 67.914483 -148.063829)
			(xy 67.860127 -148.067706) (xy 67.805773 -148.063808) (xy 67.752527 -148.052213) (xy 67.701472 -148.033158)
			(xy 67.65365 -148.007031) (xy 67.631564 -147.991068) (xy 67.612552 -147.977472) (xy 67.570669 -147.95674)
			(xy 67.525701 -147.944014) (xy 67.479164 -147.939724) (xy 67.432627 -147.944014) (xy 67.387659 -147.95674)
			(xy 67.345776 -147.977472) (xy 67.326764 -147.991068) (xy 67.304714 -148.007079) (xy 67.256889 -148.033199)
			(xy 67.205833 -148.052247) (xy 67.152586 -148.063835) (xy 67.098232 -148.067727) (xy 67.043877 -148.063844)
			(xy 66.990628 -148.052265) (xy 66.939569 -148.033225) (xy 66.891739 -148.007113) (xy 66.848112 -147.97446)
			(xy 66.809577 -147.93593) (xy 66.776917 -147.892308) (xy 66.750798 -147.844482) (xy 66.731751 -147.793426)
			(xy 66.720164 -147.740178) (xy 66.716273 -147.685824) (xy 29.820108 -147.685824) (xy 29.820108 -147.739608)
			(xy 29.820564 -147.761558) (xy 29.828096 -147.804806) (xy 29.842952 -147.846116) (xy 29.864689 -147.884256)
			(xy 29.89266 -147.918091) (xy 29.926031 -147.946613) (xy 29.96381 -147.968972) (xy 30.00487 -147.984503)
			(xy 30.047989 -147.992744) (xy 30.091883 -147.993448) (xy 30.135244 -147.986594) (xy 30.15615 -147.979892)
			(xy 30.19755 -147.966292) (xy 30.282281 -147.945913) (xy 30.368534 -147.93346) (xy 30.45557 -147.929042)
			(xy 30.542641 -147.932696) (xy 30.629 -147.94439) (xy 30.713907 -147.964025) (xy 30.796633 -147.991432)
			(xy 30.876468 -148.026375) (xy 30.952728 -148.068555) (xy 31.024757 -148.11761) (xy 31.091939 -148.173119)
			(xy 31.153697 -148.234606) (xy 31.209501 -148.301544) (xy 31.258872 -148.373357) (xy 31.301386 -148.449431)
			(xy 31.33668 -148.529112) (xy 31.36445 -148.611717) (xy 31.384457 -148.696536) (xy 31.396531 -148.782843)
			(xy 31.400567 -148.869897) (xy 31.398552 -148.913358) (xy 34.599874 -148.913358) (xy 34.599874 -148.826458)
			(xy 34.607892 -148.739929) (xy 34.62386 -148.654509) (xy 34.647641 -148.570927) (xy 34.679033 -148.489895)
			(xy 34.717767 -148.412106) (xy 34.763514 -148.338222) (xy 34.815883 -148.268875) (xy 34.874427 -148.204655)
			(xy 34.938647 -148.146111) (xy 35.007994 -148.093742) (xy 35.081878 -148.047995) (xy 35.159667 -148.009261)
			(xy 35.240699 -147.977869) (xy 35.324281 -147.954088) (xy 35.409701 -147.93812) (xy 35.49623 -147.930102)
			(xy 35.58313 -147.930102) (xy 35.669659 -147.93812) (xy 35.755079 -147.954088) (xy 35.838661 -147.977869)
			(xy 35.919693 -148.009261) (xy 35.997482 -148.047995) (xy 36.071366 -148.093742) (xy 36.140713 -148.146111)
			(xy 36.204933 -148.204655) (xy 36.263477 -148.268875) (xy 36.315846 -148.338222) (xy 36.361593 -148.412106)
			(xy 36.400327 -148.489895) (xy 36.431719 -148.570927) (xy 36.4555 -148.654509) (xy 36.471468 -148.739929)
			(xy 36.479486 -148.826458) (xy 36.479988 -148.869908) (xy 36.479486 -148.913358) (xy 36.471468 -148.999887)
			(xy 36.4555 -149.085307) (xy 36.431719 -149.168889) (xy 36.400327 -149.249921) (xy 36.361593 -149.32771)
			(xy 36.315846 -149.401594) (xy 36.282714 -149.445468) (xy 80.244678 -149.445468) (xy 80.244678 -149.385532)
			(xy 80.252501 -149.32611) (xy 80.268014 -149.268217) (xy 80.29095 -149.212844) (xy 80.320917 -149.160938)
			(xy 80.357404 -149.113388) (xy 80.399784 -149.071008) (xy 80.447334 -149.034521) (xy 80.49924 -149.004554)
			(xy 80.554613 -148.981618) (xy 80.612506 -148.966105) (xy 80.671928 -148.958282) (xy 80.731864 -148.958282)
			(xy 80.791286 -148.966105) (xy 80.849179 -148.981618) (xy 80.904552 -149.004554) (xy 80.956458 -149.034521)
			(xy 81.004008 -149.071008) (xy 81.046388 -149.113388) (xy 81.082875 -149.160938) (xy 81.112842 -149.212844)
			(xy 81.135778 -149.268217) (xy 81.151291 -149.32611) (xy 81.159114 -149.385532) (xy 81.159604 -149.4155)
			(xy 81.159114 -149.445468) (xy 81.151291 -149.50489) (xy 81.135778 -149.562783) (xy 81.112842 -149.618156)
			(xy 81.082875 -149.670062) (xy 81.046388 -149.717612) (xy 81.004008 -149.759992) (xy 80.956458 -149.796479)
			(xy 80.904552 -149.826446) (xy 80.849179 -149.849382) (xy 80.791286 -149.864895) (xy 80.731864 -149.872718)
			(xy 80.671928 -149.872718) (xy 80.612506 -149.864895) (xy 80.554613 -149.849382) (xy 80.49924 -149.826446)
			(xy 80.447334 -149.796479) (xy 80.399784 -149.759992) (xy 80.357404 -149.717612) (xy 80.320917 -149.670062)
			(xy 80.29095 -149.618156) (xy 80.268014 -149.562783) (xy 80.252501 -149.50489) (xy 80.244678 -149.445468)
			(xy 36.282714 -149.445468) (xy 36.263477 -149.470941) (xy 36.204933 -149.535161) (xy 36.140713 -149.593705)
			(xy 36.071366 -149.646074) (xy 35.997482 -149.691821) (xy 35.919693 -149.730555) (xy 35.838661 -149.761947)
			(xy 35.755079 -149.785728) (xy 35.669659 -149.801696) (xy 35.58313 -149.809714) (xy 35.49623 -149.809714)
			(xy 35.409701 -149.801696) (xy 35.324281 -149.785728) (xy 35.240699 -149.761947) (xy 35.159667 -149.730555)
			(xy 35.081878 -149.691821) (xy 35.007994 -149.646074) (xy 34.938647 -149.593705) (xy 34.874427 -149.535161)
			(xy 34.815883 -149.470941) (xy 34.763514 -149.401594) (xy 34.717767 -149.32771) (xy 34.679033 -149.249921)
			(xy 34.647641 -149.168889) (xy 34.62386 -149.085307) (xy 34.607892 -148.999887) (xy 34.599874 -148.913358)
			(xy 31.398552 -148.913358) (xy 31.396531 -148.956951) (xy 31.384458 -149.043259) (xy 31.364451 -149.128078)
			(xy 31.336682 -149.210683) (xy 31.301389 -149.290365) (xy 31.258875 -149.366438) (xy 31.209504 -149.438252)
			(xy 31.153701 -149.50519) (xy 31.091943 -149.566678) (xy 31.024762 -149.622187) (xy 30.952732 -149.671243)
			(xy 30.876473 -149.713423) (xy 30.796638 -149.748367) (xy 30.713912 -149.775773) (xy 30.629005 -149.795409)
			(xy 30.542646 -149.807103) (xy 30.455575 -149.810758) (xy 30.368539 -149.80634) (xy 30.282286 -149.793888)
			(xy 30.197555 -149.77351) (xy 30.15615 -149.759924) (xy 30.135234 -149.753273) (xy 30.091882 -149.746443)
			(xy 30.048002 -149.747163) (xy 30.004897 -149.755411) (xy 29.963851 -149.770943) (xy 29.926084 -149.793296)
			(xy 29.892719 -149.821805) (xy 29.864748 -149.855623) (xy 29.843004 -149.893744) (xy 29.828133 -149.935034)
			(xy 29.820577 -149.978265) (xy 29.820108 -150.000208) (xy 29.820108 -150.279608) (xy 29.820564 -150.301558)
			(xy 29.828096 -150.344806) (xy 29.831396 -150.353982) (xy 66.716329 -150.353982) (xy 66.720219 -150.299636)
			(xy 66.731803 -150.246396) (xy 66.750846 -150.195347) (xy 66.776961 -150.147528) (xy 66.809615 -150.103912)
			(xy 66.848144 -150.065387) (xy 66.891764 -150.032737) (xy 66.939586 -150.006628) (xy 66.990638 -149.987591)
			(xy 67.043879 -149.976012) (xy 67.098226 -149.972129) (xy 67.152572 -149.97602) (xy 67.205811 -149.987605)
			(xy 67.25686 -150.006649) (xy 67.304679 -150.032765) (xy 67.326764 -150.048722) (xy 67.345776 -150.062318)
			(xy 67.387659 -150.08305) (xy 67.432627 -150.095776) (xy 67.479164 -150.100066) (xy 67.525701 -150.095776)
			(xy 67.570669 -150.08305) (xy 67.612552 -150.062318) (xy 67.631564 -150.048722) (xy 67.653625 -150.032719)
			(xy 67.701455 -150.006588) (xy 67.752517 -149.987531) (xy 67.805771 -149.975936) (xy 67.860133 -149.972038)
			(xy 67.914497 -149.975917) (xy 67.967756 -149.987494) (xy 68.018824 -150.006533) (xy 68.066663 -150.032647)
			(xy 68.110298 -150.065303) (xy 68.148841 -150.103838) (xy 68.181508 -150.147466) (xy 68.207632 -150.195299)
			(xy 68.226682 -150.246363) (xy 68.238271 -150.299619) (xy 68.242162 -150.353982) (xy 69.707922 -150.353982)
			(xy 69.711812 -150.299634) (xy 69.723396 -150.246393) (xy 69.742441 -150.195342) (xy 69.768556 -150.147522)
			(xy 69.801212 -150.103904) (xy 69.839743 -150.065379) (xy 69.883364 -150.032729) (xy 69.931188 -150.00662)
			(xy 69.982241 -149.987582) (xy 70.035484 -149.976004) (xy 70.089832 -149.972122) (xy 70.14418 -149.976014)
			(xy 70.197421 -149.9876) (xy 70.248471 -150.006647) (xy 70.296291 -150.032764) (xy 70.318376 -150.048722)
			(xy 70.337388 -150.062318) (xy 70.379271 -150.08305) (xy 70.424239 -150.095776) (xy 70.470776 -150.100066)
			(xy 70.517313 -150.095776) (xy 70.562281 -150.08305) (xy 70.604164 -150.062318) (xy 70.623176 -150.048722)
			(xy 70.645237 -150.03272) (xy 70.693066 -150.006591) (xy 70.744126 -149.987536) (xy 70.797379 -149.975942)
			(xy 70.85174 -149.972045) (xy 70.906103 -149.975925) (xy 70.959359 -149.987502) (xy 71.010426 -150.006542)
			(xy 71.058263 -150.032655) (xy 71.101896 -150.065311) (xy 71.140438 -150.103845) (xy 71.173103 -150.147472)
			(xy 71.199226 -150.195303) (xy 71.218276 -150.246366) (xy 71.229864 -150.299621) (xy 71.233755 -150.353982)
			(xy 71.229869 -150.408344) (xy 71.218286 -150.461599) (xy 71.199241 -150.512664) (xy 71.173122 -150.560498)
			(xy 71.140462 -150.604128) (xy 71.101924 -150.642665) (xy 71.058293 -150.675326) (xy 71.010459 -150.701444)
			(xy 70.959394 -150.720488) (xy 70.906138 -150.73207) (xy 70.851776 -150.735955) (xy 70.797415 -150.732063)
			(xy 70.744161 -150.720474) (xy 70.693098 -150.701424) (xy 70.645267 -150.6753) (xy 70.623176 -150.659338)
			(xy 70.604164 -150.645742) (xy 70.562281 -150.62501) (xy 70.517313 -150.612284) (xy 70.470776 -150.607994)
			(xy 70.424239 -150.612284) (xy 70.379271 -150.62501) (xy 70.337388 -150.645742) (xy 70.318376 -150.659338)
			(xy 70.29626 -150.675255) (xy 70.248438 -150.701368) (xy 70.197387 -150.72041) (xy 70.144145 -150.731991)
			(xy 70.089796 -150.735878) (xy 70.035448 -150.73199) (xy 69.982207 -150.720408) (xy 69.931155 -150.701365)
			(xy 69.883334 -150.675252) (xy 69.839715 -150.642598) (xy 69.801188 -150.604068) (xy 69.768537 -150.560448)
			(xy 69.742426 -150.512625) (xy 69.723386 -150.461573) (xy 69.711806 -150.40833) (xy 69.707922 -150.353982)
			(xy 68.242162 -150.353982) (xy 68.238276 -150.408345) (xy 68.226693 -150.461602) (xy 68.207647 -150.512668)
			(xy 68.181527 -150.560504) (xy 68.148865 -150.604135) (xy 68.110326 -150.642673) (xy 68.066693 -150.675334)
			(xy 68.018857 -150.701452) (xy 67.96779 -150.720496) (xy 67.914533 -150.732078) (xy 67.860169 -150.735962)
			(xy 67.805807 -150.732069) (xy 67.752551 -150.720479) (xy 67.701487 -150.701427) (xy 67.653655 -150.675301)
			(xy 67.631564 -150.659338) (xy 67.612552 -150.645742) (xy 67.570669 -150.62501) (xy 67.525701 -150.612284)
			(xy 67.479164 -150.607994) (xy 67.432627 -150.612284) (xy 67.387659 -150.62501) (xy 67.345776 -150.645742)
			(xy 67.326764 -150.659338) (xy 67.304649 -150.675254) (xy 67.256827 -150.701365) (xy 67.205777 -150.720405)
			(xy 67.152536 -150.731985) (xy 67.09819 -150.735871) (xy 67.043843 -150.731982) (xy 66.990603 -150.720399)
			(xy 66.939554 -150.701357) (xy 66.891734 -150.675243) (xy 66.848117 -150.64259) (xy 66.809592 -150.604061)
			(xy 66.776941 -150.560442) (xy 66.750831 -150.51262) (xy 66.731793 -150.46157) (xy 66.720214 -150.408329)
			(xy 66.716329 -150.353982) (xy 29.831396 -150.353982) (xy 29.842952 -150.386116) (xy 29.864689 -150.424256)
			(xy 29.89266 -150.458091) (xy 29.926031 -150.486613) (xy 29.96381 -150.508972) (xy 30.00487 -150.524503)
			(xy 30.047989 -150.532744) (xy 30.091883 -150.533448) (xy 30.135244 -150.526594) (xy 30.15615 -150.519892)
			(xy 30.19755 -150.506292) (xy 30.282281 -150.485913) (xy 30.368534 -150.47346) (xy 30.45557 -150.469042)
			(xy 30.542641 -150.472696) (xy 30.629 -150.48439) (xy 30.713907 -150.504025) (xy 30.796633 -150.531432)
			(xy 30.876468 -150.566375) (xy 30.952728 -150.608555) (xy 31.024757 -150.65761) (xy 31.091939 -150.713119)
			(xy 31.153697 -150.774606) (xy 31.209501 -150.841544) (xy 31.258872 -150.913357) (xy 31.301386 -150.989431)
			(xy 31.33668 -151.069112) (xy 31.36445 -151.151717) (xy 31.384457 -151.236536) (xy 31.396531 -151.322843)
			(xy 31.400567 -151.409897) (xy 31.398552 -151.453358) (xy 34.599874 -151.453358) (xy 34.599874 -151.366458)
			(xy 34.607892 -151.279929) (xy 34.62386 -151.194509) (xy 34.647641 -151.110927) (xy 34.679033 -151.029895)
			(xy 34.717767 -150.952106) (xy 34.763514 -150.878222) (xy 34.815883 -150.808875) (xy 34.874427 -150.744655)
			(xy 34.938647 -150.686111) (xy 35.007994 -150.633742) (xy 35.081878 -150.587995) (xy 35.159667 -150.549261)
			(xy 35.240699 -150.517869) (xy 35.324281 -150.494088) (xy 35.409701 -150.47812) (xy 35.49623 -150.470102)
			(xy 35.58313 -150.470102) (xy 35.669659 -150.47812) (xy 35.755079 -150.494088) (xy 35.838661 -150.517869)
			(xy 35.919693 -150.549261) (xy 35.997482 -150.587995) (xy 36.071366 -150.633742) (xy 36.140713 -150.686111)
			(xy 36.204933 -150.744655) (xy 36.263477 -150.808875) (xy 36.315846 -150.878222) (xy 36.361593 -150.952106)
			(xy 36.400327 -151.029895) (xy 36.427103 -151.099012) (xy 51.667664 -151.099012) (xy 53.31968 -151.099012)
			(xy 53.31968 -152.725583) (xy 66.716327 -152.725583) (xy 66.720217 -152.671237) (xy 66.731801 -152.617997)
			(xy 66.750844 -152.566947) (xy 66.776959 -152.519128) (xy 66.809613 -152.475511) (xy 66.848142 -152.436986)
			(xy 66.891762 -152.404337) (xy 66.939585 -152.378227) (xy 66.990636 -152.35919) (xy 67.043877 -152.347611)
			(xy 67.098224 -152.343727) (xy 67.152571 -152.347618) (xy 67.205811 -152.359203) (xy 67.25686 -152.378248)
			(xy 67.304679 -152.404363) (xy 67.326764 -152.42032) (xy 67.345776 -152.433916) (xy 67.387659 -152.454648)
			(xy 67.432627 -152.467374) (xy 67.479164 -152.471664) (xy 67.525701 -152.467374) (xy 67.570669 -152.454648)
			(xy 67.612552 -152.433916) (xy 67.631564 -152.42032) (xy 67.653627 -152.404319) (xy 67.701456 -152.378189)
			(xy 67.752518 -152.359132) (xy 67.805772 -152.347537) (xy 67.860135 -152.343639) (xy 67.914498 -152.347519)
			(xy 67.967756 -152.359096) (xy 68.018825 -152.378135) (xy 68.066663 -152.404249) (xy 68.110298 -152.436905)
			(xy 68.148841 -152.47544) (xy 68.181507 -152.519068) (xy 68.207631 -152.566901) (xy 68.226681 -152.617965)
			(xy 68.23827 -152.67122) (xy 68.242161 -152.725583) (xy 69.70792 -152.725583) (xy 69.71181 -152.671235)
			(xy 69.723395 -152.617993) (xy 69.742439 -152.566943) (xy 69.768554 -152.519122) (xy 69.80121 -152.475504)
			(xy 69.839741 -152.436978) (xy 69.883362 -152.404328) (xy 69.931186 -152.378219) (xy 69.982239 -152.359181)
			(xy 70.035482 -152.347603) (xy 70.089831 -152.34372) (xy 70.144179 -152.347612) (xy 70.19742 -152.359199)
			(xy 70.248471 -152.378245) (xy 70.29629 -152.404362) (xy 70.318376 -152.42032) (xy 70.337388 -152.433916)
			(xy 70.379271 -152.454648) (xy 70.424239 -152.467374) (xy 70.470776 -152.471664) (xy 70.517313 -152.467374)
			(xy 70.562281 -152.454648) (xy 70.604164 -152.433916) (xy 70.623176 -152.42032) (xy 70.645238 -152.40432)
			(xy 70.693067 -152.378192) (xy 70.744128 -152.359137) (xy 70.797381 -152.347543) (xy 70.851741 -152.343647)
			(xy 70.906103 -152.347527) (xy 70.95936 -152.359104) (xy 71.010426 -152.378143) (xy 71.058263 -152.404257)
			(xy 71.101896 -152.436913) (xy 71.140438 -152.475447) (xy 71.173102 -152.519074) (xy 71.199225 -152.566905)
			(xy 71.218275 -152.617968) (xy 71.229863 -152.671222) (xy 71.233753 -152.725583) (xy 71.229867 -152.779945)
			(xy 71.218284 -152.8332) (xy 71.199239 -152.884264) (xy 71.17312 -152.932098) (xy 71.14046 -152.975728)
			(xy 71.101922 -153.014265) (xy 71.058291 -153.046925) (xy 71.010457 -153.073043) (xy 70.959392 -153.092086)
			(xy 70.906137 -153.103669) (xy 70.851775 -153.107553) (xy 70.797414 -153.103662) (xy 70.74416 -153.092072)
			(xy 70.693098 -153.073022) (xy 70.645267 -153.046898) (xy 70.623176 -153.030936) (xy 70.604164 -153.01734)
			(xy 70.562281 -152.996608) (xy 70.517313 -152.983882) (xy 70.470776 -152.979592) (xy 70.424239 -152.983882)
			(xy 70.379271 -152.996608) (xy 70.337388 -153.01734) (xy 70.318376 -153.030936) (xy 70.296262 -153.046856)
			(xy 70.24844 -153.072969) (xy 70.197388 -153.092011) (xy 70.144146 -153.103593) (xy 70.089798 -153.10748)
			(xy 70.035449 -153.103592) (xy 69.982207 -153.092009) (xy 69.931156 -153.072967) (xy 69.883334 -153.046854)
			(xy 69.839715 -153.0142) (xy 69.801188 -152.97567) (xy 69.768536 -152.93205) (xy 69.742425 -152.884227)
			(xy 69.723385 -152.833174) (xy 69.711805 -152.779932) (xy 69.70792 -152.725583) (xy 68.242161 -152.725583)
			(xy 68.238274 -152.779946) (xy 68.226691 -152.833203) (xy 68.207645 -152.884269) (xy 68.181525 -152.932104)
			(xy 68.148863 -152.975735) (xy 68.110324 -153.014273) (xy 68.066692 -153.046933) (xy 68.018855 -153.073051)
			(xy 67.967789 -153.092095) (xy 67.914532 -153.103677) (xy 67.860168 -153.107561) (xy 67.805806 -153.103668)
			(xy 67.75255 -153.092077) (xy 67.701487 -153.073025) (xy 67.653655 -153.046899) (xy 67.631564 -153.030936)
			(xy 67.612552 -153.01734) (xy 67.570669 -152.996608) (xy 67.525701 -152.983882) (xy 67.479164 -152.979592)
			(xy 67.432627 -152.983882) (xy 67.387659 -152.996608) (xy 67.345776 -153.01734) (xy 67.326764 -153.030936)
			(xy 67.30465 -153.046855) (xy 67.256829 -153.072966) (xy 67.205778 -153.092006) (xy 67.152538 -153.103587)
			(xy 67.098191 -153.107473) (xy 67.043844 -153.103584) (xy 66.990604 -153.092001) (xy 66.939554 -153.072959)
			(xy 66.891734 -153.046845) (xy 66.848117 -153.014192) (xy 66.809591 -152.975663) (xy 66.776941 -152.932044)
			(xy 66.75083 -152.884222) (xy 66.731792 -152.833171) (xy 66.720212 -152.77993) (xy 66.716327 -152.725583)
			(xy 53.31968 -152.725583) (xy 53.31968 -152.751028) (xy 51.667664 -152.751028) (xy 51.667664 -151.099012)
			(xy 36.427103 -151.099012) (xy 36.431719 -151.110927) (xy 36.4555 -151.194509) (xy 36.471468 -151.279929)
			(xy 36.479486 -151.366458) (xy 36.479988 -151.409908) (xy 36.479486 -151.453358) (xy 36.471468 -151.539887)
			(xy 36.4555 -151.625307) (xy 36.431719 -151.708889) (xy 36.400327 -151.789921) (xy 36.361593 -151.86771)
			(xy 36.315846 -151.941594) (xy 36.297736 -151.965575) (xy 48.168042 -151.965575) (xy 48.168042 -151.884465)
			(xy 48.175992 -151.803746) (xy 48.191815 -151.724195) (xy 48.21536 -151.646579) (xy 48.246399 -151.571643)
			(xy 48.284634 -151.500111) (xy 48.329696 -151.432671) (xy 48.381151 -151.369972) (xy 48.438504 -151.312619)
			(xy 48.501203 -151.261164) (xy 48.568643 -151.216102) (xy 48.640175 -151.177867) (xy 48.715111 -151.146828)
			(xy 48.792727 -151.123283) (xy 48.872278 -151.10746) (xy 48.952997 -151.09951) (xy 49.034107 -151.09951)
			(xy 49.114826 -151.10746) (xy 49.194377 -151.123283) (xy 49.271993 -151.146828) (xy 49.346929 -151.177867)
			(xy 49.418461 -151.216102) (xy 49.485901 -151.261164) (xy 49.5486 -151.312619) (xy 49.605953 -151.369972)
			(xy 49.657408 -151.432671) (xy 49.70247 -151.500111) (xy 49.740705 -151.571643) (xy 49.771744 -151.646579)
			(xy 49.795289 -151.724195) (xy 49.811112 -151.803746) (xy 49.819062 -151.884465) (xy 49.81956 -151.92502)
			(xy 49.819062 -151.965575) (xy 49.811112 -152.046294) (xy 49.795289 -152.125845) (xy 49.771744 -152.203461)
			(xy 49.740705 -152.278397) (xy 49.70247 -152.349929) (xy 49.657408 -152.417369) (xy 49.605953 -152.480068)
			(xy 49.5486 -152.537421) (xy 49.485901 -152.588876) (xy 49.418461 -152.633938) (xy 49.346929 -152.672173)
			(xy 49.271993 -152.703212) (xy 49.194377 -152.726757) (xy 49.114826 -152.74258) (xy 49.034107 -152.75053)
			(xy 48.952997 -152.75053) (xy 48.872278 -152.74258) (xy 48.792727 -152.726757) (xy 48.715111 -152.703212)
			(xy 48.640175 -152.672173) (xy 48.568643 -152.633938) (xy 48.501203 -152.588876) (xy 48.438504 -152.537421)
			(xy 48.381151 -152.480068) (xy 48.329696 -152.417369) (xy 48.284634 -152.349929) (xy 48.246399 -152.278397)
			(xy 48.21536 -152.203461) (xy 48.191815 -152.125845) (xy 48.175992 -152.046294) (xy 48.168042 -151.965575)
			(xy 36.297736 -151.965575) (xy 36.263477 -152.010941) (xy 36.204933 -152.075161) (xy 36.140713 -152.133705)
			(xy 36.071366 -152.186074) (xy 35.997482 -152.231821) (xy 35.919693 -152.270555) (xy 35.838661 -152.301947)
			(xy 35.755079 -152.325728) (xy 35.669659 -152.341696) (xy 35.58313 -152.349714) (xy 35.49623 -152.349714)
			(xy 35.409701 -152.341696) (xy 35.324281 -152.325728) (xy 35.240699 -152.301947) (xy 35.159667 -152.270555)
			(xy 35.081878 -152.231821) (xy 35.007994 -152.186074) (xy 34.938647 -152.133705) (xy 34.874427 -152.075161)
			(xy 34.815883 -152.010941) (xy 34.763514 -151.941594) (xy 34.717767 -151.86771) (xy 34.679033 -151.789921)
			(xy 34.647641 -151.708889) (xy 34.62386 -151.625307) (xy 34.607892 -151.539887) (xy 34.599874 -151.453358)
			(xy 31.398552 -151.453358) (xy 31.396531 -151.496951) (xy 31.384458 -151.583259) (xy 31.364451 -151.668078)
			(xy 31.336682 -151.750683) (xy 31.301389 -151.830365) (xy 31.258875 -151.906438) (xy 31.209504 -151.978252)
			(xy 31.153701 -152.04519) (xy 31.091943 -152.106678) (xy 31.024762 -152.162187) (xy 30.952732 -152.211243)
			(xy 30.876473 -152.253423) (xy 30.796638 -152.288367) (xy 30.713912 -152.315773) (xy 30.629005 -152.335409)
			(xy 30.542646 -152.347103) (xy 30.455575 -152.350758) (xy 30.368539 -152.34634) (xy 30.282286 -152.333888)
			(xy 30.197555 -152.31351) (xy 30.15615 -152.299924) (xy 30.135234 -152.293273) (xy 30.091882 -152.286443)
			(xy 30.048002 -152.287163) (xy 30.004897 -152.295411) (xy 29.963851 -152.310943) (xy 29.926084 -152.333296)
			(xy 29.892719 -152.361805) (xy 29.864748 -152.395623) (xy 29.843004 -152.433744) (xy 29.828133 -152.475034)
			(xy 29.820577 -152.518265) (xy 29.820108 -152.540208) (xy 29.820108 -152.819608) (xy 29.820564 -152.841558)
			(xy 29.828096 -152.884806) (xy 29.842952 -152.926116) (xy 29.864689 -152.964256) (xy 29.89266 -152.998091)
			(xy 29.926031 -153.026613) (xy 29.96381 -153.048972) (xy 30.00487 -153.064503) (xy 30.047989 -153.072744)
			(xy 30.091883 -153.073448) (xy 30.135244 -153.066594) (xy 30.15615 -153.059892) (xy 30.19755 -153.046292)
			(xy 30.282281 -153.025913) (xy 30.368534 -153.01346) (xy 30.45557 -153.009042) (xy 30.542641 -153.012696)
			(xy 30.629 -153.02439) (xy 30.713907 -153.044025) (xy 30.796633 -153.071432) (xy 30.876468 -153.106375)
			(xy 30.952728 -153.148555) (xy 31.024757 -153.19761) (xy 31.091939 -153.253119) (xy 31.153697 -153.314606)
			(xy 31.209501 -153.381544) (xy 31.258872 -153.453357) (xy 31.301386 -153.529431) (xy 31.33668 -153.609112)
			(xy 31.36445 -153.691717) (xy 31.384457 -153.776536) (xy 31.396531 -153.862843) (xy 31.400567 -153.949897)
			(xy 31.398552 -153.993358) (xy 34.599874 -153.993358) (xy 34.599874 -153.906458) (xy 34.607892 -153.819929)
			(xy 34.62386 -153.734509) (xy 34.647641 -153.650927) (xy 34.679033 -153.569895) (xy 34.717767 -153.492106)
			(xy 34.763514 -153.418222) (xy 34.815883 -153.348875) (xy 34.874427 -153.284655) (xy 34.938647 -153.226111)
			(xy 35.007994 -153.173742) (xy 35.081878 -153.127995) (xy 35.159667 -153.089261) (xy 35.240699 -153.057869)
			(xy 35.324281 -153.034088) (xy 35.409701 -153.01812) (xy 35.49623 -153.010102) (xy 35.58313 -153.010102)
			(xy 35.669659 -153.01812) (xy 35.755079 -153.034088) (xy 35.838661 -153.057869) (xy 35.919693 -153.089261)
			(xy 35.997482 -153.127995) (xy 36.071366 -153.173742) (xy 36.140713 -153.226111) (xy 36.204933 -153.284655)
			(xy 36.263477 -153.348875) (xy 36.315846 -153.418222) (xy 36.361593 -153.492106) (xy 36.400327 -153.569895)
			(xy 36.416745 -153.612275) (xy 39.565224 -153.612275) (xy 39.569115 -153.557927) (xy 39.580701 -153.504685)
			(xy 39.599747 -153.453635) (xy 39.625864 -153.405815) (xy 39.65852 -153.362198) (xy 39.697052 -153.323674)
			(xy 39.740675 -153.291025) (xy 39.7885 -153.264917) (xy 39.839554 -153.245881) (xy 39.892797 -153.234305)
			(xy 39.947146 -153.230424) (xy 40.001494 -153.234318) (xy 40.054735 -153.245907) (xy 40.105784 -153.264955)
			(xy 40.153603 -153.291075) (xy 40.175688 -153.307034) (xy 40.1947 -153.32063) (xy 40.236583 -153.341362)
			(xy 40.281551 -153.354088) (xy 40.328088 -153.358378) (xy 40.374625 -153.354088) (xy 40.419593 -153.341362)
			(xy 40.461476 -153.32063) (xy 40.480488 -153.307034) (xy 40.502537 -153.291016) (xy 40.550366 -153.264888)
			(xy 40.601426 -153.245833) (xy 40.654679 -153.234239) (xy 40.70904 -153.230343) (xy 40.763402 -153.234222)
			(xy 40.816658 -153.245799) (xy 40.867725 -153.264838) (xy 40.915562 -153.290951) (xy 40.959195 -153.323607)
			(xy 40.997737 -153.36214) (xy 41.030402 -153.405766) (xy 41.056526 -153.453598) (xy 41.075576 -153.50466)
			(xy 41.087166 -153.557914) (xy 41.091057 -153.612275) (xy 41.087173 -153.666636) (xy 41.075591 -153.719892)
			(xy 41.056547 -153.770957) (xy 41.03043 -153.818791) (xy 40.99777 -153.862422) (xy 40.959234 -153.90096)
			(xy 40.915604 -153.933621) (xy 40.867771 -153.959741) (xy 40.816707 -153.978786) (xy 40.763452 -153.99037)
			(xy 40.70909 -153.994257) (xy 40.654729 -153.990368) (xy 40.601475 -153.978781) (xy 40.550412 -153.959733)
			(xy 40.502579 -153.933611) (xy 40.480488 -153.91765) (xy 40.461476 -153.904054) (xy 40.419593 -153.883322)
			(xy 40.374625 -153.870596) (xy 40.328088 -153.866306) (xy 40.281551 -153.870596) (xy 40.236583 -153.883322)
			(xy 40.1947 -153.904054) (xy 40.175688 -153.91765) (xy 40.153561 -153.933552) (xy 40.105739 -153.959666)
			(xy 40.054687 -153.978707) (xy 40.001445 -153.990289) (xy 39.947096 -153.994176) (xy 39.892748 -153.990288)
			(xy 39.839506 -153.978705) (xy 39.788454 -153.959662) (xy 39.740633 -153.933548) (xy 39.697014 -153.900893)
			(xy 39.658487 -153.862364) (xy 39.625836 -153.818743) (xy 39.599726 -153.770919) (xy 39.580687 -153.719866)
			(xy 39.569108 -153.666624) (xy 39.565224 -153.612275) (xy 36.416745 -153.612275) (xy 36.431719 -153.650927)
			(xy 36.4555 -153.734509) (xy 36.471468 -153.819929) (xy 36.479486 -153.906458) (xy 36.479988 -153.949908)
			(xy 36.479486 -153.993358) (xy 36.471468 -154.079887) (xy 36.4555 -154.165307) (xy 36.431719 -154.248889)
			(xy 36.400327 -154.329921) (xy 36.361593 -154.40771) (xy 36.315846 -154.481594) (xy 36.263477 -154.550941)
			(xy 36.204933 -154.615161) (xy 36.140713 -154.673705) (xy 36.121153 -154.688476) (xy 66.716337 -154.688476)
			(xy 66.720227 -154.634131) (xy 66.731812 -154.580892) (xy 66.750856 -154.529845) (xy 66.776971 -154.482027)
			(xy 66.809625 -154.438412) (xy 66.848154 -154.399889) (xy 66.891774 -154.367241) (xy 66.939595 -154.341133)
			(xy 66.990646 -154.322097) (xy 67.043886 -154.310519) (xy 67.098232 -154.306637) (xy 67.152577 -154.310528)
			(xy 67.205815 -154.322114) (xy 67.256862 -154.341159) (xy 67.30468 -154.367275) (xy 67.326764 -154.383232)
			(xy 67.345776 -154.396828) (xy 67.387659 -154.41756) (xy 67.432627 -154.430286) (xy 67.479164 -154.434576)
			(xy 67.525701 -154.430286) (xy 67.570669 -154.41756) (xy 67.612552 -154.396828) (xy 67.631564 -154.383232)
			(xy 67.653616 -154.367215) (xy 67.701446 -154.341083) (xy 67.752509 -154.322025) (xy 67.805764 -154.310429)
			(xy 67.860127 -154.30653) (xy 67.914493 -154.310408) (xy 67.967752 -154.321984) (xy 68.018822 -154.341023)
			(xy 68.066662 -154.367137) (xy 68.110299 -154.399793) (xy 68.148844 -154.438328) (xy 68.181511 -154.481956)
			(xy 68.207637 -154.52979) (xy 68.226688 -154.580855) (xy 68.238278 -154.634112) (xy 68.24217 -154.688476)
			(xy 69.70793 -154.688476) (xy 69.71182 -154.634129) (xy 69.723406 -154.580889) (xy 69.74245 -154.52984)
			(xy 69.768566 -154.482021) (xy 69.801222 -154.438405) (xy 69.839752 -154.399881) (xy 69.883373 -154.367232)
			(xy 69.931197 -154.341124) (xy 69.982249 -154.322088) (xy 70.035491 -154.310511) (xy 70.089838 -154.30663)
			(xy 70.144185 -154.310522) (xy 70.197425 -154.32211) (xy 70.248473 -154.341156) (xy 70.296291 -154.367274)
			(xy 70.318376 -154.383232) (xy 70.337388 -154.396828) (xy 70.379271 -154.41756) (xy 70.424239 -154.430286)
			(xy 70.470776 -154.434576) (xy 70.517313 -154.430286) (xy 70.562281 -154.41756) (xy 70.604164 -154.396828)
			(xy 70.623176 -154.383232) (xy 70.645227 -154.367216) (xy 70.693057 -154.341086) (xy 70.744118 -154.32203)
			(xy 70.797372 -154.310435) (xy 70.851734 -154.306537) (xy 70.906098 -154.310416) (xy 70.959356 -154.321993)
			(xy 71.010424 -154.341032) (xy 71.058262 -154.367145) (xy 71.101897 -154.399801) (xy 71.14044 -154.438335)
			(xy 71.173106 -154.481962) (xy 71.199231 -154.529795) (xy 71.218282 -154.580858) (xy 71.229871 -154.634113)
			(xy 71.233763 -154.688476) (xy 71.229878 -154.742839) (xy 71.218295 -154.796096) (xy 71.199251 -154.847162)
			(xy 71.173132 -154.894997) (xy 71.140472 -154.938629) (xy 71.101933 -154.977167) (xy 71.058303 -155.009829)
			(xy 71.010467 -155.035948) (xy 70.959402 -155.054994) (xy 70.906145 -155.066577) (xy 70.851782 -155.070463)
			(xy 70.79742 -155.066572) (xy 70.744164 -155.054984) (xy 70.6931 -155.035934) (xy 70.645268 -155.00981)
			(xy 70.623176 -154.993848) (xy 70.604164 -154.980252) (xy 70.562281 -154.95952) (xy 70.517313 -154.946794)
			(xy 70.470776 -154.942504) (xy 70.424239 -154.946794) (xy 70.379271 -154.95952) (xy 70.337388 -154.980252)
			(xy 70.318376 -154.993848) (xy 70.296251 -155.009752) (xy 70.248429 -155.035864) (xy 70.197379 -155.054904)
			(xy 70.144138 -155.066484) (xy 70.08979 -155.07037) (xy 70.035443 -155.066482) (xy 69.982203 -155.054898)
			(xy 69.931153 -155.035856) (xy 69.883333 -155.009742) (xy 69.839716 -154.977088) (xy 69.80119 -154.938559)
			(xy 69.76854 -154.894939) (xy 69.74243 -154.847116) (xy 69.723392 -154.796065) (xy 69.711814 -154.742823)
			(xy 69.70793 -154.688476) (xy 68.24217 -154.688476) (xy 68.238285 -154.742841) (xy 68.226702 -154.796099)
			(xy 68.207657 -154.847166) (xy 68.181537 -154.895003) (xy 68.148875 -154.938636) (xy 68.110335 -154.977175)
			(xy 68.066703 -155.009837) (xy 68.018866 -155.035957) (xy 67.967798 -155.055002) (xy 67.91454 -155.066585)
			(xy 67.860175 -155.07047) (xy 67.805811 -155.066578) (xy 67.752555 -155.054988) (xy 67.70149 -155.035937)
			(xy 67.653656 -155.009811) (xy 67.631564 -154.993848) (xy 67.612552 -154.980252) (xy 67.570669 -154.95952)
			(xy 67.525701 -154.946794) (xy 67.479164 -154.942504) (xy 67.432627 -154.946794) (xy 67.387659 -154.95952)
			(xy 67.345776 -154.980252) (xy 67.326764 -154.993848) (xy 67.304639 -155.009751) (xy 67.256819 -155.035861)
			(xy 67.205769 -155.054899) (xy 67.152529 -155.066478) (xy 67.098184 -155.070363) (xy 67.043838 -155.066474)
			(xy 66.9906 -155.05489) (xy 66.939552 -155.035847) (xy 66.891733 -155.009733) (xy 66.848118 -154.97708)
			(xy 66.809594 -154.938551) (xy 66.776945 -154.894933) (xy 66.750836 -154.847112) (xy 66.731799 -154.796062)
			(xy 66.720221 -154.742822) (xy 66.716337 -154.688476) (xy 36.121153 -154.688476) (xy 36.071366 -154.726074)
			(xy 35.997482 -154.771821) (xy 35.919693 -154.810555) (xy 35.838661 -154.841947) (xy 35.755079 -154.865728)
			(xy 35.669659 -154.881696) (xy 35.58313 -154.889714) (xy 35.49623 -154.889714) (xy 35.409701 -154.881696)
			(xy 35.324281 -154.865728) (xy 35.240699 -154.841947) (xy 35.159667 -154.810555) (xy 35.081878 -154.771821)
			(xy 35.007994 -154.726074) (xy 34.938647 -154.673705) (xy 34.874427 -154.615161) (xy 34.815883 -154.550941)
			(xy 34.763514 -154.481594) (xy 34.717767 -154.40771) (xy 34.679033 -154.329921) (xy 34.647641 -154.248889)
			(xy 34.62386 -154.165307) (xy 34.607892 -154.079887) (xy 34.599874 -153.993358) (xy 31.398552 -153.993358)
			(xy 31.396531 -154.036951) (xy 31.384458 -154.123259) (xy 31.364451 -154.208078) (xy 31.336682 -154.290683)
			(xy 31.301389 -154.370365) (xy 31.258875 -154.446438) (xy 31.209504 -154.518252) (xy 31.153701 -154.58519)
			(xy 31.091943 -154.646678) (xy 31.024762 -154.702187) (xy 30.952732 -154.751243) (xy 30.876473 -154.793423)
			(xy 30.796638 -154.828367) (xy 30.713912 -154.855773) (xy 30.629005 -154.875409) (xy 30.542646 -154.887103)
			(xy 30.455575 -154.890758) (xy 30.368539 -154.88634) (xy 30.282286 -154.873888) (xy 30.197555 -154.85351)
			(xy 30.15615 -154.839924) (xy 30.135234 -154.833273) (xy 30.091882 -154.826443) (xy 30.048002 -154.827163)
			(xy 30.004897 -154.835411) (xy 29.963851 -154.850943) (xy 29.926084 -154.873296) (xy 29.892719 -154.901805)
			(xy 29.864748 -154.935623) (xy 29.843004 -154.973744) (xy 29.828133 -155.015034) (xy 29.820577 -155.058265)
			(xy 29.820108 -155.080208) (xy 29.820108 -155.359608) (xy 29.820564 -155.381558) (xy 29.828096 -155.424806)
			(xy 29.842952 -155.466116) (xy 29.864689 -155.504256) (xy 29.89266 -155.538091) (xy 29.926031 -155.566613)
			(xy 29.96381 -155.588972) (xy 30.00487 -155.604503) (xy 30.047989 -155.612744) (xy 30.091883 -155.613448)
			(xy 30.135244 -155.606594) (xy 30.15615 -155.599892) (xy 30.19755 -155.586292) (xy 30.282281 -155.565913)
			(xy 30.368534 -155.55346) (xy 30.45557 -155.549042) (xy 30.542641 -155.552696) (xy 30.629 -155.56439)
			(xy 30.713907 -155.584025) (xy 30.796633 -155.611432) (xy 30.876468 -155.646375) (xy 30.952728 -155.688555)
			(xy 31.024757 -155.73761) (xy 31.091939 -155.793119) (xy 31.153697 -155.854606) (xy 31.209501 -155.921544)
			(xy 31.258872 -155.993357) (xy 31.301386 -156.069431) (xy 31.33668 -156.149112) (xy 31.36445 -156.231717)
			(xy 31.384457 -156.316536) (xy 31.396531 -156.402843) (xy 31.400567 -156.489897) (xy 31.398552 -156.533358)
			(xy 34.599874 -156.533358) (xy 34.599874 -156.446458) (xy 34.607892 -156.359929) (xy 34.62386 -156.274509)
			(xy 34.647641 -156.190927) (xy 34.679033 -156.109895) (xy 34.717767 -156.032106) (xy 34.763514 -155.958222)
			(xy 34.815883 -155.888875) (xy 34.874427 -155.824655) (xy 34.938647 -155.766111) (xy 35.007994 -155.713742)
			(xy 35.081878 -155.667995) (xy 35.159667 -155.629261) (xy 35.240699 -155.597869) (xy 35.324281 -155.574088)
			(xy 35.409701 -155.55812) (xy 35.49623 -155.550102) (xy 35.58313 -155.550102) (xy 35.669659 -155.55812)
			(xy 35.755079 -155.574088) (xy 35.838661 -155.597869) (xy 35.919693 -155.629261) (xy 35.997482 -155.667995)
			(xy 36.071366 -155.713742) (xy 36.140713 -155.766111) (xy 36.204933 -155.824655) (xy 36.226034 -155.847802)
			(xy 39.565187 -155.847802) (xy 39.569075 -155.793449) (xy 39.580658 -155.740201) (xy 39.599702 -155.689145)
			(xy 39.625818 -155.641318) (xy 39.658475 -155.597695) (xy 39.697007 -155.559164) (xy 39.740632 -155.526509)
			(xy 39.78846 -155.500395) (xy 39.839517 -155.481353) (xy 39.892765 -155.469772) (xy 39.947119 -155.465887)
			(xy 40.001472 -155.469778) (xy 40.054719 -155.481364) (xy 40.105775 -155.50041) (xy 40.1536 -155.526529)
			(xy 40.175688 -155.542488) (xy 40.1947 -155.556084) (xy 40.236583 -155.576816) (xy 40.281551 -155.589542)
			(xy 40.328088 -155.593832) (xy 40.374625 -155.589542) (xy 40.419593 -155.576816) (xy 40.461476 -155.556084)
			(xy 40.480488 -155.542488) (xy 40.50258 -155.526532) (xy 40.550406 -155.50041) (xy 40.601463 -155.481361)
			(xy 40.654712 -155.469772) (xy 40.709068 -155.465879) (xy 40.763424 -155.469763) (xy 40.816674 -155.481343)
			(xy 40.867735 -155.500383) (xy 40.915565 -155.526497) (xy 40.959192 -155.559153) (xy 40.997727 -155.597685)
			(xy 41.030386 -155.64131) (xy 41.056504 -155.689138) (xy 41.075549 -155.740197) (xy 41.087133 -155.793446)
			(xy 41.091021 -155.847802) (xy 41.087132 -155.902158) (xy 41.075548 -155.955408) (xy 41.056502 -156.006466)
			(xy 41.030384 -156.054295) (xy 40.997724 -156.097919) (xy 40.959189 -156.13645) (xy 40.915561 -156.169105)
			(xy 40.86773 -156.195219) (xy 40.81667 -156.214259) (xy 40.763419 -156.225838) (xy 40.709063 -156.229721)
			(xy 40.654707 -156.225827) (xy 40.601459 -156.214238) (xy 40.550402 -156.195188) (xy 40.502576 -156.169065)
			(xy 40.480488 -156.153104) (xy 40.461476 -156.139508) (xy 40.419593 -156.118776) (xy 40.374625 -156.10605)
			(xy 40.328088 -156.10176) (xy 40.281551 -156.10605) (xy 40.236583 -156.118776) (xy 40.1947 -156.139508)
			(xy 40.175688 -156.153104) (xy 40.153604 -156.169068) (xy 40.105779 -156.195188) (xy 40.054724 -156.214235)
			(xy 40.001477 -156.225822) (xy 39.947124 -156.229713) (xy 39.89277 -156.225828) (xy 39.839522 -156.214248)
			(xy 39.788464 -156.195207) (xy 39.740636 -156.169094) (xy 39.697011 -156.136439) (xy 39.658478 -156.097909)
			(xy 39.62582 -156.054286) (xy 39.599704 -156.00646) (xy 39.580659 -155.955403) (xy 39.569075 -155.902156)
			(xy 39.565187 -155.847802) (xy 36.226034 -155.847802) (xy 36.263477 -155.888875) (xy 36.315846 -155.958222)
			(xy 36.361593 -156.032106) (xy 36.400327 -156.109895) (xy 36.431719 -156.190927) (xy 36.4555 -156.274509)
			(xy 36.471468 -156.359929) (xy 36.479486 -156.446458) (xy 36.479988 -156.489908) (xy 36.479486 -156.533358)
			(xy 36.471468 -156.619887) (xy 36.4555 -156.705307) (xy 36.431719 -156.788889) (xy 36.415029 -156.831972)
			(xy 66.716342 -156.831972) (xy 66.720233 -156.777628) (xy 66.731818 -156.72439) (xy 66.750862 -156.673343)
			(xy 66.776977 -156.625526) (xy 66.809631 -156.581913) (xy 66.84816 -156.54339) (xy 66.891779 -156.510743)
			(xy 66.939601 -156.484636) (xy 66.990651 -156.4656) (xy 67.04389 -156.454024) (xy 67.098235 -156.450142)
			(xy 67.15258 -156.454034) (xy 67.205817 -156.46562) (xy 67.256863 -156.484665) (xy 67.30468 -156.510781)
			(xy 67.326764 -156.526738) (xy 67.345776 -156.540334) (xy 67.387659 -156.561066) (xy 67.432627 -156.573792)
			(xy 67.479164 -156.578082) (xy 67.525701 -156.573792) (xy 67.570669 -156.561066) (xy 67.612552 -156.540334)
			(xy 67.631564 -156.526738) (xy 67.65361 -156.510713) (xy 67.701441 -156.484581) (xy 67.752504 -156.465522)
			(xy 67.80576 -156.453925) (xy 67.860124 -156.450025) (xy 67.91449 -156.453903) (xy 67.96775 -156.465479)
			(xy 68.018821 -156.484517) (xy 68.066662 -156.510631) (xy 68.1103 -156.543287) (xy 68.148845 -156.581822)
			(xy 68.181513 -156.625451) (xy 68.20764 -156.673285) (xy 68.226692 -156.72435) (xy 68.238282 -156.777608)
			(xy 68.242175 -156.831972) (xy 69.707935 -156.831972) (xy 69.711826 -156.777626) (xy 69.723411 -156.724387)
			(xy 69.742456 -156.673339) (xy 69.768572 -156.62552) (xy 69.801228 -156.581906) (xy 69.839758 -156.543382)
			(xy 69.883379 -156.510735) (xy 69.931202 -156.484627) (xy 69.982254 -156.465592) (xy 70.035495 -156.454016)
			(xy 70.089842 -156.450135) (xy 70.144188 -156.454028) (xy 70.197427 -156.465615) (xy 70.248474 -156.484662)
			(xy 70.296292 -156.51078) (xy 70.318376 -156.526738) (xy 70.337388 -156.540334) (xy 70.379271 -156.561066)
			(xy 70.424239 -156.573792) (xy 70.470776 -156.578082) (xy 70.517313 -156.573792) (xy 70.562281 -156.561066)
			(xy 70.604164 -156.540334) (xy 70.623176 -156.526738) (xy 70.645222 -156.510714) (xy 70.693051 -156.484583)
			(xy 70.744113 -156.465526) (xy 70.797368 -156.453931) (xy 70.851731 -156.450032) (xy 70.906095 -156.453911)
			(xy 70.959354 -156.465487) (xy 71.010422 -156.484526) (xy 71.058262 -156.510639) (xy 71.101898 -156.543295)
			(xy 71.140441 -156.581829) (xy 71.173109 -156.625457) (xy 71.199234 -156.673289) (xy 71.218285 -156.724353)
			(xy 71.229875 -156.777609) (xy 71.233768 -156.831972) (xy 71.229883 -156.886336) (xy 71.218301 -156.939594)
			(xy 71.199257 -156.99066) (xy 71.173138 -157.038497) (xy 71.140478 -157.082129) (xy 71.101939 -157.120669)
			(xy 71.058308 -157.153331) (xy 71.010473 -157.179451) (xy 70.959407 -157.198497) (xy 70.906149 -157.210081)
			(xy 70.851786 -157.213968) (xy 70.797423 -157.210077) (xy 70.744166 -157.198489) (xy 70.693102 -157.179439)
			(xy 70.645268 -157.153316) (xy 70.623176 -157.137354) (xy 70.604164 -157.123758) (xy 70.562281 -157.103026)
			(xy 70.517313 -157.0903) (xy 70.470776 -157.08601) (xy 70.424239 -157.0903) (xy 70.379271 -157.103026)
			(xy 70.337388 -157.123758) (xy 70.318376 -157.137354) (xy 70.296245 -157.15325) (xy 70.248424 -157.179361)
			(xy 70.197374 -157.1984) (xy 70.144133 -157.20998) (xy 70.089787 -157.213865) (xy 70.035441 -157.209976)
			(xy 69.982201 -157.198393) (xy 69.931152 -157.17935) (xy 69.883333 -157.153236) (xy 69.839716 -157.120582)
			(xy 69.801192 -157.082053) (xy 69.768542 -157.038433) (xy 69.742433 -156.990611) (xy 69.723396 -156.93956)
			(xy 69.711818 -156.886319) (xy 69.707935 -156.831972) (xy 68.242175 -156.831972) (xy 68.23829 -156.886338)
			(xy 68.226708 -156.939597) (xy 68.207663 -156.990665) (xy 68.181543 -157.038503) (xy 68.148881 -157.082136)
			(xy 68.110341 -157.120677) (xy 68.066708 -157.15334) (xy 68.018871 -157.17946) (xy 67.967803 -157.198506)
			(xy 67.914544 -157.210089) (xy 67.860179 -157.213975) (xy 67.805814 -157.210083) (xy 67.752557 -157.198494)
			(xy 67.701491 -157.179442) (xy 67.653656 -157.153317) (xy 67.631564 -157.137354) (xy 67.612552 -157.123758)
			(xy 67.570669 -157.103026) (xy 67.525701 -157.0903) (xy 67.479164 -157.08601) (xy 67.432627 -157.0903)
			(xy 67.387659 -157.103026) (xy 67.345776 -157.123758) (xy 67.326764 -157.137354) (xy 67.304634 -157.153249)
			(xy 67.256813 -157.179358) (xy 67.205764 -157.198395) (xy 67.152525 -157.209974) (xy 67.09818 -157.213858)
			(xy 67.043835 -157.209968) (xy 66.990598 -157.198384) (xy 66.93955 -157.179341) (xy 66.891733 -157.153227)
			(xy 66.848118 -157.120574) (xy 66.809595 -157.082046) (xy 66.776947 -157.038427) (xy 66.750839 -156.990606)
			(xy 66.731802 -156.939557) (xy 66.720225 -156.886317) (xy 66.716342 -156.831972) (xy 36.415029 -156.831972)
			(xy 36.400327 -156.869921) (xy 36.361593 -156.94771) (xy 36.315846 -157.021594) (xy 36.263477 -157.090941)
			(xy 36.204933 -157.155161) (xy 36.140713 -157.213705) (xy 36.071366 -157.266074) (xy 35.997482 -157.311821)
			(xy 35.919693 -157.350555) (xy 35.838661 -157.381947) (xy 35.755079 -157.405728) (xy 35.669659 -157.421696)
			(xy 35.58313 -157.429714) (xy 35.49623 -157.429714) (xy 35.409701 -157.421696) (xy 35.324281 -157.405728)
			(xy 35.240699 -157.381947) (xy 35.159667 -157.350555) (xy 35.081878 -157.311821) (xy 35.007994 -157.266074)
			(xy 34.938647 -157.213705) (xy 34.874427 -157.155161) (xy 34.815883 -157.090941) (xy 34.763514 -157.021594)
			(xy 34.717767 -156.94771) (xy 34.679033 -156.869921) (xy 34.647641 -156.788889) (xy 34.62386 -156.705307)
			(xy 34.607892 -156.619887) (xy 34.599874 -156.533358) (xy 31.398552 -156.533358) (xy 31.396531 -156.576951)
			(xy 31.384458 -156.663259) (xy 31.364451 -156.748078) (xy 31.336682 -156.830683) (xy 31.301389 -156.910365)
			(xy 31.258875 -156.986438) (xy 31.209504 -157.058252) (xy 31.153701 -157.12519) (xy 31.091943 -157.186678)
			(xy 31.024762 -157.242187) (xy 30.952732 -157.291243) (xy 30.876473 -157.333423) (xy 30.796638 -157.368367)
			(xy 30.713912 -157.395773) (xy 30.629005 -157.415409) (xy 30.542646 -157.427103) (xy 30.455575 -157.430758)
			(xy 30.368539 -157.42634) (xy 30.282286 -157.413888) (xy 30.197555 -157.39351) (xy 30.15615 -157.379924)
			(xy 30.135234 -157.373273) (xy 30.091882 -157.366443) (xy 30.048002 -157.367163) (xy 30.004897 -157.375411)
			(xy 29.963851 -157.390943) (xy 29.926084 -157.413296) (xy 29.892719 -157.441805) (xy 29.864748 -157.475623)
			(xy 29.843004 -157.513744) (xy 29.828133 -157.555034) (xy 29.820577 -157.598265) (xy 29.820108 -157.620208)
			(xy 29.820108 -157.899608) (xy 29.820564 -157.921558) (xy 29.828096 -157.964806) (xy 29.842952 -158.006116)
			(xy 29.864689 -158.044256) (xy 29.89266 -158.078091) (xy 29.926031 -158.106613) (xy 29.96381 -158.128972)
			(xy 30.00487 -158.144503) (xy 30.047989 -158.152744) (xy 30.091883 -158.153448) (xy 30.135244 -158.146594)
			(xy 30.15615 -158.139892) (xy 30.19755 -158.126292) (xy 30.282281 -158.105913) (xy 30.368534 -158.09346)
			(xy 30.45557 -158.089042) (xy 30.542641 -158.092696) (xy 30.629 -158.10439) (xy 30.713907 -158.124025)
			(xy 30.796633 -158.151432) (xy 30.876468 -158.186375) (xy 30.952728 -158.228555) (xy 31.024757 -158.27761)
			(xy 31.091939 -158.333119) (xy 31.153697 -158.394606) (xy 31.209501 -158.461544) (xy 31.258872 -158.533357)
			(xy 31.301386 -158.609431) (xy 31.33668 -158.689112) (xy 31.36445 -158.771717) (xy 31.384457 -158.856536)
			(xy 31.396531 -158.942843) (xy 31.400567 -159.029897) (xy 31.398552 -159.073358) (xy 34.599874 -159.073358)
			(xy 34.599874 -158.986458) (xy 34.607892 -158.899929) (xy 34.62386 -158.814509) (xy 34.647641 -158.730927)
			(xy 34.679033 -158.649895) (xy 34.717767 -158.572106) (xy 34.763514 -158.498222) (xy 34.815883 -158.428875)
			(xy 34.874427 -158.364655) (xy 34.938647 -158.306111) (xy 35.007994 -158.253742) (xy 35.081878 -158.207995)
			(xy 35.159667 -158.169261) (xy 35.240699 -158.137869) (xy 35.324281 -158.114088) (xy 35.409701 -158.09812)
			(xy 35.49623 -158.090102) (xy 35.58313 -158.090102) (xy 35.669659 -158.09812) (xy 35.755079 -158.114088)
			(xy 35.838661 -158.137869) (xy 35.919693 -158.169261) (xy 35.997482 -158.207995) (xy 36.071366 -158.253742)
			(xy 36.140713 -158.306111) (xy 36.204933 -158.364655) (xy 36.263477 -158.428875) (xy 36.315846 -158.498222)
			(xy 36.326928 -158.51612) (xy 39.565163 -158.51612) (xy 39.569048 -158.461763) (xy 39.58063 -158.408512)
			(xy 39.599672 -158.357451) (xy 39.625788 -158.30962) (xy 39.658445 -158.265993) (xy 39.696978 -158.227457)
			(xy 39.740604 -158.194798) (xy 39.788433 -158.16868) (xy 39.839493 -158.149635) (xy 39.892744 -158.138051)
			(xy 39.947101 -158.134163) (xy 40.001458 -158.138051) (xy 40.054708 -158.149636) (xy 40.105768 -158.168681)
			(xy 40.153598 -158.194799) (xy 40.175688 -158.210758) (xy 40.1947 -158.224354) (xy 40.236583 -158.245086)
			(xy 40.281551 -158.257812) (xy 40.328088 -158.262102) (xy 40.374625 -158.257812) (xy 40.419593 -158.245086)
			(xy 40.461476 -158.224354) (xy 40.480488 -158.210758) (xy 40.502608 -158.194843) (xy 40.550433 -158.168725)
			(xy 40.601487 -158.149679) (xy 40.654733 -158.138093) (xy 40.709086 -158.134204) (xy 40.763438 -158.138089)
			(xy 40.816685 -158.149671) (xy 40.867741 -158.168713) (xy 40.915567 -158.194827) (xy 40.95919 -158.227483)
			(xy 40.997721 -158.266014) (xy 41.030376 -158.309638) (xy 41.05649 -158.357464) (xy 41.075531 -158.408521)
			(xy 41.087112 -158.461768) (xy 41.090996 -158.51612) (xy 41.087106 -158.570473) (xy 41.075519 -158.623718)
			(xy 41.056473 -158.674773) (xy 41.030354 -158.722597) (xy 40.997694 -158.766216) (xy 40.959159 -158.804744)
			(xy 40.915533 -158.837395) (xy 40.867704 -158.863504) (xy 40.816646 -158.882541) (xy 40.763398 -158.894117)
			(xy 40.709045 -158.897996) (xy 40.654693 -158.894101) (xy 40.601448 -158.88251) (xy 40.550396 -158.863458)
			(xy 40.502574 -158.837335) (xy 40.480488 -158.821374) (xy 40.461476 -158.807778) (xy 40.419593 -158.787046)
			(xy 40.374625 -158.77432) (xy 40.328088 -158.77003) (xy 40.281551 -158.77432) (xy 40.236583 -158.787046)
			(xy 40.1947 -158.807778) (xy 40.175688 -158.821374) (xy 40.153632 -158.837379) (xy 40.105805 -158.863502)
			(xy 40.054748 -158.882553) (xy 40.001498 -158.894143) (xy 39.947142 -158.898037) (xy 39.892784 -158.894155)
			(xy 39.839532 -158.882576) (xy 39.78847 -158.863537) (xy 39.740638 -158.837424) (xy 39.697009 -158.804769)
			(xy 39.658471 -158.766238) (xy 39.62581 -158.722614) (xy 39.599689 -158.674786) (xy 39.580641 -158.623727)
			(xy 39.569054 -158.570477) (xy 39.565163 -158.51612) (xy 36.326928 -158.51612) (xy 36.361593 -158.572106)
			(xy 36.400327 -158.649895) (xy 36.431719 -158.730927) (xy 36.4555 -158.814509) (xy 36.471468 -158.899929)
			(xy 36.479486 -158.986458) (xy 36.479988 -159.029908) (xy 36.479486 -159.073358) (xy 36.471468 -159.159887)
			(xy 36.4555 -159.245307) (xy 36.431719 -159.328889) (xy 36.400327 -159.409921) (xy 36.361593 -159.48771)
			(xy 36.315846 -159.561594) (xy 36.263477 -159.630941) (xy 36.204933 -159.695161) (xy 36.140713 -159.753705)
			(xy 36.071366 -159.806074) (xy 35.997482 -159.851821) (xy 35.919693 -159.890555) (xy 35.838661 -159.921947)
			(xy 35.755079 -159.945728) (xy 35.669659 -159.961696) (xy 35.58313 -159.969714) (xy 35.49623 -159.969714)
			(xy 35.409701 -159.961696) (xy 35.324281 -159.945728) (xy 35.240699 -159.921947) (xy 35.159667 -159.890555)
			(xy 35.081878 -159.851821) (xy 35.007994 -159.806074) (xy 34.938647 -159.753705) (xy 34.874427 -159.695161)
			(xy 34.815883 -159.630941) (xy 34.763514 -159.561594) (xy 34.717767 -159.48771) (xy 34.679033 -159.409921)
			(xy 34.647641 -159.328889) (xy 34.62386 -159.245307) (xy 34.607892 -159.159887) (xy 34.599874 -159.073358)
			(xy 31.398552 -159.073358) (xy 31.396531 -159.116951) (xy 31.384458 -159.203259) (xy 31.364451 -159.288078)
			(xy 31.336682 -159.370683) (xy 31.301389 -159.450365) (xy 31.258875 -159.526438) (xy 31.209504 -159.598252)
			(xy 31.153701 -159.66519) (xy 31.091943 -159.726678) (xy 31.024762 -159.782187) (xy 30.952732 -159.831243)
			(xy 30.876473 -159.873423) (xy 30.796638 -159.908367) (xy 30.713912 -159.935773) (xy 30.629005 -159.955409)
			(xy 30.542646 -159.967103) (xy 30.455575 -159.970758) (xy 30.368539 -159.96634) (xy 30.282286 -159.953888)
			(xy 30.197555 -159.93351) (xy 30.15615 -159.919924) (xy 30.135234 -159.913273) (xy 30.091882 -159.906443)
			(xy 30.048002 -159.907163) (xy 30.004897 -159.915411) (xy 29.963851 -159.930943) (xy 29.926084 -159.953296)
			(xy 29.892719 -159.981805) (xy 29.864748 -160.015623) (xy 29.843004 -160.053744) (xy 29.828133 -160.095034)
			(xy 29.820577 -160.138265) (xy 29.820108 -160.160208) (xy 29.820108 -160.439608) (xy 29.820564 -160.461558)
			(xy 29.828096 -160.504806) (xy 29.842952 -160.546116) (xy 29.864689 -160.584256) (xy 29.89266 -160.618091)
			(xy 29.926031 -160.646613) (xy 29.96381 -160.668972) (xy 30.00487 -160.684503) (xy 30.047989 -160.692744)
			(xy 30.091883 -160.693448) (xy 30.135244 -160.686594) (xy 30.15615 -160.679892) (xy 30.19755 -160.666292)
			(xy 30.282281 -160.645913) (xy 30.368534 -160.63346) (xy 30.45557 -160.629042) (xy 30.542641 -160.632696)
			(xy 30.629 -160.64439) (xy 30.713907 -160.664025) (xy 30.796633 -160.691432) (xy 30.876468 -160.726375)
			(xy 30.952728 -160.768555) (xy 31.024757 -160.81761) (xy 31.091939 -160.873119) (xy 31.153697 -160.934606)
			(xy 31.209501 -161.001544) (xy 31.258872 -161.073357) (xy 31.301386 -161.149431) (xy 31.33668 -161.229112)
			(xy 31.36445 -161.311717) (xy 31.384457 -161.396536) (xy 31.396531 -161.482843) (xy 31.400567 -161.569897)
			(xy 31.398552 -161.613358) (xy 34.599874 -161.613358) (xy 34.599874 -161.526458) (xy 34.607892 -161.439929)
			(xy 34.62386 -161.354509) (xy 34.647641 -161.270927) (xy 34.679033 -161.189895) (xy 34.717767 -161.112106)
			(xy 34.763514 -161.038222) (xy 34.815883 -160.968875) (xy 34.874427 -160.904655) (xy 34.938647 -160.846111)
			(xy 35.007994 -160.793742) (xy 35.081878 -160.747995) (xy 35.159667 -160.709261) (xy 35.240699 -160.677869)
			(xy 35.324281 -160.654088) (xy 35.409701 -160.63812) (xy 35.49623 -160.630102) (xy 35.58313 -160.630102)
			(xy 35.669659 -160.63812) (xy 35.755079 -160.654088) (xy 35.838661 -160.677869) (xy 35.919693 -160.709261)
			(xy 35.997482 -160.747995) (xy 36.071366 -160.793742) (xy 36.140713 -160.846111) (xy 36.186358 -160.887722)
			(xy 39.565162 -160.887722) (xy 39.569047 -160.833364) (xy 39.580628 -160.780113) (xy 39.59967 -160.729052)
			(xy 39.625786 -160.68122) (xy 39.658443 -160.637593) (xy 39.696976 -160.599057) (xy 39.740602 -160.566398)
			(xy 39.788432 -160.540279) (xy 39.839492 -160.521234) (xy 39.892742 -160.50965) (xy 39.9471 -160.505762)
			(xy 40.001457 -160.50965) (xy 40.054708 -160.521234) (xy 40.105768 -160.540279) (xy 40.153598 -160.566397)
			(xy 40.175688 -160.582356) (xy 40.1947 -160.595952) (xy 40.236583 -160.616684) (xy 40.281551 -160.62941)
			(xy 40.328088 -160.6337) (xy 40.374625 -160.62941) (xy 40.419593 -160.616684) (xy 40.461476 -160.595952)
			(xy 40.480488 -160.582356) (xy 40.50261 -160.566444) (xy 40.550434 -160.540326) (xy 40.601489 -160.52128)
			(xy 40.654734 -160.509695) (xy 40.709087 -160.505805) (xy 40.763439 -160.509691) (xy 40.816686 -160.521273)
			(xy 40.867741 -160.540315) (xy 40.915567 -160.566429) (xy 40.95919 -160.599085) (xy 40.997721 -160.637616)
			(xy 41.030375 -160.68124) (xy 41.056489 -160.729066) (xy 41.07553 -160.780122) (xy 41.08711 -160.833369)
			(xy 41.090995 -160.887722) (xy 41.087104 -160.942074) (xy 41.075518 -160.995319) (xy 41.056471 -161.046373)
			(xy 41.030352 -161.094197) (xy 40.997692 -161.137816) (xy 40.959157 -161.176344) (xy 40.915531 -161.208994)
			(xy 40.867702 -161.235103) (xy 40.816644 -161.25414) (xy 40.763397 -161.265715) (xy 40.709044 -161.269595)
			(xy 40.654692 -161.265699) (xy 40.601448 -161.254108) (xy 40.550395 -161.235056) (xy 40.502574 -161.208933)
			(xy 40.480488 -161.192972) (xy 40.461476 -161.179376) (xy 40.419593 -161.158644) (xy 40.374625 -161.145918)
			(xy 40.328088 -161.141628) (xy 40.281551 -161.145918) (xy 40.236583 -161.158644) (xy 40.1947 -161.179376)
			(xy 40.175688 -161.192972) (xy 40.153634 -161.208979) (xy 40.105807 -161.235103) (xy 40.054749 -161.254154)
			(xy 40.0015 -161.265744) (xy 39.947143 -161.269638) (xy 39.892785 -161.265756) (xy 39.839533 -161.254178)
			(xy 39.788471 -161.235139) (xy 39.740638 -161.209026) (xy 39.697009 -161.176371) (xy 39.658471 -161.13784)
			(xy 39.625809 -161.094216) (xy 39.599688 -161.046388) (xy 39.58064 -160.995329) (xy 39.569053 -160.942079)
			(xy 39.565162 -160.887722) (xy 36.186358 -160.887722) (xy 36.204933 -160.904655) (xy 36.263477 -160.968875)
			(xy 36.315846 -161.038222) (xy 36.361593 -161.112106) (xy 36.400327 -161.189895) (xy 36.431719 -161.270927)
			(xy 36.4555 -161.354509) (xy 36.471468 -161.439929) (xy 36.479486 -161.526458) (xy 36.479988 -161.569908)
			(xy 36.479486 -161.613358) (xy 36.471468 -161.699887) (xy 36.4555 -161.785307) (xy 36.431719 -161.868889)
			(xy 36.400327 -161.949921) (xy 36.361593 -162.02771) (xy 36.315846 -162.101594) (xy 36.263477 -162.170941)
			(xy 36.204933 -162.235161) (xy 36.140713 -162.293705) (xy 36.071366 -162.346074) (xy 35.997482 -162.391821)
			(xy 35.919693 -162.430555) (xy 35.838661 -162.461947) (xy 35.755079 -162.485728) (xy 35.669659 -162.501696)
			(xy 35.58313 -162.509714) (xy 35.49623 -162.509714) (xy 35.409701 -162.501696) (xy 35.324281 -162.485728)
			(xy 35.240699 -162.461947) (xy 35.159667 -162.430555) (xy 35.081878 -162.391821) (xy 35.007994 -162.346074)
			(xy 34.938647 -162.293705) (xy 34.874427 -162.235161) (xy 34.815883 -162.170941) (xy 34.763514 -162.101594)
			(xy 34.717767 -162.02771) (xy 34.679033 -161.949921) (xy 34.647641 -161.868889) (xy 34.62386 -161.785307)
			(xy 34.607892 -161.699887) (xy 34.599874 -161.613358) (xy 31.398552 -161.613358) (xy 31.396531 -161.656951)
			(xy 31.384458 -161.743259) (xy 31.364451 -161.828078) (xy 31.336682 -161.910683) (xy 31.301389 -161.990365)
			(xy 31.258875 -162.066438) (xy 31.209504 -162.138252) (xy 31.153701 -162.20519) (xy 31.091943 -162.266678)
			(xy 31.024762 -162.322187) (xy 30.952732 -162.371243) (xy 30.876473 -162.413423) (xy 30.796638 -162.448367)
			(xy 30.713912 -162.475773) (xy 30.629005 -162.495409) (xy 30.542646 -162.507103) (xy 30.455575 -162.510758)
			(xy 30.368539 -162.50634) (xy 30.282286 -162.493888) (xy 30.197555 -162.47351) (xy 30.15615 -162.459924)
			(xy 30.135234 -162.453273) (xy 30.091882 -162.446443) (xy 30.048002 -162.447163) (xy 30.004897 -162.455411)
			(xy 29.963851 -162.470943) (xy 29.926084 -162.493296) (xy 29.892719 -162.521805) (xy 29.864748 -162.555623)
			(xy 29.843004 -162.593744) (xy 29.828133 -162.635034) (xy 29.820577 -162.678265) (xy 29.820108 -162.700208)
			(xy 29.820108 -162.850614) (xy 39.565171 -162.850614) (xy 39.569057 -162.796258) (xy 39.580639 -162.743008)
			(xy 39.599682 -162.691949) (xy 39.625798 -162.644119) (xy 39.658455 -162.600494) (xy 39.696988 -162.56196)
			(xy 39.740613 -162.529302) (xy 39.788442 -162.503185) (xy 39.839501 -162.484141) (xy 39.892751 -162.472558)
			(xy 39.947107 -162.468671) (xy 40.001463 -162.47256) (xy 40.054712 -162.484145) (xy 40.10577 -162.503191)
			(xy 40.153598 -162.529309) (xy 40.175688 -162.545268) (xy 40.1947 -162.558864) (xy 40.236583 -162.579596)
			(xy 40.281551 -162.592322) (xy 40.328088 -162.596612) (xy 40.374625 -162.592322) (xy 40.419593 -162.579596)
			(xy 40.461476 -162.558864) (xy 40.480488 -162.545268) (xy 40.502599 -162.529339) (xy 40.550424 -162.50322)
			(xy 40.601479 -162.484173) (xy 40.654726 -162.472586) (xy 40.70908 -162.468695) (xy 40.763434 -162.47258)
			(xy 40.816681 -162.484161) (xy 40.867739 -162.503203) (xy 40.915567 -162.529317) (xy 40.959191 -162.561973)
			(xy 40.997723 -162.600505) (xy 41.030379 -162.644128) (xy 41.056495 -162.691956) (xy 41.075537 -162.743013)
			(xy 41.087119 -162.79626) (xy 41.091005 -162.850614) (xy 41.087115 -162.904968) (xy 41.075529 -162.958215)
			(xy 41.056483 -163.009271) (xy 41.030364 -163.057096) (xy 40.997704 -163.100717) (xy 40.959169 -163.139246)
			(xy 40.915542 -163.171898) (xy 40.867713 -163.198009) (xy 40.816654 -163.217047) (xy 40.763405 -163.228624)
			(xy 40.709051 -163.232505) (xy 40.654697 -163.22861) (xy 40.601452 -163.217019) (xy 40.550398 -163.197968)
			(xy 40.502575 -163.171845) (xy 40.480488 -163.155884) (xy 40.461476 -163.142288) (xy 40.419593 -163.121556)
			(xy 40.374625 -163.10883) (xy 40.328088 -163.10454) (xy 40.281551 -163.10883) (xy 40.236583 -163.121556)
			(xy 40.1947 -163.142288) (xy 40.175688 -163.155884) (xy 40.153623 -163.171875) (xy 40.105797 -163.197997)
			(xy 40.05474 -163.217047) (xy 40.001491 -163.228636) (xy 39.947136 -163.232529) (xy 39.892779 -163.228646)
			(xy 39.839529 -163.217067) (xy 39.788468 -163.198027) (xy 39.740637 -163.171914) (xy 39.69701 -163.139259)
			(xy 39.658473 -163.100728) (xy 39.625813 -163.057105) (xy 39.599694 -163.009277) (xy 39.580647 -162.958219)
			(xy 39.569061 -162.90497) (xy 39.565171 -162.850614) (xy 29.820108 -162.850614) (xy 29.820108 -162.979608)
			(xy 29.820564 -163.001558) (xy 29.828096 -163.044806) (xy 29.842952 -163.086116) (xy 29.864689 -163.124256)
			(xy 29.89266 -163.158091) (xy 29.926031 -163.186613) (xy 29.96381 -163.208972) (xy 30.00487 -163.224503)
			(xy 30.047989 -163.232744) (xy 30.091883 -163.233448) (xy 30.135244 -163.226594) (xy 30.15615 -163.219892)
			(xy 30.19755 -163.206292) (xy 30.282281 -163.185913) (xy 30.368534 -163.17346) (xy 30.45557 -163.169042)
			(xy 30.542641 -163.172696) (xy 30.629 -163.18439) (xy 30.713907 -163.204025) (xy 30.796633 -163.231432)
			(xy 30.876468 -163.266375) (xy 30.952728 -163.308555) (xy 31.024757 -163.35761) (xy 31.091939 -163.413119)
			(xy 31.153697 -163.474606) (xy 31.209501 -163.541544) (xy 31.258872 -163.613357) (xy 31.301386 -163.689431)
			(xy 31.33668 -163.769112) (xy 31.36445 -163.851717) (xy 31.384457 -163.936536) (xy 31.396531 -164.022843)
			(xy 31.400567 -164.109897) (xy 31.398552 -164.153358) (xy 34.599874 -164.153358) (xy 34.599874 -164.066458)
			(xy 34.607892 -163.979929) (xy 34.62386 -163.894509) (xy 34.647641 -163.810927) (xy 34.679033 -163.729895)
			(xy 34.717767 -163.652106) (xy 34.763514 -163.578222) (xy 34.815883 -163.508875) (xy 34.874427 -163.444655)
			(xy 34.938647 -163.386111) (xy 35.007994 -163.333742) (xy 35.081878 -163.287995) (xy 35.159667 -163.249261)
			(xy 35.240699 -163.217869) (xy 35.324281 -163.194088) (xy 35.409701 -163.17812) (xy 35.49623 -163.170102)
			(xy 35.58313 -163.170102) (xy 35.669659 -163.17812) (xy 35.755079 -163.194088) (xy 35.838661 -163.217869)
			(xy 35.919693 -163.249261) (xy 35.997482 -163.287995) (xy 36.071366 -163.333742) (xy 36.140713 -163.386111)
			(xy 36.204933 -163.444655) (xy 36.263477 -163.508875) (xy 36.315846 -163.578222) (xy 36.361593 -163.652106)
			(xy 36.400327 -163.729895) (xy 36.431719 -163.810927) (xy 36.4555 -163.894509) (xy 36.471468 -163.979929)
			(xy 36.479486 -164.066458) (xy 36.479988 -164.109908) (xy 36.479486 -164.153358) (xy 36.471468 -164.239887)
			(xy 36.4555 -164.325307) (xy 36.431719 -164.408889) (xy 36.400327 -164.489921) (xy 36.361593 -164.56771)
			(xy 36.315846 -164.641594) (xy 36.263477 -164.710941) (xy 36.204933 -164.775161) (xy 36.140713 -164.833705)
			(xy 36.071366 -164.886074) (xy 35.997482 -164.931821) (xy 35.919693 -164.970555) (xy 35.858888 -164.994111)
			(xy 39.565176 -164.994111) (xy 39.569062 -164.939755) (xy 39.580645 -164.886506) (xy 39.599688 -164.835448)
			(xy 39.625804 -164.787619) (xy 39.658461 -164.743994) (xy 39.696994 -164.705461) (xy 39.740619 -164.672804)
			(xy 39.788447 -164.646688) (xy 39.839506 -164.627645) (xy 39.892755 -164.616062) (xy 39.94711 -164.612176)
			(xy 40.001466 -164.616065) (xy 40.054714 -164.627651) (xy 40.105772 -164.646697) (xy 40.153599 -164.672815)
			(xy 40.175688 -164.688774) (xy 40.1947 -164.70237) (xy 40.236583 -164.723102) (xy 40.281551 -164.735828)
			(xy 40.328088 -164.740118) (xy 40.374625 -164.735828) (xy 40.419593 -164.723102) (xy 40.461476 -164.70237)
			(xy 40.480488 -164.688774) (xy 40.502593 -164.672837) (xy 40.550419 -164.646717) (xy 40.601475 -164.627669)
			(xy 40.654722 -164.616082) (xy 40.709076 -164.612191) (xy 40.763431 -164.616075) (xy 40.816679 -164.627656)
			(xy 40.867738 -164.646697) (xy 40.915566 -164.672811) (xy 40.959191 -164.705467) (xy 40.997724 -164.743999)
			(xy 41.030382 -164.787623) (xy 41.056497 -164.83545) (xy 41.075541 -164.886508) (xy 41.087123 -164.939756)
			(xy 41.091009 -164.994111) (xy 41.08712 -165.048465) (xy 41.075534 -165.101713) (xy 41.056488 -165.152769)
			(xy 41.03037 -165.200596) (xy 40.99771 -165.244218) (xy 40.959175 -165.282747) (xy 40.915548 -165.3154)
			(xy 40.867718 -165.341512) (xy 40.816659 -165.36055) (xy 40.763409 -165.372128) (xy 40.709054 -165.376009)
			(xy 40.6547 -165.372115) (xy 40.601454 -165.360525) (xy 40.550399 -165.341474) (xy 40.502575 -165.315351)
			(xy 40.480488 -165.29939) (xy 40.461476 -165.285794) (xy 40.419593 -165.265062) (xy 40.374625 -165.252336)
			(xy 40.328088 -165.248046) (xy 40.281551 -165.252336) (xy 40.236583 -165.265062) (xy 40.1947 -165.285794)
			(xy 40.175688 -165.29939) (xy 40.153617 -165.315373) (xy 40.105791 -165.341494) (xy 40.054735 -165.360543)
			(xy 40.001487 -165.372131) (xy 39.947132 -165.376024) (xy 39.892776 -165.372141) (xy 39.839527 -165.360561)
			(xy 39.788467 -165.341521) (xy 39.740637 -165.315408) (xy 39.69701 -165.282753) (xy 39.658475 -165.244222)
			(xy 39.625815 -165.200599) (xy 39.599697 -165.152772) (xy 39.580651 -165.101714) (xy 39.569066 -165.048466)
			(xy 39.565176 -164.994111) (xy 35.858888 -164.994111) (xy 35.838661 -165.001947) (xy 35.755079 -165.025728)
			(xy 35.669659 -165.041696) (xy 35.58313 -165.049714) (xy 35.49623 -165.049714) (xy 35.409701 -165.041696)
			(xy 35.324281 -165.025728) (xy 35.240699 -165.001947) (xy 35.159667 -164.970555) (xy 35.081878 -164.931821)
			(xy 35.007994 -164.886074) (xy 34.938647 -164.833705) (xy 34.874427 -164.775161) (xy 34.815883 -164.710941)
			(xy 34.763514 -164.641594) (xy 34.717767 -164.56771) (xy 34.679033 -164.489921) (xy 34.647641 -164.408889)
			(xy 34.62386 -164.325307) (xy 34.607892 -164.239887) (xy 34.599874 -164.153358) (xy 31.398552 -164.153358)
			(xy 31.396531 -164.196951) (xy 31.384458 -164.283259) (xy 31.364451 -164.368078) (xy 31.336682 -164.450683)
			(xy 31.301389 -164.530365) (xy 31.258875 -164.606438) (xy 31.209504 -164.678252) (xy 31.153701 -164.74519)
			(xy 31.091943 -164.806678) (xy 31.024762 -164.862187) (xy 30.952732 -164.911243) (xy 30.876473 -164.953423)
			(xy 30.796638 -164.988367) (xy 30.713912 -165.015773) (xy 30.629005 -165.035409) (xy 30.542646 -165.047103)
			(xy 30.455575 -165.050758) (xy 30.368539 -165.04634) (xy 30.282286 -165.033888) (xy 30.197555 -165.01351)
			(xy 30.15615 -164.999924) (xy 30.135234 -164.993273) (xy 30.091882 -164.986443) (xy 30.048002 -164.987163)
			(xy 30.004897 -164.995411) (xy 29.963851 -165.010943) (xy 29.926084 -165.033296) (xy 29.892719 -165.061805)
			(xy 29.864748 -165.095623) (xy 29.843004 -165.133744) (xy 29.828133 -165.175034) (xy 29.820577 -165.218265)
			(xy 29.820108 -165.240208) (xy 29.820108 -165.519608) (xy 29.820564 -165.541558) (xy 29.828096 -165.584806)
			(xy 29.842952 -165.626116) (xy 29.864689 -165.664256) (xy 29.89266 -165.698091) (xy 29.926031 -165.726613)
			(xy 29.96381 -165.748972) (xy 30.00487 -165.764503) (xy 30.047989 -165.772744) (xy 30.091883 -165.773448)
			(xy 30.135244 -165.766594) (xy 30.15615 -165.759892) (xy 30.19755 -165.746292) (xy 30.282281 -165.725913)
			(xy 30.368534 -165.71346) (xy 30.45557 -165.709042) (xy 30.542641 -165.712696) (xy 30.629 -165.72439)
			(xy 30.713907 -165.744025) (xy 30.796633 -165.771432) (xy 30.876468 -165.806375) (xy 30.952728 -165.848555)
			(xy 31.024757 -165.89761) (xy 31.091939 -165.953119) (xy 31.153697 -166.014606) (xy 31.209501 -166.081544)
			(xy 31.258872 -166.153357) (xy 31.301386 -166.229431) (xy 31.33668 -166.309112) (xy 31.36445 -166.391717)
			(xy 31.384457 -166.476536) (xy 31.396531 -166.562843) (xy 31.400567 -166.649897) (xy 31.398552 -166.693358)
			(xy 34.599874 -166.693358) (xy 34.599874 -166.606458) (xy 34.607892 -166.519929) (xy 34.62386 -166.434509)
			(xy 34.647641 -166.350927) (xy 34.679033 -166.269895) (xy 34.717767 -166.192106) (xy 34.763514 -166.118222)
			(xy 34.815883 -166.048875) (xy 34.874427 -165.984655) (xy 34.938647 -165.926111) (xy 35.007994 -165.873742)
			(xy 35.081878 -165.827995) (xy 35.159667 -165.789261) (xy 35.240699 -165.757869) (xy 35.324281 -165.734088)
			(xy 35.409701 -165.71812) (xy 35.49623 -165.710102) (xy 35.58313 -165.710102) (xy 35.669659 -165.71812)
			(xy 35.701718 -165.724113) (xy 76.871175 -165.724113) (xy 76.875061 -165.669758) (xy 76.886643 -165.616509)
			(xy 76.905686 -165.56545) (xy 76.931801 -165.517621) (xy 76.964458 -165.473996) (xy 77.00299 -165.435463)
			(xy 77.046615 -165.402805) (xy 77.094443 -165.376689) (xy 77.145502 -165.357645) (xy 77.19875 -165.346062)
			(xy 77.253106 -165.342175) (xy 77.307461 -165.346064) (xy 77.360709 -165.357649) (xy 77.411767 -165.376694)
			(xy 77.459595 -165.402811) (xy 77.481684 -165.41877) (xy 77.500696 -165.432366) (xy 77.542579 -165.453098)
			(xy 77.587547 -165.465824) (xy 77.634084 -165.470114) (xy 77.680621 -165.465824) (xy 77.725589 -165.453098)
			(xy 77.767472 -165.432366) (xy 77.786484 -165.41877) (xy 77.808593 -165.402838) (xy 77.856418 -165.376718)
			(xy 77.907474 -165.35767) (xy 77.960722 -165.346083) (xy 78.015076 -165.342191) (xy 78.069431 -165.346076)
			(xy 78.12268 -165.357657) (xy 78.173738 -165.376698) (xy 78.221567 -165.402812) (xy 78.265192 -165.435468)
			(xy 78.303725 -165.474) (xy 78.336382 -165.517624) (xy 78.362497 -165.565452) (xy 78.38154 -165.61651)
			(xy 78.393123 -165.669758) (xy 78.397009 -165.724113) (xy 79.675567 -165.724113) (xy 79.679453 -165.669756)
			(xy 79.691036 -165.616505) (xy 79.710079 -165.565445) (xy 79.736196 -165.517614) (xy 79.768854 -165.473988)
			(xy 79.807388 -165.435453) (xy 79.851015 -165.402795) (xy 79.898845 -165.376679) (xy 79.949906 -165.357636)
			(xy 80.003156 -165.346053) (xy 80.057514 -165.342167) (xy 80.111871 -165.346057) (xy 80.165121 -165.357643)
			(xy 80.21618 -165.37669) (xy 80.264008 -165.40281) (xy 80.286098 -165.41877) (xy 80.30511 -165.432366)
			(xy 80.346993 -165.453098) (xy 80.391961 -165.465824) (xy 80.438498 -165.470114) (xy 80.485035 -165.465824)
			(xy 80.530003 -165.453098) (xy 80.571886 -165.432366) (xy 80.590898 -165.41877) (xy 80.613007 -165.40284)
			(xy 80.660831 -165.376721) (xy 80.711886 -165.357676) (xy 80.765132 -165.34609) (xy 80.819484 -165.3422)
			(xy 80.873837 -165.346085) (xy 80.927083 -165.357667) (xy 80.97814 -165.376708) (xy 81.025966 -165.402822)
			(xy 81.069589 -165.435477) (xy 81.108121 -165.474009) (xy 81.140776 -165.517631) (xy 81.166891 -165.565458)
			(xy 81.185933 -165.616514) (xy 81.197514 -165.66976) (xy 81.2014 -165.724113) (xy 81.197511 -165.778466)
			(xy 81.185925 -165.831711) (xy 81.16688 -165.882766) (xy 81.140762 -165.930591) (xy 81.108104 -165.974211)
			(xy 81.069569 -166.01274) (xy 81.025944 -166.045392) (xy 80.978116 -166.071503) (xy 80.927058 -166.090541)
			(xy 80.873811 -166.102119) (xy 80.819458 -166.106) (xy 80.765105 -166.102107) (xy 80.711861 -166.090517)
			(xy 80.660807 -166.071468) (xy 80.612985 -166.045346) (xy 80.590898 -166.029386) (xy 80.571886 -166.01579)
			(xy 80.530003 -165.995058) (xy 80.485035 -165.982332) (xy 80.438498 -165.978042) (xy 80.391961 -165.982332)
			(xy 80.346993 -165.995058) (xy 80.30511 -166.01579) (xy 80.286098 -166.029386) (xy 80.264031 -166.045375)
			(xy 80.216204 -166.071499) (xy 80.165146 -166.090549) (xy 80.111897 -166.102139) (xy 80.05754 -166.106033)
			(xy 80.003183 -166.102151) (xy 79.949931 -166.090572) (xy 79.898869 -166.071532) (xy 79.851037 -166.045419)
			(xy 79.807408 -166.012764) (xy 79.768871 -165.974232) (xy 79.73621 -165.930608) (xy 79.71009 -165.882779)
			(xy 79.691043 -165.83172) (xy 79.679457 -165.77847) (xy 79.675567 -165.724113) (xy 78.397009 -165.724113)
			(xy 78.393119 -165.778468) (xy 78.381533 -165.831715) (xy 78.362486 -165.882772) (xy 78.336367 -165.930598)
			(xy 78.303707 -165.97422) (xy 78.265172 -166.012749) (xy 78.221544 -166.045402) (xy 78.173714 -166.071513)
			(xy 78.122654 -166.090551) (xy 78.069405 -166.102128) (xy 78.01505 -166.106008) (xy 77.960696 -166.102114)
			(xy 77.907449 -166.090522) (xy 77.856394 -166.071471) (xy 77.808571 -166.045347) (xy 77.786484 -166.029386)
			(xy 77.767472 -166.01579) (xy 77.725589 -165.995058) (xy 77.680621 -165.982332) (xy 77.634084 -165.978042)
			(xy 77.587547 -165.982332) (xy 77.542579 -165.995058) (xy 77.500696 -166.01579) (xy 77.481684 -166.029386)
			(xy 77.459617 -166.045374) (xy 77.411791 -166.071495) (xy 77.360735 -166.090544) (xy 77.307487 -166.102132)
			(xy 77.253132 -166.106025) (xy 77.198777 -166.102141) (xy 77.145527 -166.090562) (xy 77.094467 -166.071522)
			(xy 77.046637 -166.045409) (xy 77.00301 -166.012755) (xy 76.964475 -165.974224) (xy 76.931815 -165.930601)
			(xy 76.905697 -165.882774) (xy 76.886651 -165.831717) (xy 76.875065 -165.778468) (xy 76.871175 -165.724113)
			(xy 35.701718 -165.724113) (xy 35.755079 -165.734088) (xy 35.838661 -165.757869) (xy 35.919693 -165.789261)
			(xy 35.997482 -165.827995) (xy 36.071366 -165.873742) (xy 36.140713 -165.926111) (xy 36.204933 -165.984655)
			(xy 36.263477 -166.048875) (xy 36.315846 -166.118222) (xy 36.361593 -166.192106) (xy 36.400327 -166.269895)
			(xy 36.431719 -166.350927) (xy 36.4555 -166.434509) (xy 36.471468 -166.519929) (xy 36.479486 -166.606458)
			(xy 36.479988 -166.649908) (xy 36.479486 -166.693358) (xy 36.471468 -166.779887) (xy 36.4555 -166.865307)
			(xy 36.431719 -166.948889) (xy 36.400327 -167.029921) (xy 36.361593 -167.10771) (xy 36.315846 -167.181594)
			(xy 36.263477 -167.250941) (xy 36.204933 -167.315161) (xy 36.140713 -167.373705) (xy 36.071366 -167.426074)
			(xy 35.997482 -167.471821) (xy 35.919693 -167.510555) (xy 35.838661 -167.541947) (xy 35.755079 -167.565728)
			(xy 35.669659 -167.581696) (xy 35.58313 -167.589714) (xy 35.49623 -167.589714) (xy 35.409701 -167.581696)
			(xy 35.324281 -167.565728) (xy 35.240699 -167.541947) (xy 35.159667 -167.510555) (xy 35.081878 -167.471821)
			(xy 35.007994 -167.426074) (xy 34.938647 -167.373705) (xy 34.874427 -167.315161) (xy 34.815883 -167.250941)
			(xy 34.763514 -167.181594) (xy 34.717767 -167.10771) (xy 34.679033 -167.029921) (xy 34.647641 -166.948889)
			(xy 34.62386 -166.865307) (xy 34.607892 -166.779887) (xy 34.599874 -166.693358) (xy 31.398552 -166.693358)
			(xy 31.396531 -166.736951) (xy 31.384458 -166.823259) (xy 31.364451 -166.908078) (xy 31.336682 -166.990683)
			(xy 31.301389 -167.070365) (xy 31.258875 -167.146438) (xy 31.209504 -167.218252) (xy 31.153701 -167.28519)
			(xy 31.091943 -167.346678) (xy 31.024762 -167.402187) (xy 30.952732 -167.451243) (xy 30.876473 -167.493423)
			(xy 30.796638 -167.528367) (xy 30.713912 -167.555773) (xy 30.629005 -167.575409) (xy 30.542646 -167.587103)
			(xy 30.455575 -167.590758) (xy 30.368539 -167.58634) (xy 30.282286 -167.573888) (xy 30.197555 -167.55351)
			(xy 30.15615 -167.539924) (xy 30.135234 -167.533273) (xy 30.091882 -167.526443) (xy 30.048002 -167.527163)
			(xy 30.004897 -167.535411) (xy 29.963851 -167.550943) (xy 29.926084 -167.573296) (xy 29.892719 -167.601805)
			(xy 29.864748 -167.635623) (xy 29.843004 -167.673744) (xy 29.828133 -167.715034) (xy 29.820577 -167.758265)
			(xy 29.820108 -167.780208) (xy 29.820108 -167.959481) (xy 76.871219 -167.959481) (xy 76.875109 -167.905132)
			(xy 76.886694 -167.85189) (xy 76.905739 -167.800839) (xy 76.931855 -167.753017) (xy 76.964512 -167.7094)
			(xy 77.003043 -167.670874) (xy 77.046666 -167.638224) (xy 77.094491 -167.612115) (xy 77.145545 -167.593078)
			(xy 77.198789 -167.581501) (xy 77.253138 -167.577619) (xy 77.307487 -167.581511) (xy 77.360728 -167.593099)
			(xy 77.411779 -167.612147) (xy 77.459599 -167.638265) (xy 77.481684 -167.654224) (xy 77.500696 -167.66782)
			(xy 77.542579 -167.688552) (xy 77.587547 -167.701278) (xy 77.634084 -167.705568) (xy 77.680621 -167.701278)
			(xy 77.725589 -167.688552) (xy 77.767472 -167.66782) (xy 77.786484 -167.654224) (xy 77.808543 -167.63822)
			(xy 77.856371 -167.612092) (xy 77.907431 -167.593038) (xy 77.960683 -167.581444) (xy 78.015044 -167.577548)
			(xy 78.069405 -167.581428) (xy 78.122661 -167.593006) (xy 78.173726 -167.612045) (xy 78.221563 -167.638159)
			(xy 78.265195 -167.670814) (xy 78.303736 -167.709348) (xy 78.336401 -167.752974) (xy 78.362523 -167.800805)
			(xy 78.381573 -167.851867) (xy 78.393161 -167.90512) (xy 78.397052 -167.959481) (xy 79.67561 -167.959481)
			(xy 79.6795 -167.90513) (xy 79.691086 -167.851886) (xy 79.710132 -167.800833) (xy 79.73625 -167.75301)
			(xy 79.768908 -167.709392) (xy 79.807441 -167.670865) (xy 79.851065 -167.638214) (xy 79.898893 -167.612105)
			(xy 79.949949 -167.593068) (xy 80.003195 -167.581491) (xy 80.057546 -167.57761) (xy 80.111897 -167.581504)
			(xy 80.16514 -167.593094) (xy 80.216191 -167.612143) (xy 80.264012 -167.638264) (xy 80.286098 -167.654224)
			(xy 80.30511 -167.66782) (xy 80.346993 -167.688552) (xy 80.391961 -167.701278) (xy 80.438498 -167.705568)
			(xy 80.485035 -167.701278) (xy 80.530003 -167.688552) (xy 80.571886 -167.66782) (xy 80.590898 -167.654224)
			(xy 80.612956 -167.638221) (xy 80.660784 -167.612096) (xy 80.711843 -167.593043) (xy 80.765093 -167.581452)
			(xy 80.819452 -167.577557) (xy 80.873811 -167.581438) (xy 80.927065 -167.593016) (xy 80.978128 -167.612055)
			(xy 81.025962 -167.638168) (xy 81.069593 -167.670823) (xy 81.108132 -167.709356) (xy 81.140795 -167.752981)
			(xy 81.166917 -167.80081) (xy 81.185965 -167.851871) (xy 81.197553 -167.905122) (xy 81.201443 -167.959481)
			(xy 81.197558 -168.01384) (xy 81.185976 -168.067093) (xy 81.166933 -168.118155) (xy 81.140816 -168.165987)
			(xy 81.108157 -168.209615) (xy 81.069622 -168.248151) (xy 81.025995 -168.280811) (xy 80.978163 -168.306929)
			(xy 80.927101 -168.325973) (xy 80.873849 -168.337557) (xy 80.81949 -168.341443) (xy 80.765131 -168.337554)
			(xy 80.711879 -168.325968) (xy 80.660819 -168.30692) (xy 80.612989 -168.2808) (xy 80.590898 -168.26484)
			(xy 80.571886 -168.251244) (xy 80.530003 -168.230512) (xy 80.485035 -168.217786) (xy 80.438498 -168.213496)
			(xy 80.391961 -168.217786) (xy 80.346993 -168.230512) (xy 80.30511 -168.251244) (xy 80.286098 -168.26484)
			(xy 80.26398 -168.280757) (xy 80.216156 -168.306873) (xy 80.165103 -168.325917) (xy 80.111859 -168.337501)
			(xy 80.057508 -168.34139) (xy 80.003157 -168.337503) (xy 79.949912 -168.325921) (xy 79.898858 -168.306879)
			(xy 79.851033 -168.280765) (xy 79.807412 -168.24811) (xy 79.768882 -168.209579) (xy 79.736229 -168.165957)
			(xy 79.710116 -168.118132) (xy 79.691075 -168.067077) (xy 79.679495 -168.013832) (xy 79.67561 -167.959481)
			(xy 78.397052 -167.959481) (xy 78.393166 -168.013842) (xy 78.381584 -168.067096) (xy 78.362539 -168.11816)
			(xy 78.336421 -168.165994) (xy 78.303761 -168.209623) (xy 78.265224 -168.248161) (xy 78.221595 -168.280821)
			(xy 78.173761 -168.306939) (xy 78.122698 -168.325983) (xy 78.069443 -168.337566) (xy 78.015082 -168.341452)
			(xy 77.960722 -168.337561) (xy 77.907468 -168.325973) (xy 77.856406 -168.306924) (xy 77.808575 -168.280801)
			(xy 77.786484 -168.26484) (xy 77.767472 -168.251244) (xy 77.725589 -168.230512) (xy 77.680621 -168.217786)
			(xy 77.634084 -168.213496) (xy 77.587547 -168.217786) (xy 77.542579 -168.230512) (xy 77.500696 -168.251244)
			(xy 77.481684 -168.26484) (xy 77.459566 -168.280755) (xy 77.411744 -168.306869) (xy 77.360691 -168.325912)
			(xy 77.307449 -168.337494) (xy 77.2531 -168.341381) (xy 77.198751 -168.337494) (xy 77.145508 -168.325911)
			(xy 77.094456 -168.306869) (xy 77.046633 -168.280755) (xy 77.003014 -168.248101) (xy 76.964486 -168.209571)
			(xy 76.931834 -168.16595) (xy 76.905723 -168.118126) (xy 76.886683 -168.067073) (xy 76.875103 -168.01383)
			(xy 76.871219 -167.959481) (xy 29.820108 -167.959481) (xy 29.820108 -168.059608) (xy 29.820564 -168.081558)
			(xy 29.828096 -168.124806) (xy 29.842952 -168.166116) (xy 29.864689 -168.204256) (xy 29.89266 -168.238091)
			(xy 29.926031 -168.266613) (xy 29.96381 -168.288972) (xy 30.00487 -168.304503) (xy 30.047989 -168.312744)
			(xy 30.091883 -168.313448) (xy 30.135244 -168.306594) (xy 30.15615 -168.299892) (xy 30.195931 -168.28681)
			(xy 30.277287 -168.266933) (xy 30.360088 -168.25437) (xy 30.443678 -168.249218) (xy 30.527395 -168.25152)
			(xy 30.610576 -168.261257) (xy 30.692562 -168.278352) (xy 30.772702 -168.302669) (xy 30.850363 -168.334016)
			(xy 30.924929 -168.372144) (xy 30.99581 -168.416752) (xy 31.062443 -168.467485) (xy 31.124301 -168.523943)
			(xy 31.180894 -168.585677) (xy 31.206694 -168.618662) (xy 31.233675 -168.654818) (xy 31.281365 -168.731402)
			(xy 31.3215 -168.812203) (xy 31.35371 -168.896478) (xy 31.377698 -168.98345) (xy 31.393244 -169.07232)
			(xy 31.400206 -169.162271) (xy 31.398877 -169.233358) (xy 34.599874 -169.233358) (xy 34.599874 -169.146458)
			(xy 34.607892 -169.059929) (xy 34.62386 -168.974509) (xy 34.647641 -168.890927) (xy 34.679033 -168.809895)
			(xy 34.717767 -168.732106) (xy 34.763514 -168.658222) (xy 34.815883 -168.588875) (xy 34.874427 -168.524655)
			(xy 34.938647 -168.466111) (xy 35.007994 -168.413742) (xy 35.081878 -168.367995) (xy 35.159667 -168.329261)
			(xy 35.240699 -168.297869) (xy 35.324281 -168.274088) (xy 35.409701 -168.25812) (xy 35.49623 -168.250102)
			(xy 35.58313 -168.250102) (xy 35.669659 -168.25812) (xy 35.755079 -168.274088) (xy 35.838661 -168.297869)
			(xy 35.919693 -168.329261) (xy 35.997482 -168.367995) (xy 36.071366 -168.413742) (xy 36.140713 -168.466111)
			(xy 36.204933 -168.524655) (xy 36.263477 -168.588875) (xy 36.315846 -168.658222) (xy 36.361593 -168.732106)
			(xy 36.400327 -168.809895) (xy 36.431719 -168.890927) (xy 36.4555 -168.974509) (xy 36.471468 -169.059929)
			(xy 36.479486 -169.146458) (xy 36.479988 -169.189908) (xy 36.479486 -169.233358) (xy 36.471468 -169.319887)
			(xy 36.4555 -169.405307) (xy 36.431719 -169.488889) (xy 36.400327 -169.569921) (xy 36.361593 -169.64771)
			(xy 36.315846 -169.721594) (xy 36.263477 -169.790941) (xy 36.204933 -169.855161) (xy 36.140713 -169.913705)
			(xy 36.071366 -169.966074) (xy 35.997482 -170.011821) (xy 35.919693 -170.050555) (xy 35.838661 -170.081947)
			(xy 35.755079 -170.105728) (xy 35.669659 -170.121696) (xy 35.58313 -170.129714) (xy 35.49623 -170.129714)
			(xy 35.409701 -170.121696) (xy 35.324281 -170.105728) (xy 35.240699 -170.081947) (xy 35.159667 -170.050555)
			(xy 35.081878 -170.011821) (xy 35.007994 -169.966074) (xy 34.938647 -169.913705) (xy 34.874427 -169.855161)
			(xy 34.815883 -169.790941) (xy 34.763514 -169.721594) (xy 34.717767 -169.64771) (xy 34.679033 -169.569921)
			(xy 34.647641 -169.488889) (xy 34.62386 -169.405307) (xy 34.607892 -169.319887) (xy 34.599874 -169.233358)
			(xy 31.398877 -169.233358) (xy 31.398519 -169.252475) (xy 31.393892 -169.29735) (xy 31.388896 -169.33707)
			(xy 31.373002 -169.415537) (xy 31.362142 -169.454068) (xy 31.356642 -169.476695) (xy 31.353025 -169.523115)
			(xy 31.357922 -169.569416) (xy 31.371169 -169.614052) (xy 31.392323 -169.655529) (xy 31.420677 -169.69246)
			(xy 31.455283 -169.72361) (xy 31.494982 -169.747937) (xy 31.538448 -169.764628) (xy 31.584226 -169.773124)
			(xy 31.607506 -169.7736) (xy 32.415988 -169.7736) (xy 32.415988 -170.627799) (xy 76.871195 -170.627799)
			(xy 76.875082 -170.573446) (xy 76.886666 -170.5202) (xy 76.905709 -170.469145) (xy 76.931825 -170.42132)
			(xy 76.964482 -170.377698) (xy 77.003014 -170.339168) (xy 77.046638 -170.306514) (xy 77.094464 -170.2804)
			(xy 77.145521 -170.26136) (xy 77.198767 -170.249779) (xy 77.25312 -170.245895) (xy 77.307472 -170.249785)
			(xy 77.360718 -170.261371) (xy 77.411772 -170.280417) (xy 77.459596 -170.306535) (xy 77.481684 -170.322494)
			(xy 77.500696 -170.33609) (xy 77.542579 -170.356822) (xy 77.587547 -170.369548) (xy 77.634084 -170.373838)
			(xy 77.680621 -170.369548) (xy 77.725589 -170.356822) (xy 77.767472 -170.33609) (xy 77.786484 -170.322494)
			(xy 77.808571 -170.30653) (xy 77.856397 -170.280406) (xy 77.907455 -170.261356) (xy 77.960705 -170.249766)
			(xy 78.015062 -170.245872) (xy 78.069419 -170.249755) (xy 78.122671 -170.261334) (xy 78.173733 -170.280375)
			(xy 78.221565 -170.306489) (xy 78.265193 -170.339144) (xy 78.30373 -170.377677) (xy 78.33639 -170.421302)
			(xy 78.362509 -170.469131) (xy 78.381555 -170.520191) (xy 78.39314 -170.573441) (xy 78.397028 -170.627799)
			(xy 79.675586 -170.627799) (xy 79.679474 -170.573444) (xy 79.691058 -170.520197) (xy 79.710103 -170.46914)
			(xy 79.73622 -170.421313) (xy 79.768878 -170.37769) (xy 79.807412 -170.339158) (xy 79.851037 -170.306504)
			(xy 79.898866 -170.28039) (xy 79.949925 -170.26135) (xy 80.003173 -170.24977) (xy 80.057528 -170.245886)
			(xy 80.111882 -170.249778) (xy 80.165129 -170.261366) (xy 80.216185 -170.280414) (xy 80.26401 -170.306534)
			(xy 80.286098 -170.322494) (xy 80.30511 -170.33609) (xy 80.346993 -170.356822) (xy 80.391961 -170.369548)
			(xy 80.438498 -170.373838) (xy 80.485035 -170.369548) (xy 80.530003 -170.356822) (xy 80.571886 -170.33609)
			(xy 80.590898 -170.322494) (xy 80.612984 -170.306531) (xy 80.66081 -170.28041) (xy 80.711867 -170.261361)
			(xy 80.765115 -170.249773) (xy 80.81947 -170.245881) (xy 80.873825 -170.249764) (xy 80.927075 -170.261344)
			(xy 80.978135 -170.280385) (xy 81.025965 -170.306498) (xy 81.069591 -170.339153) (xy 81.108126 -170.377685)
			(xy 81.140785 -170.421309) (xy 81.166902 -170.469137) (xy 81.185947 -170.520195) (xy 81.197531 -170.573443)
			(xy 81.201419 -170.627799) (xy 81.197532 -170.682154) (xy 81.185948 -170.735403) (xy 81.166903 -170.786461)
			(xy 81.140786 -170.834289) (xy 81.108127 -170.877913) (xy 81.069593 -170.916445) (xy 81.025967 -170.9491)
			(xy 80.978137 -170.975214) (xy 80.927077 -170.994255) (xy 80.873828 -171.005836) (xy 80.819472 -171.009719)
			(xy 80.765117 -171.005828) (xy 80.711869 -170.99424) (xy 80.660812 -170.975191) (xy 80.612986 -170.94907)
			(xy 80.590898 -170.93311) (xy 80.571886 -170.919514) (xy 80.530003 -170.898782) (xy 80.485035 -170.886056)
			(xy 80.438498 -170.881766) (xy 80.391961 -170.886056) (xy 80.346993 -170.898782) (xy 80.30511 -170.919514)
			(xy 80.286098 -170.93311) (xy 80.264008 -170.949067) (xy 80.216183 -170.975187) (xy 80.165127 -170.994235)
			(xy 80.11188 -171.005822) (xy 80.057526 -171.009714) (xy 80.003171 -171.00583) (xy 79.949922 -170.994249)
			(xy 79.898864 -170.975209) (xy 79.851035 -170.949095) (xy 79.80741 -170.91644) (xy 79.768876 -170.877909)
			(xy 79.736218 -170.834285) (xy 79.710102 -170.786458) (xy 79.691058 -170.735401) (xy 79.679474 -170.682153)
			(xy 79.675586 -170.627799) (xy 78.397028 -170.627799) (xy 78.39314 -170.682156) (xy 78.381555 -170.735407)
			(xy 78.36251 -170.786467) (xy 78.336391 -170.834296) (xy 78.303731 -170.877921) (xy 78.265195 -170.916454)
			(xy 78.221567 -170.94911) (xy 78.173735 -170.975224) (xy 78.122673 -170.994265) (xy 78.069422 -171.005845)
			(xy 78.015064 -171.009728) (xy 77.960707 -171.005835) (xy 77.907458 -170.994245) (xy 77.8564 -170.975195)
			(xy 77.808573 -170.949071) (xy 77.786484 -170.93311) (xy 77.767472 -170.919514) (xy 77.725589 -170.898782)
			(xy 77.680621 -170.886056) (xy 77.634084 -170.881766) (xy 77.587547 -170.886056) (xy 77.542579 -170.898782)
			(xy 77.500696 -170.919514) (xy 77.481684 -170.93311) (xy 77.459594 -170.949066) (xy 77.41177 -170.975184)
			(xy 77.360715 -170.99423) (xy 77.30747 -171.005815) (xy 77.253118 -171.009705) (xy 77.198765 -171.00582)
			(xy 77.145519 -170.99424) (xy 77.094462 -170.975199) (xy 77.046636 -170.949085) (xy 77.003012 -170.916431)
			(xy 76.96448 -170.8779) (xy 76.931824 -170.834278) (xy 76.905708 -170.786453) (xy 76.886665 -170.735397)
			(xy 76.875082 -170.682151) (xy 76.871195 -170.627799) (xy 32.415988 -170.627799) (xy 32.415988 -171.773358)
			(xy 34.599874 -171.773358) (xy 34.599874 -171.686458) (xy 34.607892 -171.599929) (xy 34.62386 -171.514509)
			(xy 34.647641 -171.430927) (xy 34.679033 -171.349895) (xy 34.717767 -171.272106) (xy 34.763514 -171.198222)
			(xy 34.815883 -171.128875) (xy 34.874427 -171.064655) (xy 34.938647 -171.006111) (xy 35.007994 -170.953742)
			(xy 35.081878 -170.907995) (xy 35.159667 -170.869261) (xy 35.240699 -170.837869) (xy 35.324281 -170.814088)
			(xy 35.409701 -170.79812) (xy 35.49623 -170.790102) (xy 35.58313 -170.790102) (xy 35.669659 -170.79812)
			(xy 35.755079 -170.814088) (xy 35.838661 -170.837869) (xy 35.919693 -170.869261) (xy 35.997482 -170.907995)
			(xy 36.071366 -170.953742) (xy 36.140713 -171.006111) (xy 36.204933 -171.064655) (xy 36.263477 -171.128875)
			(xy 36.315846 -171.198222) (xy 36.361593 -171.272106) (xy 36.400327 -171.349895) (xy 36.431719 -171.430927)
			(xy 36.4555 -171.514509) (xy 36.471468 -171.599929) (xy 36.479486 -171.686458) (xy 36.479988 -171.729908)
			(xy 36.479486 -171.773358) (xy 36.471468 -171.859887) (xy 36.4555 -171.945307) (xy 36.431719 -172.028889)
			(xy 36.400327 -172.109921) (xy 36.361593 -172.18771) (xy 36.315846 -172.261594) (xy 36.277723 -172.312076)
			(xy 51.141376 -172.312076) (xy 52.793392 -172.312076) (xy 52.793392 -172.9994) (xy 76.871193 -172.9994)
			(xy 76.875081 -172.945047) (xy 76.886664 -172.891801) (xy 76.905707 -172.840745) (xy 76.931823 -172.79292)
			(xy 76.96448 -172.749298) (xy 77.003012 -172.710767) (xy 77.046636 -172.678113) (xy 77.094463 -172.652)
			(xy 77.145519 -172.632959) (xy 77.198766 -172.621378) (xy 77.253119 -172.617493) (xy 77.307471 -172.621383)
			(xy 77.360717 -172.632969) (xy 77.411772 -172.652015) (xy 77.459596 -172.678133) (xy 77.481684 -172.694092)
			(xy 77.500696 -172.707688) (xy 77.542579 -172.72842) (xy 77.587547 -172.741146) (xy 77.634084 -172.745436)
			(xy 77.680621 -172.741146) (xy 77.725589 -172.72842) (xy 77.767472 -172.707688) (xy 77.786484 -172.694092)
			(xy 77.808573 -172.678131) (xy 77.856399 -172.652007) (xy 77.907457 -172.632957) (xy 77.960706 -172.621367)
			(xy 78.015063 -172.617474) (xy 78.06942 -172.621357) (xy 78.122672 -172.632936) (xy 78.173733 -172.651977)
			(xy 78.221565 -172.678091) (xy 78.265193 -172.710746) (xy 78.303729 -172.749279) (xy 78.336389 -172.792904)
			(xy 78.362508 -172.840733) (xy 78.381554 -172.891792) (xy 78.393138 -172.945043) (xy 78.397026 -172.9994)
			(xy 79.675585 -172.9994) (xy 79.679472 -172.945045) (xy 79.691056 -172.891797) (xy 79.710101 -172.84074)
			(xy 79.736218 -172.792913) (xy 79.768876 -172.749289) (xy 79.80741 -172.710758) (xy 79.851035 -172.678103)
			(xy 79.898864 -172.651989) (xy 79.949923 -172.632949) (xy 80.003172 -172.621369) (xy 80.057527 -172.617485)
			(xy 80.111881 -172.621376) (xy 80.165128 -172.632964) (xy 80.216185 -172.652012) (xy 80.26401 -172.678132)
			(xy 80.286098 -172.694092) (xy 80.30511 -172.707688) (xy 80.346993 -172.72842) (xy 80.391961 -172.741146)
			(xy 80.438498 -172.745436) (xy 80.485035 -172.741146) (xy 80.530003 -172.72842) (xy 80.571886 -172.707688)
			(xy 80.590898 -172.694092) (xy 80.612986 -172.678132) (xy 80.660812 -172.652011) (xy 80.711868 -172.632962)
			(xy 80.765116 -172.621374) (xy 80.819471 -172.617482) (xy 80.873826 -172.621366) (xy 80.927076 -172.632946)
			(xy 80.978135 -172.651987) (xy 81.025965 -172.6781) (xy 81.069591 -172.710755) (xy 81.108125 -172.749287)
			(xy 81.140784 -172.792911) (xy 81.166901 -172.840738) (xy 81.185946 -172.891796) (xy 81.19753 -172.945045)
			(xy 81.201418 -172.9994) (xy 81.19753 -173.053755) (xy 81.185946 -173.107004) (xy 81.166901 -173.158062)
			(xy 81.140784 -173.205889) (xy 81.108125 -173.249513) (xy 81.069591 -173.288045) (xy 81.025965 -173.3207)
			(xy 80.978135 -173.346813) (xy 80.927076 -173.365854) (xy 80.873826 -173.377434) (xy 80.819471 -173.381318)
			(xy 80.765116 -173.377426) (xy 80.711868 -173.365838) (xy 80.660812 -173.346789) (xy 80.612986 -173.320668)
			(xy 80.590898 -173.304708) (xy 80.571886 -173.291112) (xy 80.530003 -173.27038) (xy 80.485035 -173.257654)
			(xy 80.438498 -173.253364) (xy 80.391961 -173.257654) (xy 80.346993 -173.27038) (xy 80.30511 -173.291112)
			(xy 80.286098 -173.304708) (xy 80.26401 -173.320668) (xy 80.216185 -173.346788) (xy 80.165128 -173.365836)
			(xy 80.111881 -173.377424) (xy 80.057527 -173.381315) (xy 80.003172 -173.377431) (xy 79.949923 -173.365851)
			(xy 79.898864 -173.346811) (xy 79.851035 -173.320697) (xy 79.80741 -173.288042) (xy 79.768876 -173.249511)
			(xy 79.736218 -173.205887) (xy 79.710101 -173.15806) (xy 79.691056 -173.107003) (xy 79.679472 -173.053755)
			(xy 79.675585 -172.9994) (xy 78.397026 -172.9994) (xy 78.393138 -173.053757) (xy 78.381554 -173.107008)
			(xy 78.362508 -173.158067) (xy 78.336389 -173.205896) (xy 78.303729 -173.249521) (xy 78.265193 -173.288054)
			(xy 78.221565 -173.320709) (xy 78.173733 -173.346823) (xy 78.122672 -173.365864) (xy 78.06942 -173.377443)
			(xy 78.015063 -173.381326) (xy 77.960706 -173.377433) (xy 77.907457 -173.365843) (xy 77.856399 -173.346793)
			(xy 77.808573 -173.320669) (xy 77.786484 -173.304708) (xy 77.767472 -173.291112) (xy 77.725589 -173.27038)
			(xy 77.680621 -173.257654) (xy 77.634084 -173.253364) (xy 77.587547 -173.257654) (xy 77.542579 -173.27038)
			(xy 77.500696 -173.291112) (xy 77.481684 -173.304708) (xy 77.459596 -173.320667) (xy 77.411772 -173.346785)
			(xy 77.360717 -173.365831) (xy 77.307471 -173.377417) (xy 77.253119 -173.381307) (xy 77.198766 -173.377422)
			(xy 77.145519 -173.365841) (xy 77.094463 -173.3468) (xy 77.046636 -173.320687) (xy 77.003012 -173.288033)
			(xy 76.96448 -173.249502) (xy 76.931823 -173.20588) (xy 76.905707 -173.158055) (xy 76.886664 -173.106999)
			(xy 76.875081 -173.053753) (xy 76.871193 -172.9994) (xy 52.793392 -172.9994) (xy 52.793392 -173.963584)
			(xy 51.141376 -173.963584) (xy 51.141376 -172.312076) (xy 36.277723 -172.312076) (xy 36.263477 -172.330941)
			(xy 36.204933 -172.395161) (xy 36.140713 -172.453705) (xy 36.071366 -172.506074) (xy 35.997482 -172.551821)
			(xy 35.919693 -172.590555) (xy 35.838661 -172.621947) (xy 35.755079 -172.645728) (xy 35.669659 -172.661696)
			(xy 35.58313 -172.669714) (xy 35.49623 -172.669714) (xy 35.409701 -172.661696) (xy 35.324281 -172.645728)
			(xy 35.240699 -172.621947) (xy 35.159667 -172.590555) (xy 35.081878 -172.551821) (xy 35.007994 -172.506074)
			(xy 34.938647 -172.453705) (xy 34.874427 -172.395161) (xy 34.815883 -172.330941) (xy 34.763514 -172.261594)
			(xy 34.717767 -172.18771) (xy 34.679033 -172.109921) (xy 34.647641 -172.028889) (xy 34.62386 -171.945307)
			(xy 34.607892 -171.859887) (xy 34.599874 -171.773358) (xy 32.415988 -171.773358) (xy 32.415988 -173.178385)
			(xy 47.641754 -173.178385) (xy 47.641754 -173.097275) (xy 47.649704 -173.016556) (xy 47.665527 -172.937005)
			(xy 47.689072 -172.859389) (xy 47.720111 -172.784453) (xy 47.758346 -172.712921) (xy 47.803408 -172.645481)
			(xy 47.854863 -172.582782) (xy 47.912216 -172.525429) (xy 47.974915 -172.473974) (xy 48.042355 -172.428912)
			(xy 48.113887 -172.390677) (xy 48.188823 -172.359638) (xy 48.266439 -172.336093) (xy 48.34599 -172.32027)
			(xy 48.426709 -172.31232) (xy 48.507819 -172.31232) (xy 48.588538 -172.32027) (xy 48.668089 -172.336093)
			(xy 48.745705 -172.359638) (xy 48.820641 -172.390677) (xy 48.892173 -172.428912) (xy 48.959613 -172.473974)
			(xy 49.022312 -172.525429) (xy 49.079665 -172.582782) (xy 49.13112 -172.645481) (xy 49.176182 -172.712921)
			(xy 49.214417 -172.784453) (xy 49.245456 -172.859389) (xy 49.269001 -172.937005) (xy 49.284824 -173.016556)
			(xy 49.292774 -173.097275) (xy 49.293272 -173.13783) (xy 49.292774 -173.178385) (xy 49.284824 -173.259104)
			(xy 49.269001 -173.338655) (xy 49.245456 -173.416271) (xy 49.214417 -173.491207) (xy 49.176182 -173.562739)
			(xy 49.13112 -173.630179) (xy 49.079665 -173.692878) (xy 49.022312 -173.750231) (xy 48.959613 -173.801686)
			(xy 48.892173 -173.846748) (xy 48.820641 -173.884983) (xy 48.745705 -173.916022) (xy 48.668089 -173.939567)
			(xy 48.588538 -173.95539) (xy 48.507819 -173.96334) (xy 48.426709 -173.96334) (xy 48.34599 -173.95539)
			(xy 48.266439 -173.939567) (xy 48.188823 -173.916022) (xy 48.113887 -173.884983) (xy 48.042355 -173.846748)
			(xy 47.974915 -173.801686) (xy 47.912216 -173.750231) (xy 47.854863 -173.692878) (xy 47.803408 -173.630179)
			(xy 47.758346 -173.562739) (xy 47.720111 -173.491207) (xy 47.689072 -173.416271) (xy 47.665527 -173.338655)
			(xy 47.649704 -173.259104) (xy 47.641754 -173.178385) (xy 32.415988 -173.178385) (xy 32.415988 -173.700186)
			(xy 32.416527 -173.716804) (xy 32.425116 -173.748911) (xy 32.441713 -173.777706) (xy 32.453072 -173.789848)
			(xy 33.62567 -174.962293) (xy 76.871203 -174.962293) (xy 76.875091 -174.907942) (xy 76.886675 -174.854697)
			(xy 76.905719 -174.803643) (xy 76.931835 -174.755819) (xy 76.964492 -174.712198) (xy 77.003024 -174.67367)
			(xy 77.046647 -174.641017) (xy 77.094473 -174.614905) (xy 77.145529 -174.595866) (xy 77.198775 -174.584286)
			(xy 77.253126 -174.580403) (xy 77.307477 -174.584294) (xy 77.360721 -174.595881) (xy 77.411774 -174.614927)
			(xy 77.459597 -174.641045) (xy 77.481684 -174.657004) (xy 77.500696 -174.6706) (xy 77.542579 -174.691332)
			(xy 77.587547 -174.704058) (xy 77.634084 -174.708348) (xy 77.680621 -174.704058) (xy 77.725589 -174.691332)
			(xy 77.767472 -174.6706) (xy 77.786484 -174.657004) (xy 77.808561 -174.641027) (xy 77.856389 -174.614902)
			(xy 77.907447 -174.59585) (xy 77.960698 -174.584259) (xy 78.015056 -174.580364) (xy 78.069415 -174.584246)
			(xy 78.122668 -174.595825) (xy 78.173731 -174.614865) (xy 78.221564 -174.640979) (xy 78.265194 -174.673634)
			(xy 78.303732 -174.712167) (xy 78.336394 -174.755793) (xy 78.362514 -174.803622) (xy 78.381561 -174.854683)
			(xy 78.393147 -174.907934) (xy 78.397036 -174.962293) (xy 79.675594 -174.962293) (xy 79.679483 -174.90794)
			(xy 79.691068 -174.854693) (xy 79.710112 -174.803637) (xy 79.73623 -174.755812) (xy 79.768888 -174.71219)
			(xy 79.807421 -174.673661) (xy 79.851047 -174.641007) (xy 79.898875 -174.614895) (xy 79.949933 -174.595856)
			(xy 80.00318 -174.584277) (xy 80.057534 -174.580394) (xy 80.111887 -174.584287) (xy 80.165133 -174.595875)
			(xy 80.216187 -174.614924) (xy 80.264011 -174.641044) (xy 80.286098 -174.657004) (xy 80.30511 -174.6706)
			(xy 80.346993 -174.691332) (xy 80.391961 -174.704058) (xy 80.438498 -174.708348) (xy 80.485035 -174.704058)
			(xy 80.530003 -174.691332) (xy 80.571886 -174.6706) (xy 80.590898 -174.657004) (xy 80.612975 -174.641028)
			(xy 80.660801 -174.614905) (xy 80.711859 -174.595855) (xy 80.765107 -174.584266) (xy 80.819464 -174.580373)
			(xy 80.873821 -174.584255) (xy 80.927072 -174.595835) (xy 80.978132 -174.614875) (xy 81.025964 -174.640988)
			(xy 81.069592 -174.673643) (xy 81.108128 -174.712175) (xy 81.140788 -174.7558) (xy 81.166907 -174.803628)
			(xy 81.185953 -174.854687) (xy 81.197538 -174.907936) (xy 81.201427 -174.962293) (xy 81.197541 -175.016649)
			(xy 81.185957 -175.0699) (xy 81.166913 -175.120959) (xy 81.140796 -175.168788) (xy 81.108137 -175.212414)
			(xy 81.069603 -175.250947) (xy 81.025976 -175.283604) (xy 80.978146 -175.309719) (xy 80.927085 -175.328761)
			(xy 80.873835 -175.340343) (xy 80.819478 -175.344227) (xy 80.765122 -175.340336) (xy 80.711872 -175.328749)
			(xy 80.660814 -175.309701) (xy 80.612987 -175.28358) (xy 80.590898 -175.26762) (xy 80.571886 -175.254024)
			(xy 80.530003 -175.233292) (xy 80.485035 -175.220566) (xy 80.438498 -175.216276) (xy 80.391961 -175.220566)
			(xy 80.346993 -175.233292) (xy 80.30511 -175.254024) (xy 80.286098 -175.26762) (xy 80.263999 -175.283564)
			(xy 80.216174 -175.309682) (xy 80.165119 -175.328729) (xy 80.111873 -175.340315) (xy 80.05752 -175.344206)
			(xy 80.003166 -175.340321) (xy 79.949919 -175.32874) (xy 79.898862 -175.309699) (xy 79.851035 -175.283585)
			(xy 79.807411 -175.25093) (xy 79.768878 -175.212399) (xy 79.736222 -175.168776) (xy 79.710106 -175.120949)
			(xy 79.691063 -175.069893) (xy 79.679481 -175.016646) (xy 79.675594 -174.962293) (xy 78.397036 -174.962293)
			(xy 78.393149 -175.016651) (xy 78.381565 -175.069903) (xy 78.36252 -175.120964) (xy 78.336401 -175.168795)
			(xy 78.303741 -175.212422) (xy 78.265205 -175.250956) (xy 78.221576 -175.283614) (xy 78.173744 -175.309729)
			(xy 78.122681 -175.328771) (xy 78.069429 -175.340352) (xy 78.01507 -175.344236) (xy 77.960712 -175.340343)
			(xy 77.907461 -175.328754) (xy 77.856402 -175.309704) (xy 77.808573 -175.283581) (xy 77.786484 -175.26762)
			(xy 77.767472 -175.254024) (xy 77.725589 -175.233292) (xy 77.680621 -175.220566) (xy 77.634084 -175.216276)
			(xy 77.587547 -175.220566) (xy 77.542579 -175.233292) (xy 77.500696 -175.254024) (xy 77.481684 -175.26762)
			(xy 77.459585 -175.283562) (xy 77.411761 -175.309679) (xy 77.360707 -175.328724) (xy 77.307463 -175.340308)
			(xy 77.253112 -175.344197) (xy 77.19876 -175.340312) (xy 77.145515 -175.32873) (xy 77.09446 -175.309689)
			(xy 77.046635 -175.283575) (xy 77.003013 -175.250921) (xy 76.964482 -175.212391) (xy 76.931827 -175.168769)
			(xy 76.905713 -175.120944) (xy 76.886671 -175.069889) (xy 76.875089 -175.016644) (xy 76.871203 -174.962293)
			(xy 33.62567 -174.962293) (xy 34.404554 -175.741076) (xy 37.79647 -175.741076) (xy 39.161183 -177.105789)
			(xy 76.871207 -177.105789) (xy 76.875096 -177.051439) (xy 76.886681 -176.998195) (xy 76.905725 -176.947142)
			(xy 76.931841 -176.899318) (xy 76.964498 -176.855699) (xy 77.00303 -176.817171) (xy 77.046653 -176.784519)
			(xy 77.094478 -176.758408) (xy 77.145534 -176.739369) (xy 77.198779 -176.727791) (xy 77.25313 -176.723907)
			(xy 77.30748 -176.727799) (xy 77.360723 -176.739386) (xy 77.411776 -176.758433) (xy 77.459597 -176.784551)
			(xy 77.481684 -176.80051) (xy 77.500696 -176.814106) (xy 77.542579 -176.834838) (xy 77.587547 -176.847564)
			(xy 77.634084 -176.851854) (xy 77.680621 -176.847564) (xy 77.725589 -176.834838) (xy 77.767472 -176.814106)
			(xy 77.786484 -176.80051) (xy 77.808556 -176.784524) (xy 77.856383 -176.758399) (xy 77.907442 -176.739346)
			(xy 77.960693 -176.727754) (xy 78.015052 -176.723859) (xy 78.069412 -176.727741) (xy 78.122666 -176.739319)
			(xy 78.173729 -176.758359) (xy 78.221564 -176.784473) (xy 78.265194 -176.817128) (xy 78.303733 -176.855661)
			(xy 78.336396 -176.899287) (xy 78.362517 -176.947117) (xy 78.381564 -176.998178) (xy 78.393151 -177.05143)
			(xy 78.397041 -177.105789) (xy 79.675599 -177.105789) (xy 79.679488 -177.051437) (xy 79.691073 -176.998191)
			(xy 79.710118 -176.947136) (xy 79.736236 -176.899311) (xy 79.768894 -176.855691) (xy 79.807427 -176.817162)
			(xy 79.851052 -176.784509) (xy 79.89888 -176.758398) (xy 79.949938 -176.73936) (xy 80.003185 -176.727781)
			(xy 80.057538 -176.723899) (xy 80.11189 -176.727792) (xy 80.165135 -176.739381) (xy 80.216188 -176.758429)
			(xy 80.264011 -176.78455) (xy 80.286098 -176.80051) (xy 80.30511 -176.814106) (xy 80.346993 -176.834838)
			(xy 80.391961 -176.847564) (xy 80.438498 -176.851854) (xy 80.485035 -176.847564) (xy 80.530003 -176.834838)
			(xy 80.571886 -176.814106) (xy 80.590898 -176.80051) (xy 80.612969 -176.784526) (xy 80.660796 -176.758402)
			(xy 80.711854 -176.739352) (xy 80.765103 -176.727761) (xy 80.81946 -176.723868) (xy 80.873818 -176.72775)
			(xy 80.927069 -176.739329) (xy 80.978131 -176.758369) (xy 81.025963 -176.784482) (xy 81.069592 -176.817137)
			(xy 81.108129 -176.855669) (xy 81.14079 -176.899294) (xy 81.16691 -176.947123) (xy 81.185957 -176.998182)
			(xy 81.197543 -177.051432) (xy 81.201432 -177.105789) (xy 81.197546 -177.160147) (xy 81.185963 -177.213397)
			(xy 81.166919 -177.264458) (xy 81.140802 -177.312288) (xy 81.108143 -177.355914) (xy 81.069608 -177.394448)
			(xy 81.025982 -177.427106) (xy 80.978151 -177.453222) (xy 80.92709 -177.472265) (xy 80.873839 -177.483847)
			(xy 80.819482 -177.487732) (xy 80.765125 -177.483842) (xy 80.711875 -177.472255) (xy 80.660816 -177.453207)
			(xy 80.612988 -177.427086) (xy 80.590898 -177.411126) (xy 80.571886 -177.39753) (xy 80.530003 -177.376798)
			(xy 80.485035 -177.364072) (xy 80.438498 -177.359782) (xy 80.391961 -177.364072) (xy 80.346993 -177.376798)
			(xy 80.30511 -177.39753) (xy 80.286098 -177.411126) (xy 80.263993 -177.427061) (xy 80.216169 -177.45318)
			(xy 80.165114 -177.472225) (xy 80.111869 -177.483811) (xy 80.057516 -177.487701) (xy 80.003163 -177.483816)
			(xy 79.949917 -177.472234) (xy 79.898861 -177.453193) (xy 79.851034 -177.427079) (xy 79.807411 -177.394424)
			(xy 79.768879 -177.355893) (xy 79.736224 -177.31227) (xy 79.710109 -177.264444) (xy 79.691067 -177.213388)
			(xy 79.679485 -177.160142) (xy 79.675599 -177.105789) (xy 78.397041 -177.105789) (xy 78.393154 -177.160148)
			(xy 78.38157 -177.213401) (xy 78.362526 -177.264463) (xy 78.336407 -177.312295) (xy 78.303747 -177.355922)
			(xy 78.265211 -177.394458) (xy 78.221582 -177.427116) (xy 78.173749 -177.453232) (xy 78.122686 -177.472275)
			(xy 78.069433 -177.483856) (xy 78.015074 -177.487741) (xy 77.960715 -177.483849) (xy 77.907463 -177.47226)
			(xy 77.856403 -177.45321) (xy 77.808574 -177.427087) (xy 77.786484 -177.411126) (xy 77.767472 -177.39753)
			(xy 77.725589 -177.376798) (xy 77.680621 -177.364072) (xy 77.634084 -177.359782) (xy 77.587547 -177.364072)
			(xy 77.542579 -177.376798) (xy 77.500696 -177.39753) (xy 77.481684 -177.411126) (xy 77.459579 -177.42706)
			(xy 77.411756 -177.453176) (xy 77.360703 -177.47222) (xy 77.307459 -177.483804) (xy 77.253108 -177.487693)
			(xy 77.198757 -177.483806) (xy 77.145513 -177.472225) (xy 77.094459 -177.453183) (xy 77.046634 -177.427069)
			(xy 77.003013 -177.394415) (xy 76.964483 -177.355885) (xy 76.931829 -177.312263) (xy 76.905716 -177.264439)
			(xy 76.886675 -177.213384) (xy 76.875093 -177.16014) (xy 76.871207 -177.105789) (xy 39.161183 -177.105789)
			(xy 41.072816 -179.017422) (xy 41.072816 -181.764178) (xy 41.073313 -181.787192) (xy 41.081602 -181.832467)
			(xy 41.097912 -181.875509) (xy 41.12171 -181.914907) (xy 41.152216 -181.949373) (xy 41.188433 -181.977779)
			(xy 41.229175 -181.999195) (xy 41.273109 -182.01292) (xy 41.318797 -182.018505) (xy 41.341802 -182.01767)
			(xy 41.414943 -182.01387) (xy 41.561419 -182.013238) (xy 41.707713 -182.020559) (xy 41.853394 -182.03581)
			(xy 41.998032 -182.058946) (xy 42.141201 -182.0899) (xy 42.282479 -182.128579) (xy 42.421449 -182.17487)
			(xy 42.557701 -182.228636) (xy 42.690834 -182.289719) (xy 42.820455 -182.357939) (xy 42.946182 -182.433094)
			(xy 43.067643 -182.514963) (xy 43.184482 -182.603304) (xy 43.296353 -182.697858) (xy 43.402927 -182.798344)
			(xy 43.503889 -182.904468) (xy 43.598942 -183.015915) (xy 43.687805 -183.132358) (xy 43.770216 -183.253452)
			(xy 43.834591 -183.36006) (xy 63.647831 -183.36006) (xy 63.651866 -183.284356) (xy 63.663925 -183.209511)
			(xy 63.683871 -183.13637) (xy 63.711478 -183.065765) (xy 63.746434 -182.998494) (xy 63.788342 -182.935319)
			(xy 63.836728 -182.876957) (xy 63.891044 -182.824069) (xy 63.950673 -182.777254) (xy 64.014941 -182.737042)
			(xy 64.083118 -182.70389) (xy 64.154434 -182.678172) (xy 64.228079 -182.66018) (xy 64.303219 -182.650118)
			(xy 64.379003 -182.648099) (xy 64.454573 -182.654148) (xy 64.529071 -182.668195) (xy 64.601654 -182.690081)
			(xy 64.6715 -182.719558) (xy 64.737817 -182.756293) (xy 64.799853 -182.799868) (xy 64.856906 -182.84979)
			(xy 64.90833 -182.905494) (xy 64.953541 -182.966349) (xy 64.992028 -183.031664) (xy 65.023354 -183.1007)
			(xy 65.047164 -183.172675) (xy 65.063189 -183.246773) (xy 65.071248 -183.322154) (xy 65.071752 -183.36006)
			(xy 66.187831 -183.36006) (xy 66.191866 -183.284356) (xy 66.203925 -183.209511) (xy 66.223871 -183.13637)
			(xy 66.251478 -183.065765) (xy 66.286434 -182.998494) (xy 66.328342 -182.935319) (xy 66.376728 -182.876957)
			(xy 66.431044 -182.824069) (xy 66.490673 -182.777254) (xy 66.554941 -182.737042) (xy 66.623118 -182.70389)
			(xy 66.694434 -182.678172) (xy 66.768079 -182.66018) (xy 66.843219 -182.650118) (xy 66.919003 -182.648099)
			(xy 66.994573 -182.654148) (xy 67.069071 -182.668195) (xy 67.141654 -182.690081) (xy 67.2115 -182.719558)
			(xy 67.277817 -182.756293) (xy 67.339853 -182.799868) (xy 67.396906 -182.84979) (xy 67.44833 -182.905494)
			(xy 67.493541 -182.966349) (xy 67.532028 -183.031664) (xy 67.563354 -183.1007) (xy 67.587164 -183.172675)
			(xy 67.603189 -183.246773) (xy 67.611248 -183.322154) (xy 67.611752 -183.36006) (xy 68.727831 -183.36006)
			(xy 68.731866 -183.284356) (xy 68.743925 -183.209511) (xy 68.763871 -183.13637) (xy 68.791478 -183.065765)
			(xy 68.826434 -182.998494) (xy 68.868342 -182.935319) (xy 68.916728 -182.876957) (xy 68.971044 -182.824069)
			(xy 69.030673 -182.777254) (xy 69.094941 -182.737042) (xy 69.163118 -182.70389) (xy 69.234434 -182.678172)
			(xy 69.308079 -182.66018) (xy 69.383219 -182.650118) (xy 69.459003 -182.648099) (xy 69.534573 -182.654148)
			(xy 69.609071 -182.668195) (xy 69.681654 -182.690081) (xy 69.7515 -182.719558) (xy 69.817817 -182.756293)
			(xy 69.879853 -182.799868) (xy 69.936906 -182.84979) (xy 69.98833 -182.905494) (xy 70.033541 -182.966349)
			(xy 70.072028 -183.031664) (xy 70.103354 -183.1007) (xy 70.127164 -183.172675) (xy 70.143189 -183.246773)
			(xy 70.151248 -183.322154) (xy 70.151752 -183.36006) (xy 71.267831 -183.36006) (xy 71.271866 -183.284356)
			(xy 71.283925 -183.209511) (xy 71.303871 -183.13637) (xy 71.331478 -183.065765) (xy 71.366434 -182.998494)
			(xy 71.408342 -182.935319) (xy 71.456728 -182.876957) (xy 71.511044 -182.824069) (xy 71.570673 -182.777254)
			(xy 71.634941 -182.737042) (xy 71.703118 -182.70389) (xy 71.774434 -182.678172) (xy 71.848079 -182.66018)
			(xy 71.923219 -182.650118) (xy 71.999003 -182.648099) (xy 72.074573 -182.654148) (xy 72.149071 -182.668195)
			(xy 72.221654 -182.690081) (xy 72.2915 -182.719558) (xy 72.357817 -182.756293) (xy 72.419853 -182.799868)
			(xy 72.476906 -182.84979) (xy 72.52833 -182.905494) (xy 72.573541 -182.966349) (xy 72.612028 -183.031664)
			(xy 72.643354 -183.1007) (xy 72.667164 -183.172675) (xy 72.683189 -183.246773) (xy 72.691248 -183.322154)
			(xy 72.691752 -183.36006) (xy 73.807831 -183.36006) (xy 73.811866 -183.284356) (xy 73.823925 -183.209511)
			(xy 73.843871 -183.13637) (xy 73.871478 -183.065765) (xy 73.906434 -182.998494) (xy 73.948342 -182.935319)
			(xy 73.996728 -182.876957) (xy 74.051044 -182.824069) (xy 74.110673 -182.777254) (xy 74.174941 -182.737042)
			(xy 74.243118 -182.70389) (xy 74.314434 -182.678172) (xy 74.388079 -182.66018) (xy 74.463219 -182.650118)
			(xy 74.539003 -182.648099) (xy 74.614573 -182.654148) (xy 74.689071 -182.668195) (xy 74.761654 -182.690081)
			(xy 74.8315 -182.719558) (xy 74.897817 -182.756293) (xy 74.959853 -182.799868) (xy 75.016906 -182.84979)
			(xy 75.06833 -182.905494) (xy 75.113541 -182.966349) (xy 75.152028 -183.031664) (xy 75.183354 -183.1007)
			(xy 75.207164 -183.172675) (xy 75.223189 -183.246773) (xy 75.231248 -183.322154) (xy 75.231752 -183.36006)
			(xy 76.347831 -183.36006) (xy 76.351866 -183.284356) (xy 76.363925 -183.209511) (xy 76.383871 -183.13637)
			(xy 76.411478 -183.065765) (xy 76.446434 -182.998494) (xy 76.488342 -182.935319) (xy 76.536728 -182.876957)
			(xy 76.591044 -182.824069) (xy 76.650673 -182.777254) (xy 76.714941 -182.737042) (xy 76.783118 -182.70389)
			(xy 76.854434 -182.678172) (xy 76.928079 -182.66018) (xy 77.003219 -182.650118) (xy 77.079003 -182.648099)
			(xy 77.154573 -182.654148) (xy 77.229071 -182.668195) (xy 77.301654 -182.690081) (xy 77.3715 -182.719558)
			(xy 77.437817 -182.756293) (xy 77.499853 -182.799868) (xy 77.556906 -182.84979) (xy 77.60833 -182.905494)
			(xy 77.653541 -182.966349) (xy 77.692028 -183.031664) (xy 77.723354 -183.1007) (xy 77.747164 -183.172675)
			(xy 77.763189 -183.246773) (xy 77.771248 -183.322154) (xy 77.771752 -183.36006) (xy 78.887831 -183.36006)
			(xy 78.891866 -183.284356) (xy 78.903925 -183.209511) (xy 78.923871 -183.13637) (xy 78.951478 -183.065765)
			(xy 78.986434 -182.998494) (xy 79.028342 -182.935319) (xy 79.076728 -182.876957) (xy 79.131044 -182.824069)
			(xy 79.190673 -182.777254) (xy 79.254941 -182.737042) (xy 79.323118 -182.70389) (xy 79.394434 -182.678172)
			(xy 79.468079 -182.66018) (xy 79.543219 -182.650118) (xy 79.619003 -182.648099) (xy 79.694573 -182.654148)
			(xy 79.769071 -182.668195) (xy 79.841654 -182.690081) (xy 79.9115 -182.719558) (xy 79.977817 -182.756293)
			(xy 80.039853 -182.799868) (xy 80.096906 -182.84979) (xy 80.14833 -182.905494) (xy 80.193541 -182.966349)
			(xy 80.232028 -183.031664) (xy 80.263354 -183.1007) (xy 80.287164 -183.172675) (xy 80.303189 -183.246773)
			(xy 80.311248 -183.322154) (xy 80.311752 -183.36006) (xy 81.427831 -183.36006) (xy 81.431866 -183.284356)
			(xy 81.443925 -183.209511) (xy 81.463871 -183.13637) (xy 81.491478 -183.065765) (xy 81.526434 -182.998494)
			(xy 81.568342 -182.935319) (xy 81.616728 -182.876957) (xy 81.671044 -182.824069) (xy 81.730673 -182.777254)
			(xy 81.794941 -182.737042) (xy 81.863118 -182.70389) (xy 81.934434 -182.678172) (xy 82.008079 -182.66018)
			(xy 82.083219 -182.650118) (xy 82.159003 -182.648099) (xy 82.234573 -182.654148) (xy 82.309071 -182.668195)
			(xy 82.381654 -182.690081) (xy 82.4515 -182.719558) (xy 82.517817 -182.756293) (xy 82.579853 -182.799868)
			(xy 82.636906 -182.84979) (xy 82.68833 -182.905494) (xy 82.733541 -182.966349) (xy 82.772028 -183.031664)
			(xy 82.803354 -183.1007) (xy 82.827164 -183.172675) (xy 82.843189 -183.246773) (xy 82.851248 -183.322154)
			(xy 82.851752 -183.36006) (xy 82.851248 -183.397966) (xy 82.843189 -183.473347) (xy 82.827164 -183.547445)
			(xy 82.803354 -183.61942) (xy 82.772028 -183.688456) (xy 82.733541 -183.753771) (xy 82.68833 -183.814626)
			(xy 82.636906 -183.87033) (xy 82.579853 -183.920252) (xy 82.517817 -183.963827) (xy 82.4515 -184.000562)
			(xy 82.381654 -184.030039) (xy 82.309071 -184.051925) (xy 82.234573 -184.065972) (xy 82.159003 -184.072021)
			(xy 82.083219 -184.070002) (xy 82.008079 -184.05994) (xy 81.934434 -184.041948) (xy 81.863118 -184.01623)
			(xy 81.794941 -183.983078) (xy 81.730673 -183.942866) (xy 81.671044 -183.896051) (xy 81.616728 -183.843163)
			(xy 81.568342 -183.784801) (xy 81.526434 -183.721626) (xy 81.491478 -183.654355) (xy 81.463871 -183.58375)
			(xy 81.443925 -183.510609) (xy 81.431866 -183.435764) (xy 81.427831 -183.36006) (xy 80.311752 -183.36006)
			(xy 80.311248 -183.397966) (xy 80.303189 -183.473347) (xy 80.287164 -183.547445) (xy 80.263354 -183.61942)
			(xy 80.232028 -183.688456) (xy 80.193541 -183.753771) (xy 80.14833 -183.814626) (xy 80.096906 -183.87033)
			(xy 80.039853 -183.920252) (xy 79.977817 -183.963827) (xy 79.9115 -184.000562) (xy 79.841654 -184.030039)
			(xy 79.769071 -184.051925) (xy 79.694573 -184.065972) (xy 79.619003 -184.072021) (xy 79.543219 -184.070002)
			(xy 79.468079 -184.05994) (xy 79.394434 -184.041948) (xy 79.323118 -184.01623) (xy 79.254941 -183.983078)
			(xy 79.190673 -183.942866) (xy 79.131044 -183.896051) (xy 79.076728 -183.843163) (xy 79.028342 -183.784801)
			(xy 78.986434 -183.721626) (xy 78.951478 -183.654355) (xy 78.923871 -183.58375) (xy 78.903925 -183.510609)
			(xy 78.891866 -183.435764) (xy 78.887831 -183.36006) (xy 77.771752 -183.36006) (xy 77.771248 -183.397966)
			(xy 77.763189 -183.473347) (xy 77.747164 -183.547445) (xy 77.723354 -183.61942) (xy 77.692028 -183.688456)
			(xy 77.653541 -183.753771) (xy 77.60833 -183.814626) (xy 77.556906 -183.87033) (xy 77.499853 -183.920252)
			(xy 77.437817 -183.963827) (xy 77.3715 -184.000562) (xy 77.301654 -184.030039) (xy 77.229071 -184.051925)
			(xy 77.154573 -184.065972) (xy 77.079003 -184.072021) (xy 77.003219 -184.070002) (xy 76.928079 -184.05994)
			(xy 76.854434 -184.041948) (xy 76.783118 -184.01623) (xy 76.714941 -183.983078) (xy 76.650673 -183.942866)
			(xy 76.591044 -183.896051) (xy 76.536728 -183.843163) (xy 76.488342 -183.784801) (xy 76.446434 -183.721626)
			(xy 76.411478 -183.654355) (xy 76.383871 -183.58375) (xy 76.363925 -183.510609) (xy 76.351866 -183.435764)
			(xy 76.347831 -183.36006) (xy 75.231752 -183.36006) (xy 75.231248 -183.397966) (xy 75.223189 -183.473347)
			(xy 75.207164 -183.547445) (xy 75.183354 -183.61942) (xy 75.152028 -183.688456) (xy 75.113541 -183.753771)
			(xy 75.06833 -183.814626) (xy 75.016906 -183.87033) (xy 74.959853 -183.920252) (xy 74.897817 -183.963827)
			(xy 74.8315 -184.000562) (xy 74.761654 -184.030039) (xy 74.689071 -184.051925) (xy 74.614573 -184.065972)
			(xy 74.539003 -184.072021) (xy 74.463219 -184.070002) (xy 74.388079 -184.05994) (xy 74.314434 -184.041948)
			(xy 74.243118 -184.01623) (xy 74.174941 -183.983078) (xy 74.110673 -183.942866) (xy 74.051044 -183.896051)
			(xy 73.996728 -183.843163) (xy 73.948342 -183.784801) (xy 73.906434 -183.721626) (xy 73.871478 -183.654355)
			(xy 73.843871 -183.58375) (xy 73.823925 -183.510609) (xy 73.811866 -183.435764) (xy 73.807831 -183.36006)
			(xy 72.691752 -183.36006) (xy 72.691248 -183.397966) (xy 72.683189 -183.473347) (xy 72.667164 -183.547445)
			(xy 72.643354 -183.61942) (xy 72.612028 -183.688456) (xy 72.573541 -183.753771) (xy 72.52833 -183.814626)
			(xy 72.476906 -183.87033) (xy 72.419853 -183.920252) (xy 72.357817 -183.963827) (xy 72.2915 -184.000562)
			(xy 72.221654 -184.030039) (xy 72.149071 -184.051925) (xy 72.074573 -184.065972) (xy 71.999003 -184.072021)
			(xy 71.923219 -184.070002) (xy 71.848079 -184.05994) (xy 71.774434 -184.041948) (xy 71.703118 -184.01623)
			(xy 71.634941 -183.983078) (xy 71.570673 -183.942866) (xy 71.511044 -183.896051) (xy 71.456728 -183.843163)
			(xy 71.408342 -183.784801) (xy 71.366434 -183.721626) (xy 71.331478 -183.654355) (xy 71.303871 -183.58375)
			(xy 71.283925 -183.510609) (xy 71.271866 -183.435764) (xy 71.267831 -183.36006) (xy 70.151752 -183.36006)
			(xy 70.151248 -183.397966) (xy 70.143189 -183.473347) (xy 70.127164 -183.547445) (xy 70.103354 -183.61942)
			(xy 70.072028 -183.688456) (xy 70.033541 -183.753771) (xy 69.98833 -183.814626) (xy 69.936906 -183.87033)
			(xy 69.879853 -183.920252) (xy 69.817817 -183.963827) (xy 69.7515 -184.000562) (xy 69.681654 -184.030039)
			(xy 69.609071 -184.051925) (xy 69.534573 -184.065972) (xy 69.459003 -184.072021) (xy 69.383219 -184.070002)
			(xy 69.308079 -184.05994) (xy 69.234434 -184.041948) (xy 69.163118 -184.01623) (xy 69.094941 -183.983078)
			(xy 69.030673 -183.942866) (xy 68.971044 -183.896051) (xy 68.916728 -183.843163) (xy 68.868342 -183.784801)
			(xy 68.826434 -183.721626) (xy 68.791478 -183.654355) (xy 68.763871 -183.58375) (xy 68.743925 -183.510609)
			(xy 68.731866 -183.435764) (xy 68.727831 -183.36006) (xy 67.611752 -183.36006) (xy 67.611248 -183.397966)
			(xy 67.603189 -183.473347) (xy 67.587164 -183.547445) (xy 67.563354 -183.61942) (xy 67.532028 -183.688456)
			(xy 67.493541 -183.753771) (xy 67.44833 -183.814626) (xy 67.396906 -183.87033) (xy 67.339853 -183.920252)
			(xy 67.277817 -183.963827) (xy 67.2115 -184.000562) (xy 67.141654 -184.030039) (xy 67.069071 -184.051925)
			(xy 66.994573 -184.065972) (xy 66.919003 -184.072021) (xy 66.843219 -184.070002) (xy 66.768079 -184.05994)
			(xy 66.694434 -184.041948) (xy 66.623118 -184.01623) (xy 66.554941 -183.983078) (xy 66.490673 -183.942866)
			(xy 66.431044 -183.896051) (xy 66.376728 -183.843163) (xy 66.328342 -183.784801) (xy 66.286434 -183.721626)
			(xy 66.251478 -183.654355) (xy 66.223871 -183.58375) (xy 66.203925 -183.510609) (xy 66.191866 -183.435764)
			(xy 66.187831 -183.36006) (xy 65.071752 -183.36006) (xy 65.071248 -183.397966) (xy 65.063189 -183.473347)
			(xy 65.047164 -183.547445) (xy 65.023354 -183.61942) (xy 64.992028 -183.688456) (xy 64.953541 -183.753771)
			(xy 64.90833 -183.814626) (xy 64.856906 -183.87033) (xy 64.799853 -183.920252) (xy 64.737817 -183.963827)
			(xy 64.6715 -184.000562) (xy 64.601654 -184.030039) (xy 64.529071 -184.051925) (xy 64.454573 -184.065972)
			(xy 64.379003 -184.072021) (xy 64.303219 -184.070002) (xy 64.228079 -184.05994) (xy 64.154434 -184.041948)
			(xy 64.083118 -184.01623) (xy 64.014941 -183.983078) (xy 63.950673 -183.942866) (xy 63.891044 -183.896051)
			(xy 63.836728 -183.843163) (xy 63.788342 -183.784801) (xy 63.746434 -183.721626) (xy 63.711478 -183.654355)
			(xy 63.683871 -183.58375) (xy 63.663925 -183.510609) (xy 63.651866 -183.435764) (xy 63.647831 -183.36006)
			(xy 43.834591 -183.36006) (xy 43.845932 -183.378842) (xy 43.914731 -183.508156) (xy 43.976409 -183.641015)
			(xy 44.030784 -183.777025) (xy 44.077696 -183.915787) (xy 44.117006 -184.05689) (xy 44.121022 -184.07507)
			(xy 84.927951 -184.07507) (xy 84.931986 -183.999366) (xy 84.944045 -183.924521) (xy 84.963991 -183.85138)
			(xy 84.991598 -183.780775) (xy 85.026554 -183.713504) (xy 85.068462 -183.650329) (xy 85.116848 -183.591967)
			(xy 85.171164 -183.539079) (xy 85.230793 -183.492264) (xy 85.295061 -183.452052) (xy 85.363238 -183.4189)
			(xy 85.434554 -183.393182) (xy 85.508199 -183.37519) (xy 85.583339 -183.365128) (xy 85.659123 -183.363109)
			(xy 85.734693 -183.369158) (xy 85.809191 -183.383205) (xy 85.881774 -183.405091) (xy 85.95162 -183.434568)
			(xy 86.017937 -183.471303) (xy 86.079973 -183.514878) (xy 86.137026 -183.5648) (xy 86.18845 -183.620504)
			(xy 86.233661 -183.681359) (xy 86.272148 -183.746674) (xy 86.303474 -183.81571) (xy 86.327284 -183.887685)
			(xy 86.343309 -183.961783) (xy 86.351368 -184.037164) (xy 86.351872 -184.07507) (xy 86.351368 -184.112976)
			(xy 86.343309 -184.188357) (xy 86.327284 -184.262455) (xy 86.303474 -184.33443) (xy 86.272148 -184.403466)
			(xy 86.233661 -184.468781) (xy 86.18845 -184.529636) (xy 86.137026 -184.58534) (xy 86.079973 -184.635262)
			(xy 86.017937 -184.678837) (xy 85.95162 -184.715572) (xy 85.881774 -184.745049) (xy 85.809191 -184.766935)
			(xy 85.734693 -184.780982) (xy 85.659123 -184.787031) (xy 85.583339 -184.785012) (xy 85.508199 -184.77495)
			(xy 85.434554 -184.756958) (xy 85.363238 -184.73124) (xy 85.295061 -184.698088) (xy 85.230793 -184.657876)
			(xy 85.171164 -184.611061) (xy 85.116848 -184.558173) (xy 85.068462 -184.499811) (xy 85.026554 -184.436636)
			(xy 84.991598 -184.369365) (xy 84.963991 -184.29876) (xy 84.944045 -184.225619) (xy 84.931986 -184.150774)
			(xy 84.927951 -184.07507) (xy 44.121022 -184.07507) (xy 44.148599 -184.199919) (xy 44.172382 -184.344453)
			(xy 44.188284 -184.490064) (xy 44.196259 -184.636324) (xy 44.196762 -184.709562) (xy 44.19656 -184.762703)
			(xy 44.192493 -184.868905) (xy 44.188634 -184.921906) (xy 44.182581 -184.992712) (xy 44.16396 -185.133611)
			(xy 44.137944 -185.273334) (xy 44.120634 -185.34507) (xy 86.197951 -185.34507) (xy 86.201986 -185.269366)
			(xy 86.214045 -185.194521) (xy 86.233991 -185.12138) (xy 86.261598 -185.050775) (xy 86.296554 -184.983504)
			(xy 86.338462 -184.920329) (xy 86.386848 -184.861967) (xy 86.441164 -184.809079) (xy 86.500793 -184.762264)
			(xy 86.565061 -184.722052) (xy 86.633238 -184.6889) (xy 86.704554 -184.663182) (xy 86.778199 -184.64519)
			(xy 86.853339 -184.635128) (xy 86.929123 -184.633109) (xy 87.004693 -184.639158) (xy 87.079191 -184.653205)
			(xy 87.151774 -184.675091) (xy 87.22162 -184.704568) (xy 87.287937 -184.741303) (xy 87.349973 -184.784878)
			(xy 87.407026 -184.8348) (xy 87.45845 -184.890504) (xy 87.503661 -184.951359) (xy 87.542148 -185.016674)
			(xy 87.573474 -185.08571) (xy 87.597284 -185.157685) (xy 87.613309 -185.231783) (xy 87.621368 -185.307164)
			(xy 87.621872 -185.34507) (xy 87.621368 -185.382976) (xy 87.613309 -185.458357) (xy 87.597284 -185.532455)
			(xy 87.573474 -185.60443) (xy 87.542148 -185.673466) (xy 87.503661 -185.738781) (xy 87.45845 -185.799636)
			(xy 87.407026 -185.85534) (xy 87.349973 -185.905262) (xy 87.287937 -185.948837) (xy 87.22162 -185.985572)
			(xy 87.151774 -186.015049) (xy 87.079191 -186.036935) (xy 87.004693 -186.050982) (xy 86.929123 -186.057031)
			(xy 86.853339 -186.055012) (xy 86.778199 -186.04495) (xy 86.704554 -186.026958) (xy 86.633238 -186.00124)
			(xy 86.565061 -185.968088) (xy 86.500793 -185.927876) (xy 86.441164 -185.881061) (xy 86.386848 -185.828173)
			(xy 86.338462 -185.769811) (xy 86.296554 -185.706636) (xy 86.261598 -185.639365) (xy 86.233991 -185.56876)
			(xy 86.214045 -185.495619) (xy 86.201986 -185.420774) (xy 86.197951 -185.34507) (xy 44.120634 -185.34507)
			(xy 44.104606 -185.411493) (xy 44.064038 -185.547705) (xy 44.016354 -185.681592) (xy 43.961685 -185.812781)
			(xy 43.900183 -185.940909) (xy 43.835048 -186.06008) (xy 63.647831 -186.06008) (xy 63.651866 -185.984376)
			(xy 63.663925 -185.909531) (xy 63.683871 -185.83639) (xy 63.711478 -185.765785) (xy 63.746434 -185.698514)
			(xy 63.788342 -185.635339) (xy 63.836728 -185.576977) (xy 63.891044 -185.524089) (xy 63.950673 -185.477274)
			(xy 64.014941 -185.437062) (xy 64.083118 -185.40391) (xy 64.154434 -185.378192) (xy 64.228079 -185.3602)
			(xy 64.303219 -185.350138) (xy 64.379003 -185.348119) (xy 64.454573 -185.354168) (xy 64.529071 -185.368215)
			(xy 64.601654 -185.390101) (xy 64.6715 -185.419578) (xy 64.737817 -185.456313) (xy 64.799853 -185.499888)
			(xy 64.856906 -185.54981) (xy 64.90833 -185.605514) (xy 64.953541 -185.666369) (xy 64.992028 -185.731684)
			(xy 65.023354 -185.80072) (xy 65.047164 -185.872695) (xy 65.063189 -185.946793) (xy 65.071248 -186.022174)
			(xy 65.071752 -186.06008) (xy 66.187831 -186.06008) (xy 66.191866 -185.984376) (xy 66.203925 -185.909531)
			(xy 66.223871 -185.83639) (xy 66.251478 -185.765785) (xy 66.286434 -185.698514) (xy 66.328342 -185.635339)
			(xy 66.376728 -185.576977) (xy 66.431044 -185.524089) (xy 66.490673 -185.477274) (xy 66.554941 -185.437062)
			(xy 66.623118 -185.40391) (xy 66.694434 -185.378192) (xy 66.768079 -185.3602) (xy 66.843219 -185.350138)
			(xy 66.919003 -185.348119) (xy 66.994573 -185.354168) (xy 67.069071 -185.368215) (xy 67.141654 -185.390101)
			(xy 67.2115 -185.419578) (xy 67.277817 -185.456313) (xy 67.339853 -185.499888) (xy 67.396906 -185.54981)
			(xy 67.44833 -185.605514) (xy 67.493541 -185.666369) (xy 67.532028 -185.731684) (xy 67.563354 -185.80072)
			(xy 67.587164 -185.872695) (xy 67.603189 -185.946793) (xy 67.611248 -186.022174) (xy 67.611752 -186.06008)
			(xy 68.727831 -186.06008) (xy 68.731866 -185.984376) (xy 68.743925 -185.909531) (xy 68.763871 -185.83639)
			(xy 68.791478 -185.765785) (xy 68.826434 -185.698514) (xy 68.868342 -185.635339) (xy 68.916728 -185.576977)
			(xy 68.971044 -185.524089) (xy 69.030673 -185.477274) (xy 69.094941 -185.437062) (xy 69.163118 -185.40391)
			(xy 69.234434 -185.378192) (xy 69.308079 -185.3602) (xy 69.383219 -185.350138) (xy 69.459003 -185.348119)
			(xy 69.534573 -185.354168) (xy 69.609071 -185.368215) (xy 69.681654 -185.390101) (xy 69.7515 -185.419578)
			(xy 69.817817 -185.456313) (xy 69.879853 -185.499888) (xy 69.936906 -185.54981) (xy 69.98833 -185.605514)
			(xy 70.033541 -185.666369) (xy 70.072028 -185.731684) (xy 70.103354 -185.80072) (xy 70.127164 -185.872695)
			(xy 70.143189 -185.946793) (xy 70.151248 -186.022174) (xy 70.151752 -186.06008) (xy 71.267831 -186.06008)
			(xy 71.271866 -185.984376) (xy 71.283925 -185.909531) (xy 71.303871 -185.83639) (xy 71.331478 -185.765785)
			(xy 71.366434 -185.698514) (xy 71.408342 -185.635339) (xy 71.456728 -185.576977) (xy 71.511044 -185.524089)
			(xy 71.570673 -185.477274) (xy 71.634941 -185.437062) (xy 71.703118 -185.40391) (xy 71.774434 -185.378192)
			(xy 71.848079 -185.3602) (xy 71.923219 -185.350138) (xy 71.999003 -185.348119) (xy 72.074573 -185.354168)
			(xy 72.149071 -185.368215) (xy 72.221654 -185.390101) (xy 72.2915 -185.419578) (xy 72.357817 -185.456313)
			(xy 72.419853 -185.499888) (xy 72.476906 -185.54981) (xy 72.52833 -185.605514) (xy 72.573541 -185.666369)
			(xy 72.612028 -185.731684) (xy 72.643354 -185.80072) (xy 72.667164 -185.872695) (xy 72.683189 -185.946793)
			(xy 72.691248 -186.022174) (xy 72.691752 -186.06008) (xy 73.807831 -186.06008) (xy 73.811866 -185.984376)
			(xy 73.823925 -185.909531) (xy 73.843871 -185.83639) (xy 73.871478 -185.765785) (xy 73.906434 -185.698514)
			(xy 73.948342 -185.635339) (xy 73.996728 -185.576977) (xy 74.051044 -185.524089) (xy 74.110673 -185.477274)
			(xy 74.174941 -185.437062) (xy 74.243118 -185.40391) (xy 74.314434 -185.378192) (xy 74.388079 -185.3602)
			(xy 74.463219 -185.350138) (xy 74.539003 -185.348119) (xy 74.614573 -185.354168) (xy 74.689071 -185.368215)
			(xy 74.761654 -185.390101) (xy 74.8315 -185.419578) (xy 74.897817 -185.456313) (xy 74.959853 -185.499888)
			(xy 75.016906 -185.54981) (xy 75.06833 -185.605514) (xy 75.113541 -185.666369) (xy 75.152028 -185.731684)
			(xy 75.183354 -185.80072) (xy 75.207164 -185.872695) (xy 75.223189 -185.946793) (xy 75.231248 -186.022174)
			(xy 75.231752 -186.06008) (xy 76.347831 -186.06008) (xy 76.351866 -185.984376) (xy 76.363925 -185.909531)
			(xy 76.383871 -185.83639) (xy 76.411478 -185.765785) (xy 76.446434 -185.698514) (xy 76.488342 -185.635339)
			(xy 76.536728 -185.576977) (xy 76.591044 -185.524089) (xy 76.650673 -185.477274) (xy 76.714941 -185.437062)
			(xy 76.783118 -185.40391) (xy 76.854434 -185.378192) (xy 76.928079 -185.3602) (xy 77.003219 -185.350138)
			(xy 77.079003 -185.348119) (xy 77.154573 -185.354168) (xy 77.229071 -185.368215) (xy 77.301654 -185.390101)
			(xy 77.3715 -185.419578) (xy 77.437817 -185.456313) (xy 77.499853 -185.499888) (xy 77.556906 -185.54981)
			(xy 77.60833 -185.605514) (xy 77.653541 -185.666369) (xy 77.692028 -185.731684) (xy 77.723354 -185.80072)
			(xy 77.747164 -185.872695) (xy 77.763189 -185.946793) (xy 77.771248 -186.022174) (xy 77.771752 -186.06008)
			(xy 78.887831 -186.06008) (xy 78.891866 -185.984376) (xy 78.903925 -185.909531) (xy 78.923871 -185.83639)
			(xy 78.951478 -185.765785) (xy 78.986434 -185.698514) (xy 79.028342 -185.635339) (xy 79.076728 -185.576977)
			(xy 79.131044 -185.524089) (xy 79.190673 -185.477274) (xy 79.254941 -185.437062) (xy 79.323118 -185.40391)
			(xy 79.394434 -185.378192) (xy 79.468079 -185.3602) (xy 79.543219 -185.350138) (xy 79.619003 -185.348119)
			(xy 79.694573 -185.354168) (xy 79.769071 -185.368215) (xy 79.841654 -185.390101) (xy 79.9115 -185.419578)
			(xy 79.977817 -185.456313) (xy 80.039853 -185.499888) (xy 80.096906 -185.54981) (xy 80.14833 -185.605514)
			(xy 80.193541 -185.666369) (xy 80.232028 -185.731684) (xy 80.263354 -185.80072) (xy 80.287164 -185.872695)
			(xy 80.303189 -185.946793) (xy 80.311248 -186.022174) (xy 80.311752 -186.06008) (xy 81.427831 -186.06008)
			(xy 81.431866 -185.984376) (xy 81.443925 -185.909531) (xy 81.463871 -185.83639) (xy 81.491478 -185.765785)
			(xy 81.526434 -185.698514) (xy 81.568342 -185.635339) (xy 81.616728 -185.576977) (xy 81.671044 -185.524089)
			(xy 81.730673 -185.477274) (xy 81.794941 -185.437062) (xy 81.863118 -185.40391) (xy 81.934434 -185.378192)
			(xy 82.008079 -185.3602) (xy 82.083219 -185.350138) (xy 82.159003 -185.348119) (xy 82.234573 -185.354168)
			(xy 82.309071 -185.368215) (xy 82.381654 -185.390101) (xy 82.4515 -185.419578) (xy 82.517817 -185.456313)
			(xy 82.579853 -185.499888) (xy 82.636906 -185.54981) (xy 82.68833 -185.605514) (xy 82.733541 -185.666369)
			(xy 82.772028 -185.731684) (xy 82.803354 -185.80072) (xy 82.827164 -185.872695) (xy 82.843189 -185.946793)
			(xy 82.851248 -186.022174) (xy 82.851752 -186.06008) (xy 82.851248 -186.097986) (xy 82.843189 -186.173367)
			(xy 82.827164 -186.247465) (xy 82.803354 -186.31944) (xy 82.772028 -186.388476) (xy 82.733541 -186.453791)
			(xy 82.68833 -186.514646) (xy 82.636906 -186.57035) (xy 82.585798 -186.61507) (xy 84.927951 -186.61507)
			(xy 84.931986 -186.539366) (xy 84.944045 -186.464521) (xy 84.963991 -186.39138) (xy 84.991598 -186.320775)
			(xy 85.026554 -186.253504) (xy 85.068462 -186.190329) (xy 85.116848 -186.131967) (xy 85.171164 -186.079079)
			(xy 85.230793 -186.032264) (xy 85.295061 -185.992052) (xy 85.363238 -185.9589) (xy 85.434554 -185.933182)
			(xy 85.508199 -185.91519) (xy 85.583339 -185.905128) (xy 85.659123 -185.903109) (xy 85.734693 -185.909158)
			(xy 85.809191 -185.923205) (xy 85.881774 -185.945091) (xy 85.95162 -185.974568) (xy 86.017937 -186.011303)
			(xy 86.079973 -186.054878) (xy 86.137026 -186.1048) (xy 86.18845 -186.160504) (xy 86.233661 -186.221359)
			(xy 86.272148 -186.286674) (xy 86.303474 -186.35571) (xy 86.327284 -186.427685) (xy 86.343309 -186.501783)
			(xy 86.351368 -186.577164) (xy 86.351872 -186.61507) (xy 87.467951 -186.61507) (xy 87.471986 -186.539366)
			(xy 87.484045 -186.464521) (xy 87.503991 -186.39138) (xy 87.531598 -186.320775) (xy 87.566554 -186.253504)
			(xy 87.608462 -186.190329) (xy 87.656848 -186.131967) (xy 87.711164 -186.079079) (xy 87.770793 -186.032264)
			(xy 87.835061 -185.992052) (xy 87.903238 -185.9589) (xy 87.974554 -185.933182) (xy 88.048199 -185.91519)
			(xy 88.123339 -185.905128) (xy 88.199123 -185.903109) (xy 88.274693 -185.909158) (xy 88.349191 -185.923205)
			(xy 88.421774 -185.945091) (xy 88.49162 -185.974568) (xy 88.557937 -186.011303) (xy 88.619973 -186.054878)
			(xy 88.677026 -186.1048) (xy 88.72845 -186.160504) (xy 88.773661 -186.221359) (xy 88.812148 -186.286674)
			(xy 88.843474 -186.35571) (xy 88.867284 -186.427685) (xy 88.883309 -186.501783) (xy 88.891368 -186.577164)
			(xy 88.891872 -186.61507) (xy 90.007951 -186.61507) (xy 90.011986 -186.539366) (xy 90.024045 -186.464521)
			(xy 90.043991 -186.39138) (xy 90.071598 -186.320775) (xy 90.106554 -186.253504) (xy 90.148462 -186.190329)
			(xy 90.196848 -186.131967) (xy 90.251164 -186.079079) (xy 90.310793 -186.032264) (xy 90.375061 -185.992052)
			(xy 90.443238 -185.9589) (xy 90.514554 -185.933182) (xy 90.588199 -185.91519) (xy 90.663339 -185.905128)
			(xy 90.739123 -185.903109) (xy 90.814693 -185.909158) (xy 90.889191 -185.923205) (xy 90.961774 -185.945091)
			(xy 91.03162 -185.974568) (xy 91.097937 -186.011303) (xy 91.159973 -186.054878) (xy 91.165918 -186.06008)
			(xy 93.15476 -186.06008) (xy 93.158776 -185.94381) (xy 93.170803 -185.828095) (xy 93.190785 -185.713485)
			(xy 93.218627 -185.600526) (xy 93.254196 -185.489758) (xy 93.297322 -185.381707) (xy 93.347799 -185.276889)
			(xy 93.405388 -185.175804) (xy 93.469814 -185.078932) (xy 93.540769 -184.986736) (xy 93.617916 -184.899655)
			(xy 93.700887 -184.818104) (xy 93.789287 -184.742472) (xy 93.882694 -184.673118) (xy 93.980663 -184.610375)
			(xy 94.082727 -184.554539) (xy 94.188401 -184.505878) (xy 94.29718 -184.464624) (xy 94.408545 -184.430973)
			(xy 94.521968 -184.405085) (xy 94.636905 -184.387084) (xy 94.752811 -184.377055) (xy 94.869133 -184.375047)
			(xy 94.985316 -184.381069) (xy 95.100807 -184.395092) (xy 95.215055 -184.41705) (xy 95.327516 -184.446837)
			(xy 95.437654 -184.484312) (xy 95.544944 -184.529297) (xy 95.648875 -184.581576) (xy 95.748951 -184.640901)
			(xy 95.844697 -184.706989) (xy 95.935654 -184.779525) (xy 96.02139 -184.858164) (xy 96.101497 -184.94253)
			(xy 96.175593 -185.032222) (xy 96.243323 -185.126812) (xy 96.304367 -185.22585) (xy 96.358432 -185.328863)
			(xy 96.405262 -185.43536) (xy 96.444633 -185.544835) (xy 96.476357 -185.656765) (xy 96.500283 -185.770617)
			(xy 96.516297 -185.885849) (xy 96.524324 -186.001911) (xy 96.524826 -186.06008) (xy 96.524324 -186.118249)
			(xy 96.516297 -186.234311) (xy 96.500283 -186.349543) (xy 96.476357 -186.463395) (xy 96.444633 -186.575325)
			(xy 96.405262 -186.6848) (xy 96.358432 -186.791297) (xy 96.304367 -186.89431) (xy 96.243323 -186.993348)
			(xy 96.175593 -187.087938) (xy 96.101497 -187.17763) (xy 96.02139 -187.261996) (xy 95.935654 -187.340635)
			(xy 95.844697 -187.413171) (xy 95.748951 -187.479259) (xy 95.648875 -187.538584) (xy 95.544944 -187.590863)
			(xy 95.437654 -187.635848) (xy 95.327516 -187.673323) (xy 95.215055 -187.70311) (xy 95.100807 -187.725068)
			(xy 94.985316 -187.739091) (xy 94.869133 -187.745113) (xy 94.752811 -187.743105) (xy 94.636905 -187.733076)
			(xy 94.521968 -187.715075) (xy 94.408545 -187.689187) (xy 94.29718 -187.655536) (xy 94.188401 -187.614282)
			(xy 94.082727 -187.565621) (xy 93.980663 -187.509785) (xy 93.882694 -187.447042) (xy 93.789287 -187.377688)
			(xy 93.700887 -187.302056) (xy 93.617916 -187.220505) (xy 93.540769 -187.133424) (xy 93.469814 -187.041228)
			(xy 93.405388 -186.944356) (xy 93.347799 -186.843271) (xy 93.297322 -186.738453) (xy 93.254196 -186.630402)
			(xy 93.218627 -186.519634) (xy 93.190785 -186.406675) (xy 93.170803 -186.292065) (xy 93.158776 -186.17635)
			(xy 93.15476 -186.06008) (xy 91.165918 -186.06008) (xy 91.217026 -186.1048) (xy 91.26845 -186.160504)
			(xy 91.313661 -186.221359) (xy 91.352148 -186.286674) (xy 91.383474 -186.35571) (xy 91.407284 -186.427685)
			(xy 91.423309 -186.501783) (xy 91.431368 -186.577164) (xy 91.431872 -186.61507) (xy 91.431368 -186.652976)
			(xy 91.423309 -186.728357) (xy 91.407284 -186.802455) (xy 91.383474 -186.87443) (xy 91.352148 -186.943466)
			(xy 91.313661 -187.008781) (xy 91.26845 -187.069636) (xy 91.217026 -187.12534) (xy 91.159973 -187.175262)
			(xy 91.097937 -187.218837) (xy 91.03162 -187.255572) (xy 90.961774 -187.285049) (xy 90.889191 -187.306935)
			(xy 90.814693 -187.320982) (xy 90.739123 -187.327031) (xy 90.663339 -187.325012) (xy 90.588199 -187.31495)
			(xy 90.514554 -187.296958) (xy 90.443238 -187.27124) (xy 90.375061 -187.238088) (xy 90.310793 -187.197876)
			(xy 90.251164 -187.151061) (xy 90.196848 -187.098173) (xy 90.148462 -187.039811) (xy 90.106554 -186.976636)
			(xy 90.071598 -186.909365) (xy 90.043991 -186.83876) (xy 90.024045 -186.765619) (xy 90.011986 -186.690774)
			(xy 90.007951 -186.61507) (xy 88.891872 -186.61507) (xy 88.891368 -186.652976) (xy 88.883309 -186.728357)
			(xy 88.867284 -186.802455) (xy 88.843474 -186.87443) (xy 88.812148 -186.943466) (xy 88.773661 -187.008781)
			(xy 88.72845 -187.069636) (xy 88.677026 -187.12534) (xy 88.619973 -187.175262) (xy 88.557937 -187.218837)
			(xy 88.49162 -187.255572) (xy 88.421774 -187.285049) (xy 88.349191 -187.306935) (xy 88.274693 -187.320982)
			(xy 88.199123 -187.327031) (xy 88.123339 -187.325012) (xy 88.048199 -187.31495) (xy 87.974554 -187.296958)
			(xy 87.903238 -187.27124) (xy 87.835061 -187.238088) (xy 87.770793 -187.197876) (xy 87.711164 -187.151061)
			(xy 87.656848 -187.098173) (xy 87.608462 -187.039811) (xy 87.566554 -186.976636) (xy 87.531598 -186.909365)
			(xy 87.503991 -186.83876) (xy 87.484045 -186.765619) (xy 87.471986 -186.690774) (xy 87.467951 -186.61507)
			(xy 86.351872 -186.61507) (xy 86.351368 -186.652976) (xy 86.343309 -186.728357) (xy 86.327284 -186.802455)
			(xy 86.303474 -186.87443) (xy 86.272148 -186.943466) (xy 86.233661 -187.008781) (xy 86.18845 -187.069636)
			(xy 86.137026 -187.12534) (xy 86.079973 -187.175262) (xy 86.017937 -187.218837) (xy 85.95162 -187.255572)
			(xy 85.881774 -187.285049) (xy 85.809191 -187.306935) (xy 85.734693 -187.320982) (xy 85.659123 -187.327031)
			(xy 85.583339 -187.325012) (xy 85.508199 -187.31495) (xy 85.434554 -187.296958) (xy 85.363238 -187.27124)
			(xy 85.295061 -187.238088) (xy 85.230793 -187.197876) (xy 85.171164 -187.151061) (xy 85.116848 -187.098173)
			(xy 85.068462 -187.039811) (xy 85.026554 -186.976636) (xy 84.991598 -186.909365) (xy 84.963991 -186.83876)
			(xy 84.944045 -186.765619) (xy 84.931986 -186.690774) (xy 84.927951 -186.61507) (xy 82.585798 -186.61507)
			(xy 82.579853 -186.620272) (xy 82.517817 -186.663847) (xy 82.4515 -186.700582) (xy 82.381654 -186.730059)
			(xy 82.309071 -186.751945) (xy 82.234573 -186.765992) (xy 82.159003 -186.772041) (xy 82.083219 -186.770022)
			(xy 82.008079 -186.75996) (xy 81.934434 -186.741968) (xy 81.863118 -186.71625) (xy 81.794941 -186.683098)
			(xy 81.730673 -186.642886) (xy 81.671044 -186.596071) (xy 81.616728 -186.543183) (xy 81.568342 -186.484821)
			(xy 81.526434 -186.421646) (xy 81.491478 -186.354375) (xy 81.463871 -186.28377) (xy 81.443925 -186.210629)
			(xy 81.431866 -186.135784) (xy 81.427831 -186.06008) (xy 80.311752 -186.06008) (xy 80.311248 -186.097986)
			(xy 80.303189 -186.173367) (xy 80.287164 -186.247465) (xy 80.263354 -186.31944) (xy 80.232028 -186.388476)
			(xy 80.193541 -186.453791) (xy 80.14833 -186.514646) (xy 80.096906 -186.57035) (xy 80.039853 -186.620272)
			(xy 79.977817 -186.663847) (xy 79.9115 -186.700582) (xy 79.841654 -186.730059) (xy 79.769071 -186.751945)
			(xy 79.694573 -186.765992) (xy 79.619003 -186.772041) (xy 79.543219 -186.770022) (xy 79.468079 -186.75996)
			(xy 79.394434 -186.741968) (xy 79.323118 -186.71625) (xy 79.254941 -186.683098) (xy 79.190673 -186.642886)
			(xy 79.131044 -186.596071) (xy 79.076728 -186.543183) (xy 79.028342 -186.484821) (xy 78.986434 -186.421646)
			(xy 78.951478 -186.354375) (xy 78.923871 -186.28377) (xy 78.903925 -186.210629) (xy 78.891866 -186.135784)
			(xy 78.887831 -186.06008) (xy 77.771752 -186.06008) (xy 77.771248 -186.097986) (xy 77.763189 -186.173367)
			(xy 77.747164 -186.247465) (xy 77.723354 -186.31944) (xy 77.692028 -186.388476) (xy 77.653541 -186.453791)
			(xy 77.60833 -186.514646) (xy 77.556906 -186.57035) (xy 77.499853 -186.620272) (xy 77.437817 -186.663847)
			(xy 77.3715 -186.700582) (xy 77.301654 -186.730059) (xy 77.229071 -186.751945) (xy 77.154573 -186.765992)
			(xy 77.079003 -186.772041) (xy 77.003219 -186.770022) (xy 76.928079 -186.75996) (xy 76.854434 -186.741968)
			(xy 76.783118 -186.71625) (xy 76.714941 -186.683098) (xy 76.650673 -186.642886) (xy 76.591044 -186.596071)
			(xy 76.536728 -186.543183) (xy 76.488342 -186.484821) (xy 76.446434 -186.421646) (xy 76.411478 -186.354375)
			(xy 76.383871 -186.28377) (xy 76.363925 -186.210629) (xy 76.351866 -186.135784) (xy 76.347831 -186.06008)
			(xy 75.231752 -186.06008) (xy 75.231248 -186.097986) (xy 75.223189 -186.173367) (xy 75.207164 -186.247465)
			(xy 75.183354 -186.31944) (xy 75.152028 -186.388476) (xy 75.113541 -186.453791) (xy 75.06833 -186.514646)
			(xy 75.016906 -186.57035) (xy 74.959853 -186.620272) (xy 74.897817 -186.663847) (xy 74.8315 -186.700582)
			(xy 74.761654 -186.730059) (xy 74.689071 -186.751945) (xy 74.614573 -186.765992) (xy 74.539003 -186.772041)
			(xy 74.463219 -186.770022) (xy 74.388079 -186.75996) (xy 74.314434 -186.741968) (xy 74.243118 -186.71625)
			(xy 74.174941 -186.683098) (xy 74.110673 -186.642886) (xy 74.051044 -186.596071) (xy 73.996728 -186.543183)
			(xy 73.948342 -186.484821) (xy 73.906434 -186.421646) (xy 73.871478 -186.354375) (xy 73.843871 -186.28377)
			(xy 73.823925 -186.210629) (xy 73.811866 -186.135784) (xy 73.807831 -186.06008) (xy 72.691752 -186.06008)
			(xy 72.691248 -186.097986) (xy 72.683189 -186.173367) (xy 72.667164 -186.247465) (xy 72.643354 -186.31944)
			(xy 72.612028 -186.388476) (xy 72.573541 -186.453791) (xy 72.52833 -186.514646) (xy 72.476906 -186.57035)
			(xy 72.419853 -186.620272) (xy 72.357817 -186.663847) (xy 72.2915 -186.700582) (xy 72.221654 -186.730059)
			(xy 72.149071 -186.751945) (xy 72.074573 -186.765992) (xy 71.999003 -186.772041) (xy 71.923219 -186.770022)
			(xy 71.848079 -186.75996) (xy 71.774434 -186.741968) (xy 71.703118 -186.71625) (xy 71.634941 -186.683098)
			(xy 71.570673 -186.642886) (xy 71.511044 -186.596071) (xy 71.456728 -186.543183) (xy 71.408342 -186.484821)
			(xy 71.366434 -186.421646) (xy 71.331478 -186.354375) (xy 71.303871 -186.28377) (xy 71.283925 -186.210629)
			(xy 71.271866 -186.135784) (xy 71.267831 -186.06008) (xy 70.151752 -186.06008) (xy 70.151248 -186.097986)
			(xy 70.143189 -186.173367) (xy 70.127164 -186.247465) (xy 70.103354 -186.31944) (xy 70.072028 -186.388476)
			(xy 70.033541 -186.453791) (xy 69.98833 -186.514646) (xy 69.936906 -186.57035) (xy 69.879853 -186.620272)
			(xy 69.817817 -186.663847) (xy 69.7515 -186.700582) (xy 69.681654 -186.730059) (xy 69.609071 -186.751945)
			(xy 69.534573 -186.765992) (xy 69.459003 -186.772041) (xy 69.383219 -186.770022) (xy 69.308079 -186.75996)
			(xy 69.234434 -186.741968) (xy 69.163118 -186.71625) (xy 69.094941 -186.683098) (xy 69.030673 -186.642886)
			(xy 68.971044 -186.596071) (xy 68.916728 -186.543183) (xy 68.868342 -186.484821) (xy 68.826434 -186.421646)
			(xy 68.791478 -186.354375) (xy 68.763871 -186.28377) (xy 68.743925 -186.210629) (xy 68.731866 -186.135784)
			(xy 68.727831 -186.06008) (xy 67.611752 -186.06008) (xy 67.611248 -186.097986) (xy 67.603189 -186.173367)
			(xy 67.587164 -186.247465) (xy 67.563354 -186.31944) (xy 67.532028 -186.388476) (xy 67.493541 -186.453791)
			(xy 67.44833 -186.514646) (xy 67.396906 -186.57035) (xy 67.339853 -186.620272) (xy 67.277817 -186.663847)
			(xy 67.2115 -186.700582) (xy 67.141654 -186.730059) (xy 67.069071 -186.751945) (xy 66.994573 -186.765992)
			(xy 66.919003 -186.772041) (xy 66.843219 -186.770022) (xy 66.768079 -186.75996) (xy 66.694434 -186.741968)
			(xy 66.623118 -186.71625) (xy 66.554941 -186.683098) (xy 66.490673 -186.642886) (xy 66.431044 -186.596071)
			(xy 66.376728 -186.543183) (xy 66.328342 -186.484821) (xy 66.286434 -186.421646) (xy 66.251478 -186.354375)
			(xy 66.223871 -186.28377) (xy 66.203925 -186.210629) (xy 66.191866 -186.135784) (xy 66.187831 -186.06008)
			(xy 65.071752 -186.06008) (xy 65.071248 -186.097986) (xy 65.063189 -186.173367) (xy 65.047164 -186.247465)
			(xy 65.023354 -186.31944) (xy 64.992028 -186.388476) (xy 64.953541 -186.453791) (xy 64.90833 -186.514646)
			(xy 64.856906 -186.57035) (xy 64.799853 -186.620272) (xy 64.737817 -186.663847) (xy 64.6715 -186.700582)
			(xy 64.601654 -186.730059) (xy 64.529071 -186.751945) (xy 64.454573 -186.765992) (xy 64.379003 -186.772041)
			(xy 64.303219 -186.770022) (xy 64.228079 -186.75996) (xy 64.154434 -186.741968) (xy 64.083118 -186.71625)
			(xy 64.014941 -186.683098) (xy 63.950673 -186.642886) (xy 63.891044 -186.596071) (xy 63.836728 -186.543183)
			(xy 63.788342 -186.484821) (xy 63.746434 -186.421646) (xy 63.711478 -186.354375) (xy 63.683871 -186.28377)
			(xy 63.663925 -186.210629) (xy 63.651866 -186.135784) (xy 63.647831 -186.06008) (xy 43.835048 -186.06008)
			(xy 43.832019 -186.065621) (xy 43.757382 -186.18657) (xy 43.676479 -186.303421) (xy 43.589534 -186.415849)
			(xy 43.49679 -186.523542) (xy 43.398503 -186.626202) (xy 43.294946 -186.723543) (xy 43.24096 -186.769756)
			(xy 43.22345 -186.785244) (xy 43.193865 -186.82143) (xy 43.171398 -186.862418) (xy 43.156809 -186.906825)
			(xy 43.150589 -186.95315) (xy 43.152949 -186.999832) (xy 43.163809 -187.045295) (xy 43.182802 -187.088003)
			(xy 43.209288 -187.126517) (xy 43.225466 -187.14339) (xy 46.53026 -190.448184) (xy 46.53026 -191.283586)
			(xy 83.761054 -191.283586) (xy 83.761054 -191.22365) (xy 83.768877 -191.164228) (xy 83.78439 -191.106335)
			(xy 83.807326 -191.050962) (xy 83.837293 -190.999056) (xy 83.87378 -190.951506) (xy 83.91616 -190.909126)
			(xy 83.96371 -190.872639) (xy 84.015616 -190.842672) (xy 84.070989 -190.819736) (xy 84.128882 -190.804223)
			(xy 84.188304 -190.7964) (xy 84.24824 -190.7964) (xy 84.307662 -190.804223) (xy 84.365555 -190.819736)
			(xy 84.420928 -190.842672) (xy 84.472834 -190.872639) (xy 84.520384 -190.909126) (xy 84.562764 -190.951506)
			(xy 84.599251 -190.999056) (xy 84.629218 -191.050962) (xy 84.652154 -191.106335) (xy 84.667667 -191.164228)
			(xy 84.67549 -191.22365) (xy 84.67598 -191.253618) (xy 84.675939 -191.256154) (xy 85.65183 -191.256154)
			(xy 85.65183 -191.196218) (xy 85.659653 -191.136796) (xy 85.675166 -191.078903) (xy 85.698102 -191.02353)
			(xy 85.728069 -190.971624) (xy 85.764556 -190.924074) (xy 85.806936 -190.881694) (xy 85.854486 -190.845207)
			(xy 85.906392 -190.81524) (xy 85.961765 -190.792304) (xy 86.019658 -190.776791) (xy 86.07908 -190.768968)
			(xy 86.139016 -190.768968) (xy 86.198438 -190.776791) (xy 86.256331 -190.792304) (xy 86.311704 -190.81524)
			(xy 86.36361 -190.845207) (xy 86.41116 -190.881694) (xy 86.45354 -190.924074) (xy 86.490027 -190.971624)
			(xy 86.500321 -190.989454) (xy 86.946468 -190.989454) (xy 86.946468 -190.929518) (xy 86.954291 -190.870096)
			(xy 86.969804 -190.812203) (xy 86.99274 -190.75683) (xy 87.022707 -190.704924) (xy 87.059194 -190.657374)
			(xy 87.101574 -190.614994) (xy 87.149124 -190.578507) (xy 87.20103 -190.54854) (xy 87.256403 -190.525604)
			(xy 87.314296 -190.510091) (xy 87.373718 -190.502268) (xy 87.433654 -190.502268) (xy 87.493076 -190.510091)
			(xy 87.550969 -190.525604) (xy 87.606342 -190.54854) (xy 87.658248 -190.578507) (xy 87.705798 -190.614994)
			(xy 87.748178 -190.657374) (xy 87.784665 -190.704924) (xy 87.814632 -190.75683) (xy 87.837568 -190.812203)
			(xy 87.853081 -190.870096) (xy 87.860904 -190.929518) (xy 87.861394 -190.959486) (xy 87.860904 -190.989454)
			(xy 87.853081 -191.048876) (xy 87.837568 -191.106769) (xy 87.814632 -191.162142) (xy 87.784665 -191.214048)
			(xy 87.767168 -191.23685) (xy 91.63734 -191.23685) (xy 91.63734 -191.176914) (xy 91.645163 -191.117492)
			(xy 91.660676 -191.059599) (xy 91.683612 -191.004226) (xy 91.713579 -190.95232) (xy 91.750066 -190.90477)
			(xy 91.792446 -190.86239) (xy 91.839996 -190.825903) (xy 91.891902 -190.795936) (xy 91.947275 -190.773)
			(xy 92.005168 -190.757487) (xy 92.06459 -190.749664) (xy 92.124526 -190.749664) (xy 92.183948 -190.757487)
			(xy 92.241841 -190.773) (xy 92.297214 -190.795936) (xy 92.34912 -190.825903) (xy 92.39667 -190.86239)
			(xy 92.43905 -190.90477) (xy 92.475537 -190.95232) (xy 92.505504 -191.004226) (xy 92.52844 -191.059599)
			(xy 92.543953 -191.117492) (xy 92.551776 -191.176914) (xy 92.552266 -191.206882) (xy 92.551776 -191.23685)
			(xy 92.543953 -191.296272) (xy 92.52844 -191.354165) (xy 92.505504 -191.409538) (xy 92.475537 -191.461444)
			(xy 92.43905 -191.508994) (xy 92.39667 -191.551374) (xy 92.34912 -191.587861) (xy 92.297214 -191.617828)
			(xy 92.241841 -191.640764) (xy 92.183948 -191.656277) (xy 92.124526 -191.6641) (xy 92.06459 -191.6641)
			(xy 92.005168 -191.656277) (xy 91.947275 -191.640764) (xy 91.891902 -191.617828) (xy 91.839996 -191.587861)
			(xy 91.792446 -191.551374) (xy 91.750066 -191.508994) (xy 91.713579 -191.461444) (xy 91.683612 -191.409538)
			(xy 91.660676 -191.354165) (xy 91.645163 -191.296272) (xy 91.63734 -191.23685) (xy 87.767168 -191.23685)
			(xy 87.748178 -191.261598) (xy 87.705798 -191.303978) (xy 87.658248 -191.340465) (xy 87.606342 -191.370432)
			(xy 87.550969 -191.393368) (xy 87.493076 -191.408881) (xy 87.433654 -191.416704) (xy 87.373718 -191.416704)
			(xy 87.314296 -191.408881) (xy 87.256403 -191.393368) (xy 87.20103 -191.370432) (xy 87.149124 -191.340465)
			(xy 87.101574 -191.303978) (xy 87.059194 -191.261598) (xy 87.022707 -191.214048) (xy 86.99274 -191.162142)
			(xy 86.969804 -191.106769) (xy 86.954291 -191.048876) (xy 86.946468 -190.989454) (xy 86.500321 -190.989454)
			(xy 86.519994 -191.02353) (xy 86.54293 -191.078903) (xy 86.558443 -191.136796) (xy 86.566266 -191.196218)
			(xy 86.566756 -191.226186) (xy 86.566266 -191.256154) (xy 86.558443 -191.315576) (xy 86.54293 -191.373469)
			(xy 86.519994 -191.428842) (xy 86.490027 -191.480748) (xy 86.45354 -191.528298) (xy 86.41116 -191.570678)
			(xy 86.36361 -191.607165) (xy 86.311704 -191.637132) (xy 86.256331 -191.660068) (xy 86.198438 -191.675581)
			(xy 86.139016 -191.683404) (xy 86.07908 -191.683404) (xy 86.019658 -191.675581) (xy 85.961765 -191.660068)
			(xy 85.906392 -191.637132) (xy 85.854486 -191.607165) (xy 85.806936 -191.570678) (xy 85.764556 -191.528298)
			(xy 85.728069 -191.480748) (xy 85.698102 -191.428842) (xy 85.675166 -191.373469) (xy 85.659653 -191.315576)
			(xy 85.65183 -191.256154) (xy 84.675939 -191.256154) (xy 84.67549 -191.283586) (xy 84.667667 -191.343008)
			(xy 84.652154 -191.400901) (xy 84.629218 -191.456274) (xy 84.599251 -191.50818) (xy 84.562764 -191.55573)
			(xy 84.520384 -191.59811) (xy 84.472834 -191.634597) (xy 84.420928 -191.664564) (xy 84.365555 -191.6875)
			(xy 84.307662 -191.703013) (xy 84.24824 -191.710836) (xy 84.188304 -191.710836) (xy 84.128882 -191.703013)
			(xy 84.070989 -191.6875) (xy 84.015616 -191.664564) (xy 83.96371 -191.634597) (xy 83.91616 -191.59811)
			(xy 83.87378 -191.55573) (xy 83.837293 -191.50818) (xy 83.807326 -191.456274) (xy 83.78439 -191.400901)
			(xy 83.768877 -191.343008) (xy 83.761054 -191.283586) (xy 46.53026 -191.283586) (xy 46.53026 -191.714583)
			(xy 59.057077 -191.714583) (xy 59.060968 -191.660225) (xy 59.072555 -191.606974) (xy 59.091604 -191.555914)
			(xy 59.117726 -191.508086) (xy 59.150389 -191.464462) (xy 59.188929 -191.425931) (xy 59.232561 -191.393278)
			(xy 59.280395 -191.367167) (xy 59.331459 -191.34813) (xy 59.384713 -191.336555) (xy 59.439072 -191.332677)
			(xy 59.49343 -191.336576) (xy 59.546679 -191.348171) (xy 59.597736 -191.367227) (xy 59.645561 -191.393356)
			(xy 59.667648 -191.40932) (xy 59.68666 -191.422916) (xy 59.728543 -191.443648) (xy 59.773511 -191.456374)
			(xy 59.820048 -191.460664) (xy 59.866585 -191.456374) (xy 59.911553 -191.443648) (xy 59.953436 -191.422916)
			(xy 59.972448 -191.40932) (xy 59.994509 -191.393326) (xy 60.042333 -191.36721) (xy 60.093387 -191.348165)
			(xy 60.146631 -191.33658) (xy 60.200982 -191.33269) (xy 60.255334 -191.336575) (xy 60.30858 -191.348155)
			(xy 60.359635 -191.367195) (xy 60.407462 -191.393307) (xy 60.451085 -191.42596) (xy 60.489617 -191.464489)
			(xy 60.522274 -191.508109) (xy 60.548391 -191.555933) (xy 60.567435 -191.606987) (xy 60.57902 -191.660232)
			(xy 60.58291 -191.714583) (xy 61.588994 -191.714583) (xy 61.592884 -191.660229) (xy 61.604471 -191.606982)
			(xy 61.623517 -191.555925) (xy 61.649637 -191.5081) (xy 61.682297 -191.464478) (xy 61.720834 -191.42595)
			(xy 61.764461 -191.393298) (xy 61.812292 -191.367187) (xy 61.863352 -191.34815) (xy 61.916601 -191.336574)
			(xy 61.970956 -191.332694) (xy 62.02531 -191.33659) (xy 62.078556 -191.348182) (xy 62.12961 -191.367234)
			(xy 62.177433 -191.393358) (xy 62.19952 -191.40932) (xy 62.218532 -191.422916) (xy 62.260415 -191.443648)
			(xy 62.305383 -191.456374) (xy 62.35192 -191.460664) (xy 62.398457 -191.456374) (xy 62.443425 -191.443648)
			(xy 62.485308 -191.422916) (xy 62.50432 -191.40932) (xy 62.526381 -191.393324) (xy 62.574207 -191.367203)
			(xy 62.625264 -191.348154) (xy 62.678511 -191.336565) (xy 62.732867 -191.332673) (xy 62.787222 -191.336556)
			(xy 62.840472 -191.348135) (xy 62.891532 -191.367175) (xy 62.939362 -191.393288) (xy 62.982989 -191.425942)
			(xy 63.021525 -191.464473) (xy 63.054185 -191.508095) (xy 63.080304 -191.555922) (xy 63.099351 -191.60698)
			(xy 63.110937 -191.660228) (xy 63.114827 -191.714583) (xy 64.393386 -191.714583) (xy 64.397276 -191.660227)
			(xy 64.408863 -191.606978) (xy 64.427911 -191.55592) (xy 64.454031 -191.508093) (xy 64.486693 -191.46447)
			(xy 64.525231 -191.42594) (xy 64.568861 -191.393288) (xy 64.616694 -191.367177) (xy 64.667756 -191.34814)
			(xy 64.721007 -191.336564) (xy 64.775364 -191.332686) (xy 64.82972 -191.336583) (xy 64.882968 -191.348176)
			(xy 64.934023 -191.36723) (xy 64.981847 -191.393357) (xy 65.003934 -191.40932) (xy 65.022946 -191.422916)
			(xy 65.064829 -191.443648) (xy 65.109797 -191.456374) (xy 65.156334 -191.460664) (xy 65.202871 -191.456374)
			(xy 65.247839 -191.443648) (xy 65.289722 -191.422916) (xy 65.308734 -191.40932) (xy 65.330795 -191.393325)
			(xy 65.37862 -191.367206) (xy 65.429675 -191.348159) (xy 65.482921 -191.336573) (xy 65.537274 -191.332681)
			(xy 65.591628 -191.336565) (xy 65.644876 -191.348145) (xy 65.695934 -191.367185) (xy 65.743762 -191.393298)
			(xy 65.787387 -191.425951) (xy 65.825921 -191.464481) (xy 65.85858 -191.508102) (xy 65.884697 -191.555928)
			(xy 65.903743 -191.606983) (xy 65.915329 -191.66023) (xy 65.919219 -191.714583) (xy 65.917691 -191.73596)
			(xy 95.212898 -191.73596) (xy 95.212898 -191.676024) (xy 95.220721 -191.616602) (xy 95.236234 -191.558709)
			(xy 95.25917 -191.503336) (xy 95.289137 -191.45143) (xy 95.325624 -191.40388) (xy 95.368004 -191.3615)
			(xy 95.415554 -191.325013) (xy 95.46746 -191.295046) (xy 95.522833 -191.27211) (xy 95.580726 -191.256597)
			(xy 95.640148 -191.248774) (xy 95.700084 -191.248774) (xy 95.759506 -191.256597) (xy 95.817399 -191.27211)
			(xy 95.872772 -191.295046) (xy 95.924678 -191.325013) (xy 95.972228 -191.3615) (xy 96.014608 -191.40388)
			(xy 96.051095 -191.45143) (xy 96.081062 -191.503336) (xy 96.103998 -191.558709) (xy 96.119511 -191.616602)
			(xy 96.127334 -191.676024) (xy 96.127824 -191.705992) (xy 96.127334 -191.73596) (xy 96.119511 -191.795382)
			(xy 96.103998 -191.853275) (xy 96.081062 -191.908648) (xy 96.051095 -191.960554) (xy 96.014608 -192.008104)
			(xy 95.972228 -192.050484) (xy 95.924678 -192.086971) (xy 95.872772 -192.116938) (xy 95.817399 -192.139874)
			(xy 95.759506 -192.155387) (xy 95.700084 -192.16321) (xy 95.640148 -192.16321) (xy 95.580726 -192.155387)
			(xy 95.522833 -192.139874) (xy 95.46746 -192.116938) (xy 95.415554 -192.086971) (xy 95.368004 -192.050484)
			(xy 95.325624 -192.008104) (xy 95.289137 -191.960554) (xy 95.25917 -191.908648) (xy 95.236234 -191.853275)
			(xy 95.220721 -191.795382) (xy 95.212898 -191.73596) (xy 65.917691 -191.73596) (xy 65.915333 -191.768937)
			(xy 65.903752 -191.822184) (xy 65.884711 -191.873242) (xy 65.858598 -191.921069) (xy 65.825943 -191.964694)
			(xy 65.787413 -192.003227) (xy 65.74379 -192.035884) (xy 65.695964 -192.062001) (xy 65.644908 -192.081045)
			(xy 65.591661 -192.09263) (xy 65.537308 -192.096519) (xy 65.482955 -192.092632) (xy 65.429707 -192.08105)
			(xy 65.378651 -192.062008) (xy 65.330823 -192.035893) (xy 65.308734 -192.019936) (xy 65.289722 -192.00634)
			(xy 65.247839 -191.985608) (xy 65.202871 -191.972882) (xy 65.156334 -191.968592) (xy 65.109797 -191.972882)
			(xy 65.064829 -191.985608) (xy 65.022946 -192.00634) (xy 65.003934 -192.019936) (xy 64.981819 -192.035861)
			(xy 64.933993 -192.061984) (xy 64.882935 -192.081033) (xy 64.829687 -192.092622) (xy 64.775331 -192.096514)
			(xy 64.720974 -192.092631) (xy 64.667723 -192.08105) (xy 64.616663 -192.062009) (xy 64.568833 -192.035894)
			(xy 64.525206 -192.003238) (xy 64.486671 -191.964704) (xy 64.454013 -191.921079) (xy 64.427897 -191.873249)
			(xy 64.408853 -191.82219) (xy 64.397271 -191.76894) (xy 64.393386 -191.714583) (xy 63.114827 -191.714583)
			(xy 63.110942 -191.768939) (xy 63.09936 -191.822188) (xy 63.080318 -191.873247) (xy 63.054203 -191.921076)
			(xy 63.021547 -191.964702) (xy 62.983015 -192.003236) (xy 62.939391 -192.035894) (xy 62.891562 -192.062011)
			(xy 62.840504 -192.081055) (xy 62.787256 -192.092639) (xy 62.7329 -192.096527) (xy 62.678545 -192.092639)
			(xy 62.625296 -192.081055) (xy 62.574238 -192.062011) (xy 62.52641 -192.035894) (xy 62.50432 -192.019936)
			(xy 62.485308 -192.00634) (xy 62.443425 -191.985608) (xy 62.398457 -191.972882) (xy 62.35192 -191.968592)
			(xy 62.305383 -191.972882) (xy 62.260415 -191.985608) (xy 62.218532 -192.00634) (xy 62.19952 -192.019936)
			(xy 62.177405 -192.03586) (xy 62.12958 -192.06198) (xy 62.078524 -192.081028) (xy 62.025277 -192.092615)
			(xy 61.970923 -192.096506) (xy 61.916568 -192.092622) (xy 61.863319 -192.081041) (xy 61.812261 -192.061999)
			(xy 61.764433 -192.035884) (xy 61.720808 -192.003228) (xy 61.682275 -191.964696) (xy 61.649619 -191.921072)
			(xy 61.623503 -191.873244) (xy 61.604461 -191.822186) (xy 61.592879 -191.768938) (xy 61.588994 -191.714583)
			(xy 60.58291 -191.714583) (xy 60.579025 -191.768935) (xy 60.567445 -191.822181) (xy 60.548405 -191.873236)
			(xy 60.522292 -191.921062) (xy 60.489639 -191.964686) (xy 60.45111 -192.003218) (xy 60.40749 -192.035874)
			(xy 60.359666 -192.061991) (xy 60.308612 -192.081036) (xy 60.255367 -192.092621) (xy 60.201016 -192.09651)
			(xy 60.146664 -192.092625) (xy 60.093419 -192.081045) (xy 60.042363 -192.062004) (xy 59.994537 -192.035892)
			(xy 59.972448 -192.019936) (xy 59.953436 -192.00634) (xy 59.911553 -191.985608) (xy 59.866585 -191.972882)
			(xy 59.820048 -191.968592) (xy 59.773511 -191.972882) (xy 59.728543 -191.985608) (xy 59.68666 -192.00634)
			(xy 59.667648 -192.019936) (xy 59.645532 -192.035862) (xy 59.597705 -192.061987) (xy 59.546647 -192.081039)
			(xy 59.493396 -192.092629) (xy 59.439039 -192.096523) (xy 59.38468 -192.09264) (xy 59.331427 -192.08106)
			(xy 59.280365 -192.062019) (xy 59.232532 -192.035904) (xy 59.188904 -192.003247) (xy 59.150367 -191.964713)
			(xy 59.117708 -191.921086) (xy 59.09159 -191.873255) (xy 59.072546 -191.822194) (xy 59.060963 -191.768942)
			(xy 59.057077 -191.714583) (xy 46.53026 -191.714583) (xy 46.53026 -192.567048) (xy 82.733878 -192.567048)
			(xy 82.733878 -192.507112) (xy 82.741701 -192.44769) (xy 82.757214 -192.389797) (xy 82.78015 -192.334424)
			(xy 82.810117 -192.282518) (xy 82.846604 -192.234968) (xy 82.888984 -192.192588) (xy 82.936534 -192.156101)
			(xy 82.98844 -192.126134) (xy 83.043813 -192.103198) (xy 83.101706 -192.087685) (xy 83.161128 -192.079862)
			(xy 83.221064 -192.079862) (xy 83.280486 -192.087685) (xy 83.338379 -192.103198) (xy 83.393752 -192.126134)
			(xy 83.445658 -192.156101) (xy 83.493208 -192.192588) (xy 83.535588 -192.234968) (xy 83.572075 -192.282518)
			(xy 83.602042 -192.334424) (xy 83.624978 -192.389797) (xy 83.640491 -192.44769) (xy 83.648314 -192.507112)
			(xy 83.648804 -192.53708) (xy 83.648314 -192.567048) (xy 83.640491 -192.62647) (xy 83.624978 -192.684363)
			(xy 83.613812 -192.71132) (xy 84.381322 -192.71132) (xy 84.381322 -192.651384) (xy 84.389145 -192.591962)
			(xy 84.404658 -192.534069) (xy 84.427594 -192.478696) (xy 84.457561 -192.42679) (xy 84.494048 -192.37924)
			(xy 84.536428 -192.33686) (xy 84.583978 -192.300373) (xy 84.635884 -192.270406) (xy 84.691257 -192.24747)
			(xy 84.74915 -192.231957) (xy 84.808572 -192.224134) (xy 84.868508 -192.224134) (xy 84.92793 -192.231957)
			(xy 84.985823 -192.24747) (xy 85.041196 -192.270406) (xy 85.093102 -192.300373) (xy 85.140652 -192.33686)
			(xy 85.183032 -192.37924) (xy 85.219519 -192.42679) (xy 85.249486 -192.478696) (xy 85.272422 -192.534069)
			(xy 85.287935 -192.591962) (xy 85.295758 -192.651384) (xy 85.296248 -192.681352) (xy 85.295758 -192.71132)
			(xy 85.287935 -192.770742) (xy 85.272422 -192.828635) (xy 85.249486 -192.884008) (xy 85.219519 -192.935914)
			(xy 85.183032 -192.983464) (xy 85.140652 -193.025844) (xy 85.093102 -193.062331) (xy 85.041196 -193.092298)
			(xy 84.985823 -193.115234) (xy 84.92793 -193.130747) (xy 84.868508 -193.13857) (xy 84.808572 -193.13857)
			(xy 84.74915 -193.130747) (xy 84.691257 -193.115234) (xy 84.635884 -193.092298) (xy 84.583978 -193.062331)
			(xy 84.536428 -193.025844) (xy 84.494048 -192.983464) (xy 84.457561 -192.935914) (xy 84.427594 -192.884008)
			(xy 84.404658 -192.828635) (xy 84.389145 -192.770742) (xy 84.381322 -192.71132) (xy 83.613812 -192.71132)
			(xy 83.602042 -192.739736) (xy 83.572075 -192.791642) (xy 83.535588 -192.839192) (xy 83.493208 -192.881572)
			(xy 83.445658 -192.918059) (xy 83.393752 -192.948026) (xy 83.338379 -192.970962) (xy 83.280486 -192.986475)
			(xy 83.221064 -192.994298) (xy 83.161128 -192.994298) (xy 83.101706 -192.986475) (xy 83.043813 -192.970962)
			(xy 82.98844 -192.948026) (xy 82.936534 -192.918059) (xy 82.888984 -192.881572) (xy 82.846604 -192.839192)
			(xy 82.810117 -192.791642) (xy 82.78015 -192.739736) (xy 82.757214 -192.684363) (xy 82.741701 -192.62647)
			(xy 82.733878 -192.567048) (xy 46.53026 -192.567048) (xy 46.53026 -193.677476) (xy 59.057087 -193.677476)
			(xy 59.060978 -193.623119) (xy 59.072566 -193.56987) (xy 59.091616 -193.518812) (xy 59.117738 -193.470985)
			(xy 59.150401 -193.427363) (xy 59.188941 -193.388834) (xy 59.232572 -193.356182) (xy 59.280406 -193.330073)
			(xy 59.331469 -193.311037) (xy 59.384722 -193.299463) (xy 59.439079 -193.295587) (xy 59.493435 -193.299486)
			(xy 59.546683 -193.311082) (xy 59.597738 -193.330139) (xy 59.645562 -193.356268) (xy 59.667648 -193.372232)
			(xy 59.68666 -193.385828) (xy 59.728543 -193.40656) (xy 59.773511 -193.419286) (xy 59.820048 -193.423576)
			(xy 59.866585 -193.419286) (xy 59.911553 -193.40656) (xy 59.953436 -193.385828) (xy 59.972448 -193.372232)
			(xy 59.994498 -193.356222) (xy 60.042322 -193.330104) (xy 60.093377 -193.311058) (xy 60.146623 -193.299471)
			(xy 60.200975 -193.29558) (xy 60.255328 -193.299464) (xy 60.308576 -193.311044) (xy 60.359633 -193.330083)
			(xy 60.407461 -193.356195) (xy 60.451086 -193.388848) (xy 60.48962 -193.427377) (xy 60.522278 -193.470998)
			(xy 60.548396 -193.518823) (xy 60.567443 -193.569878) (xy 60.579029 -193.623123) (xy 60.58292 -193.677476)
			(xy 61.589004 -193.677476) (xy 61.592895 -193.623123) (xy 61.604482 -193.569877) (xy 61.623529 -193.518823)
			(xy 61.649649 -193.470999) (xy 61.682309 -193.427379) (xy 61.720845 -193.388852) (xy 61.764472 -193.356202)
			(xy 61.812302 -193.330093) (xy 61.863361 -193.311057) (xy 61.91661 -193.299482) (xy 61.970963 -193.295604)
			(xy 62.025316 -193.2995) (xy 62.07856 -193.311093) (xy 62.129613 -193.330146) (xy 62.177434 -193.35627)
			(xy 62.19952 -193.372232) (xy 62.218532 -193.385828) (xy 62.260415 -193.40656) (xy 62.305383 -193.419286)
			(xy 62.35192 -193.423576) (xy 62.398457 -193.419286) (xy 62.443425 -193.40656) (xy 62.485308 -193.385828)
			(xy 62.50432 -193.372232) (xy 62.52637 -193.35622) (xy 62.574197 -193.330097) (xy 62.625254 -193.311047)
			(xy 62.678503 -193.299457) (xy 62.732859 -193.295563) (xy 62.787216 -193.299445) (xy 62.840468 -193.311024)
			(xy 62.891529 -193.330063) (xy 62.939361 -193.356176) (xy 62.98299 -193.38883) (xy 63.021528 -193.427361)
			(xy 63.054189 -193.470984) (xy 63.08031 -193.518812) (xy 63.099358 -193.56987) (xy 63.110945 -193.623119)
			(xy 63.114837 -193.677476) (xy 64.393395 -193.677476) (xy 64.397286 -193.623121) (xy 64.408874 -193.569874)
			(xy 64.427922 -193.518817) (xy 64.454043 -193.470992) (xy 64.486705 -193.427371) (xy 64.525243 -193.388843)
			(xy 64.568872 -193.356192) (xy 64.616704 -193.330083) (xy 64.667765 -193.311047) (xy 64.721016 -193.299473)
			(xy 64.775371 -193.295595) (xy 64.829726 -193.299493) (xy 64.882972 -193.311087) (xy 64.934026 -193.330142)
			(xy 64.981848 -193.356269) (xy 65.003934 -193.372232) (xy 65.022946 -193.385828) (xy 65.064829 -193.40656)
			(xy 65.109797 -193.419286) (xy 65.156334 -193.423576) (xy 65.202871 -193.419286) (xy 65.247839 -193.40656)
			(xy 65.289722 -193.385828) (xy 65.308734 -193.372232) (xy 65.330784 -193.356221) (xy 65.378609 -193.3301)
			(xy 65.429665 -193.311052) (xy 65.482913 -193.299464) (xy 65.537267 -193.295572) (xy 65.591622 -193.299455)
			(xy 65.644872 -193.311034) (xy 65.695931 -193.330073) (xy 65.743761 -193.356186) (xy 65.787388 -193.388839)
			(xy 65.825924 -193.427369) (xy 65.858584 -193.470991) (xy 65.884703 -193.518817) (xy 65.90375 -193.569874)
			(xy 65.915337 -193.623121) (xy 65.919228 -193.677476) (xy 65.915344 -193.731831) (xy 65.910525 -193.75399)
			(xy 83.194126 -193.75399) (xy 83.194126 -193.694054) (xy 83.201949 -193.634632) (xy 83.217462 -193.576739)
			(xy 83.240398 -193.521366) (xy 83.270365 -193.46946) (xy 83.306852 -193.42191) (xy 83.349232 -193.37953)
			(xy 83.396782 -193.343043) (xy 83.448688 -193.313076) (xy 83.504061 -193.29014) (xy 83.561954 -193.274627)
			(xy 83.621376 -193.266804) (xy 83.681312 -193.266804) (xy 83.740734 -193.274627) (xy 83.798627 -193.29014)
			(xy 83.854 -193.313076) (xy 83.905906 -193.343043) (xy 83.953456 -193.37953) (xy 83.995836 -193.42191)
			(xy 84.032323 -193.46946) (xy 84.06229 -193.521366) (xy 84.085226 -193.576739) (xy 84.100739 -193.634632)
			(xy 84.108562 -193.694054) (xy 84.109052 -193.724022) (xy 84.108562 -193.75399) (xy 84.100739 -193.813412)
			(xy 84.085226 -193.871305) (xy 84.06229 -193.926678) (xy 84.032323 -193.978584) (xy 83.995836 -194.026134)
			(xy 83.953456 -194.068514) (xy 83.905906 -194.105001) (xy 83.854 -194.134968) (xy 83.798627 -194.157904)
			(xy 83.740734 -194.173417) (xy 83.681312 -194.18124) (xy 83.621376 -194.18124) (xy 83.561954 -194.173417)
			(xy 83.504061 -194.157904) (xy 83.448688 -194.134968) (xy 83.396782 -194.105001) (xy 83.349232 -194.068514)
			(xy 83.306852 -194.026134) (xy 83.270365 -193.978584) (xy 83.240398 -193.926678) (xy 83.217462 -193.871305)
			(xy 83.201949 -193.813412) (xy 83.194126 -193.75399) (xy 65.910525 -193.75399) (xy 65.903764 -193.78508)
			(xy 65.884723 -193.836139) (xy 65.85861 -193.883968) (xy 65.825955 -193.927595) (xy 65.787424 -193.966129)
			(xy 65.743801 -193.998788) (xy 65.695975 -194.024907) (xy 65.644918 -194.043953) (xy 65.59167 -194.055538)
			(xy 65.537315 -194.059428) (xy 65.48296 -194.055543) (xy 65.429712 -194.043961) (xy 65.378653 -194.024919)
			(xy 65.330824 -193.998805) (xy 65.308734 -193.982848) (xy 65.289722 -193.969252) (xy 65.247839 -193.94852)
			(xy 65.202871 -193.935794) (xy 65.156334 -193.931504) (xy 65.109797 -193.935794) (xy 65.064829 -193.94852)
			(xy 65.022946 -193.969252) (xy 65.003934 -193.982848) (xy 64.981808 -193.998757) (xy 64.933982 -194.024878)
			(xy 64.882926 -194.043926) (xy 64.829678 -194.055514) (xy 64.775323 -194.059405) (xy 64.720968 -194.05552)
			(xy 64.667719 -194.043939) (xy 64.61666 -194.024897) (xy 64.568832 -193.998782) (xy 64.525207 -193.966126)
			(xy 64.486674 -193.927593) (xy 64.454018 -193.883968) (xy 64.427902 -193.836139) (xy 64.408861 -193.78508)
			(xy 64.39728 -193.731831) (xy 64.393395 -193.677476) (xy 63.114837 -193.677476) (xy 63.110952 -193.731833)
			(xy 63.099371 -193.785084) (xy 63.08033 -193.836144) (xy 63.054215 -193.883975) (xy 63.021559 -193.927603)
			(xy 62.983027 -193.966139) (xy 62.939402 -193.998798) (xy 62.891573 -194.024917) (xy 62.840514 -194.043963)
			(xy 62.787264 -194.055548) (xy 62.732907 -194.059437) (xy 62.678551 -194.05555) (xy 62.6253 -194.043967)
			(xy 62.57424 -194.024923) (xy 62.526411 -193.998806) (xy 62.50432 -193.982848) (xy 62.485308 -193.969252)
			(xy 62.443425 -193.94852) (xy 62.398457 -193.935794) (xy 62.35192 -193.931504) (xy 62.305383 -193.935794)
			(xy 62.260415 -193.94852) (xy 62.218532 -193.969252) (xy 62.19952 -193.982848) (xy 62.177394 -193.998756)
			(xy 62.129569 -194.024874) (xy 62.078514 -194.043921) (xy 62.025268 -194.055507) (xy 61.970915 -194.059396)
			(xy 61.916562 -194.055511) (xy 61.863315 -194.043929) (xy 61.812259 -194.024887) (xy 61.764432 -193.998772)
			(xy 61.720809 -193.966116) (xy 61.682278 -193.927584) (xy 61.649623 -193.883961) (xy 61.623509 -193.836133)
			(xy 61.604468 -193.785077) (xy 61.592888 -193.731829) (xy 61.589004 -193.677476) (xy 60.58292 -193.677476)
			(xy 60.579036 -193.731829) (xy 60.567456 -193.785076) (xy 60.548416 -193.836134) (xy 60.522304 -193.883961)
			(xy 60.489651 -193.927586) (xy 60.451122 -193.96612) (xy 60.407501 -193.998779) (xy 60.359677 -194.024897)
			(xy 60.308622 -194.043943) (xy 60.255376 -194.055529) (xy 60.201023 -194.05942) (xy 60.14667 -194.055536)
			(xy 60.093423 -194.043956) (xy 60.042366 -194.024916) (xy 59.994538 -193.998804) (xy 59.972448 -193.982848)
			(xy 59.953436 -193.969252) (xy 59.911553 -193.94852) (xy 59.866585 -193.935794) (xy 59.820048 -193.931504)
			(xy 59.773511 -193.935794) (xy 59.728543 -193.94852) (xy 59.68666 -193.969252) (xy 59.667648 -193.982848)
			(xy 59.645521 -193.998758) (xy 59.597695 -194.024881) (xy 59.546637 -194.043931) (xy 59.493388 -194.055521)
			(xy 59.439031 -194.059413) (xy 59.384674 -194.05553) (xy 59.331423 -194.043949) (xy 59.280362 -194.024907)
			(xy 59.232532 -193.998792) (xy 59.188905 -193.966135) (xy 59.15037 -193.927601) (xy 59.117712 -193.883975)
			(xy 59.091596 -193.836144) (xy 59.072553 -193.785084) (xy 59.060971 -193.731833) (xy 59.057087 -193.677476)
			(xy 46.53026 -193.677476) (xy 46.53026 -195.820972) (xy 59.057092 -195.820972) (xy 59.060983 -195.766616)
			(xy 59.072572 -195.713368) (xy 59.091622 -195.662311) (xy 59.117744 -195.614485) (xy 59.150407 -195.570863)
			(xy 59.188947 -195.532335) (xy 59.232578 -195.499684) (xy 59.280411 -195.473576) (xy 59.331474 -195.454541)
			(xy 59.384726 -195.442968) (xy 59.439083 -195.439092) (xy 59.493438 -195.442991) (xy 59.546685 -195.454588)
			(xy 59.59774 -195.473645) (xy 59.645562 -195.499774) (xy 59.667648 -195.515738) (xy 59.68666 -195.529334)
			(xy 59.728543 -195.550066) (xy 59.773511 -195.562792) (xy 59.820048 -195.567082) (xy 59.866585 -195.562792)
			(xy 59.911553 -195.550066) (xy 59.953436 -195.529334) (xy 59.972448 -195.515738) (xy 59.994492 -195.49972)
			(xy 60.042317 -195.473601) (xy 60.093372 -195.454554) (xy 60.146618 -195.442967) (xy 60.200972 -195.439075)
			(xy 60.255326 -195.442959) (xy 60.308574 -195.454538) (xy 60.359632 -195.473577) (xy 60.40746 -195.499689)
			(xy 60.451086 -195.532342) (xy 60.489621 -195.570871) (xy 60.52228 -195.614493) (xy 60.548399 -195.662318)
			(xy 60.567446 -195.713373) (xy 60.579033 -195.766619) (xy 60.582925 -195.820972) (xy 61.589008 -195.820972)
			(xy 61.5929 -195.76662) (xy 61.604487 -195.713375) (xy 61.623535 -195.662322) (xy 61.649655 -195.614498)
			(xy 61.682315 -195.57088) (xy 61.720851 -195.532353) (xy 61.764478 -195.499704) (xy 61.812308 -195.473596)
			(xy 61.863366 -195.454561) (xy 61.916614 -195.442986) (xy 61.970967 -195.439108) (xy 62.025319 -195.443005)
			(xy 62.078563 -195.454599) (xy 62.129614 -195.473651) (xy 62.177435 -195.499776) (xy 62.19952 -195.515738)
			(xy 62.218532 -195.529334) (xy 62.260415 -195.550066) (xy 62.305383 -195.562792) (xy 62.35192 -195.567082)
			(xy 62.398457 -195.562792) (xy 62.443425 -195.550066) (xy 62.485308 -195.529334) (xy 62.50432 -195.515738)
			(xy 62.526365 -195.499718) (xy 62.574191 -195.473594) (xy 62.625249 -195.454543) (xy 62.678499 -195.442953)
			(xy 62.732856 -195.439059) (xy 62.787214 -195.44294) (xy 62.840466 -195.454518) (xy 62.891528 -195.473557)
			(xy 62.939361 -195.49967) (xy 62.982991 -195.532324) (xy 63.021529 -195.570855) (xy 63.054191 -195.614479)
			(xy 63.080313 -195.662307) (xy 63.099361 -195.713365) (xy 63.11095 -195.766615) (xy 63.114841 -195.820972)
			(xy 64.3934 -195.820972) (xy 64.397292 -195.766618) (xy 64.40888 -195.713372) (xy 64.427928 -195.662316)
			(xy 64.454049 -195.614492) (xy 64.486711 -195.570871) (xy 64.525249 -195.532344) (xy 64.568878 -195.499694)
			(xy 64.616709 -195.473586) (xy 64.66777 -195.454551) (xy 64.72102 -195.442977) (xy 64.775375 -195.4391)
			(xy 64.829729 -195.442998) (xy 64.882974 -195.454593) (xy 64.934027 -195.473648) (xy 64.981848 -195.499775)
			(xy 65.003934 -195.515738) (xy 65.022946 -195.529334) (xy 65.064829 -195.550066) (xy 65.109797 -195.562792)
			(xy 65.156334 -195.567082) (xy 65.202871 -195.562792) (xy 65.247839 -195.550066) (xy 65.289722 -195.529334)
			(xy 65.308734 -195.515738) (xy 65.330778 -195.499719) (xy 65.378604 -195.473598) (xy 65.429661 -195.454549)
			(xy 65.482909 -195.44296) (xy 65.537264 -195.439067) (xy 65.59162 -195.44295) (xy 65.64487 -195.454528)
			(xy 65.69593 -195.473567) (xy 65.743761 -195.49968) (xy 65.787388 -195.532333) (xy 65.825925 -195.570863)
			(xy 65.858586 -195.614486) (xy 65.884706 -195.662312) (xy 65.903754 -195.713369) (xy 65.915341 -195.766617)
			(xy 65.919233 -195.820972) (xy 65.915349 -195.875328) (xy 65.903769 -195.928578) (xy 65.884729 -195.979638)
			(xy 65.858616 -196.027468) (xy 65.825961 -196.071095) (xy 65.78743 -196.109631) (xy 65.743807 -196.142291)
			(xy 65.69598 -196.16841) (xy 65.644923 -196.187456) (xy 65.591674 -196.199043) (xy 65.537319 -196.202933)
			(xy 65.482963 -196.199048) (xy 65.429714 -196.187467) (xy 65.378654 -196.168425) (xy 65.330825 -196.142311)
			(xy 65.308734 -196.126354) (xy 65.289722 -196.112758) (xy 65.247839 -196.092026) (xy 65.202871 -196.0793)
			(xy 65.156334 -196.07501) (xy 65.109797 -196.0793) (xy 65.064829 -196.092026) (xy 65.022946 -196.112758)
			(xy 65.003934 -196.126354) (xy 64.981802 -196.142255) (xy 64.933977 -196.168375) (xy 64.882921 -196.187422)
			(xy 64.829674 -196.199009) (xy 64.77532 -196.2029) (xy 64.720965 -196.199015) (xy 64.667717 -196.187434)
			(xy 64.616659 -196.168391) (xy 64.568831 -196.142276) (xy 64.525207 -196.10962) (xy 64.486675 -196.071087)
			(xy 64.45402 -196.027462) (xy 64.427905 -195.979634) (xy 64.408864 -195.928575) (xy 64.397284 -195.875327)
			(xy 64.3934 -195.820972) (xy 63.114841 -195.820972) (xy 63.110957 -195.87533) (xy 63.099377 -195.928582)
			(xy 63.080336 -195.979643) (xy 63.054221 -196.027475) (xy 63.021565 -196.071103) (xy 62.983032 -196.10964)
			(xy 62.939407 -196.1423) (xy 62.891578 -196.16842) (xy 62.840519 -196.187466) (xy 62.787268 -196.199052)
			(xy 62.732911 -196.202941) (xy 62.678553 -196.199055) (xy 62.625302 -196.187472) (xy 62.574242 -196.168429)
			(xy 62.526411 -196.142312) (xy 62.50432 -196.126354) (xy 62.485308 -196.112758) (xy 62.443425 -196.092026)
			(xy 62.398457 -196.0793) (xy 62.35192 -196.07501) (xy 62.305383 -196.0793) (xy 62.260415 -196.092026)
			(xy 62.218532 -196.112758) (xy 62.19952 -196.126354) (xy 62.177388 -196.142254) (xy 62.129564 -196.168372)
			(xy 62.07851 -196.187417) (xy 62.025264 -196.199002) (xy 61.970912 -196.202892) (xy 61.916559 -196.199006)
			(xy 61.863313 -196.187424) (xy 61.812257 -196.168381) (xy 61.764432 -196.142266) (xy 61.72081 -196.10961)
			(xy 61.682279 -196.071079) (xy 61.649625 -196.027455) (xy 61.623512 -195.979628) (xy 61.604472 -195.928572)
			(xy 61.592892 -195.875325) (xy 61.589008 -195.820972) (xy 60.582925 -195.820972) (xy 60.579041 -195.875326)
			(xy 60.567462 -195.928574) (xy 60.548422 -195.979632) (xy 60.52231 -196.027461) (xy 60.489657 -196.071087)
			(xy 60.451128 -196.109622) (xy 60.407507 -196.142281) (xy 60.359682 -196.1684) (xy 60.308626 -196.187446)
			(xy 60.25538 -196.199033) (xy 60.201027 -196.202925) (xy 60.146673 -196.199041) (xy 60.093425 -196.187461)
			(xy 60.042367 -196.168422) (xy 59.994538 -196.14231) (xy 59.972448 -196.126354) (xy 59.953436 -196.112758)
			(xy 59.911553 -196.092026) (xy 59.866585 -196.0793) (xy 59.820048 -196.07501) (xy 59.773511 -196.0793)
			(xy 59.728543 -196.092026) (xy 59.68666 -196.112758) (xy 59.667648 -196.126354) (xy 59.645516 -196.142256)
			(xy 59.597689 -196.168378) (xy 59.546632 -196.187428) (xy 59.493384 -196.199017) (xy 59.439028 -196.202908)
			(xy 59.384671 -196.199024) (xy 59.331421 -196.187443) (xy 59.280361 -196.168401) (xy 59.232531 -196.142286)
			(xy 59.188905 -196.109629) (xy 59.150371 -196.071095) (xy 59.117714 -196.027469) (xy 59.091599 -195.979639)
			(xy 59.072557 -195.928579) (xy 59.060976 -195.875329) (xy 59.057092 -195.820972) (xy 46.53026 -195.820972)
			(xy 46.53026 -195.903596) (xy 51.402996 -195.903596) (xy 53.055012 -195.903596) (xy 53.055012 -197.555612)
			(xy 51.402996 -197.555612) (xy 51.402996 -195.903596) (xy 46.53026 -195.903596) (xy 46.53026 -196.770159)
			(xy 47.903374 -196.770159) (xy 47.903374 -196.689049) (xy 47.911324 -196.60833) (xy 47.927147 -196.528779)
			(xy 47.950692 -196.451163) (xy 47.981731 -196.376227) (xy 48.019966 -196.304695) (xy 48.065028 -196.237255)
			(xy 48.116483 -196.174556) (xy 48.173836 -196.117203) (xy 48.236535 -196.065748) (xy 48.303975 -196.020686)
			(xy 48.375507 -195.982451) (xy 48.450443 -195.951412) (xy 48.528059 -195.927867) (xy 48.60761 -195.912044)
			(xy 48.688329 -195.904094) (xy 48.769439 -195.904094) (xy 48.850158 -195.912044) (xy 48.929709 -195.927867)
			(xy 49.007325 -195.951412) (xy 49.082261 -195.982451) (xy 49.153793 -196.020686) (xy 49.221233 -196.065748)
			(xy 49.283932 -196.117203) (xy 49.341285 -196.174556) (xy 49.39274 -196.237255) (xy 49.437802 -196.304695)
			(xy 49.476037 -196.376227) (xy 49.507076 -196.451163) (xy 49.530621 -196.528779) (xy 49.546444 -196.60833)
			(xy 49.554394 -196.689049) (xy 49.554892 -196.729604) (xy 49.554394 -196.770159) (xy 49.546444 -196.850878)
			(xy 49.530621 -196.930429) (xy 49.507076 -197.008045) (xy 49.476037 -197.082981) (xy 49.437802 -197.154513)
			(xy 49.39274 -197.221953) (xy 49.341285 -197.284652) (xy 49.283932 -197.342005) (xy 49.221233 -197.39346)
			(xy 49.153793 -197.438522) (xy 49.082261 -197.476757) (xy 49.007325 -197.507796) (xy 48.929709 -197.531341)
			(xy 48.850158 -197.547164) (xy 48.769439 -197.555114) (xy 48.688329 -197.555114) (xy 48.60761 -197.547164)
			(xy 48.528059 -197.531341) (xy 48.450443 -197.507796) (xy 48.375507 -197.476757) (xy 48.303975 -197.438522)
			(xy 48.236535 -197.39346) (xy 48.173836 -197.342005) (xy 48.116483 -197.284652) (xy 48.065028 -197.221953)
			(xy 48.019966 -197.154513) (xy 47.981731 -197.082981) (xy 47.950692 -197.008045) (xy 47.927147 -196.930429)
			(xy 47.911324 -196.850878) (xy 47.903374 -196.770159) (xy 46.53026 -196.770159) (xy 46.53026 -197.81012)
			(xy 86.39887 -197.81012) (xy 86.402874 -197.610022) (xy 86.414881 -197.410244) (xy 86.434872 -197.211107)
			(xy 86.462814 -197.012929) (xy 86.498662 -196.816027) (xy 86.54236 -196.620718) (xy 86.593837 -196.427313)
			(xy 86.653011 -196.236123) (xy 86.719787 -196.047453) (xy 86.794059 -195.861606) (xy 86.875706 -195.678879)
			(xy 86.964599 -195.499566) (xy 87.060595 -195.323952) (xy 87.16354 -195.15232) (xy 87.27327 -194.984944)
			(xy 87.389608 -194.822093) (xy 87.512369 -194.664026) (xy 87.641356 -194.510998) (xy 87.776363 -194.363253)
			(xy 87.917172 -194.221027) (xy 88.063559 -194.08455) (xy 88.215289 -193.954038) (xy 88.37212 -193.829702)
			(xy 88.533799 -193.71174) (xy 88.700069 -193.600341) (xy 88.870662 -193.495684) (xy 89.045306 -193.397936)
			(xy 89.223722 -193.307253) (xy 89.405622 -193.223782) (xy 89.590717 -193.147655) (xy 89.778709 -193.078995)
			(xy 89.969298 -193.017911) (xy 90.162178 -192.964501) (xy 90.35704 -192.918852) (xy 90.553573 -192.881035)
			(xy 90.751462 -192.851111) (xy 90.950389 -192.829129) (xy 91.150037 -192.815124) (xy 91.350085 -192.809118)
			(xy 91.550213 -192.81112) (xy 91.750101 -192.821128) (xy 91.949428 -192.839125) (xy 92.147876 -192.865083)
			(xy 92.345126 -192.89896) (xy 92.540863 -192.940702) (xy 92.734773 -192.990241) (xy 92.926546 -193.047499)
			(xy 93.115875 -193.112384) (xy 93.302455 -193.184792) (xy 93.48599 -193.264608) (xy 93.666184 -193.351702)
			(xy 93.842749 -193.445936) (xy 94.015402 -193.547159) (xy 94.183867 -193.655209) (xy 94.347875 -193.769912)
			(xy 94.507162 -193.891086) (xy 94.661473 -194.018535) (xy 94.810561 -194.152056) (xy 94.954188 -194.291436)
			(xy 95.092124 -194.43645) (xy 95.224147 -194.586867) (xy 95.350046 -194.742445) (xy 95.46962 -194.902937)
			(xy 95.555447 -195.028308) (xy 96.79735 -195.028308) (xy 96.79735 -194.968372) (xy 96.805173 -194.90895)
			(xy 96.820686 -194.851057) (xy 96.843622 -194.795684) (xy 96.873589 -194.743778) (xy 96.910076 -194.696228)
			(xy 96.952456 -194.653848) (xy 97.000006 -194.617361) (xy 97.051912 -194.587394) (xy 97.107285 -194.564458)
			(xy 97.165178 -194.548945) (xy 97.2246 -194.541122) (xy 97.284536 -194.541122) (xy 97.343958 -194.548945)
			(xy 97.401851 -194.564458) (xy 97.457224 -194.587394) (xy 97.50913 -194.617361) (xy 97.55668 -194.653848)
			(xy 97.59906 -194.696228) (xy 97.635547 -194.743778) (xy 97.665514 -194.795684) (xy 97.68845 -194.851057)
			(xy 97.703963 -194.90895) (xy 97.711786 -194.968372) (xy 97.712276 -194.99834) (xy 97.711786 -195.028308)
			(xy 97.703963 -195.08773) (xy 97.68845 -195.145623) (xy 97.665514 -195.200996) (xy 97.635547 -195.252902)
			(xy 97.59906 -195.300452) (xy 97.55668 -195.342832) (xy 97.50913 -195.379319) (xy 97.457224 -195.409286)
			(xy 97.401851 -195.432222) (xy 97.343958 -195.447735) (xy 97.284536 -195.455558) (xy 97.2246 -195.455558)
			(xy 97.165178 -195.447735) (xy 97.107285 -195.432222) (xy 97.051912 -195.409286) (xy 97.000006 -195.379319)
			(xy 96.952456 -195.342832) (xy 96.910076 -195.300452) (xy 96.873589 -195.252902) (xy 96.843622 -195.200996)
			(xy 96.820686 -195.145623) (xy 96.805173 -195.08773) (xy 96.79735 -195.028308) (xy 95.555447 -195.028308)
			(xy 95.582676 -195.068083) (xy 95.689035 -195.237621) (xy 95.788526 -195.411279) (xy 95.880989 -195.588778)
			(xy 95.966276 -195.769834) (xy 96.044251 -195.954158) (xy 96.114788 -196.141454) (xy 96.177776 -196.331422)
			(xy 96.233113 -196.523758) (xy 96.279159 -196.71182) (xy 97.787442 -196.71182) (xy 97.787442 -196.651884)
			(xy 97.795265 -196.592462) (xy 97.810778 -196.534569) (xy 97.833714 -196.479196) (xy 97.863681 -196.42729)
			(xy 97.900168 -196.37974) (xy 97.942548 -196.33736) (xy 97.990098 -196.300873) (xy 98.042004 -196.270906)
			(xy 98.097377 -196.24797) (xy 98.15527 -196.232457) (xy 98.214692 -196.224634) (xy 98.274628 -196.224634)
			(xy 98.33405 -196.232457) (xy 98.391943 -196.24797) (xy 98.447316 -196.270906) (xy 98.499222 -196.300873)
			(xy 98.546772 -196.33736) (xy 98.589152 -196.37974) (xy 98.625639 -196.42729) (xy 98.655606 -196.479196)
			(xy 98.678542 -196.534569) (xy 98.694055 -196.592462) (xy 98.701878 -196.651884) (xy 98.702368 -196.681852)
			(xy 98.701878 -196.71182) (xy 98.694055 -196.771242) (xy 98.678542 -196.829135) (xy 98.655606 -196.884508)
			(xy 98.625639 -196.936414) (xy 98.589152 -196.983964) (xy 98.546772 -197.026344) (xy 98.499222 -197.062831)
			(xy 98.447316 -197.092798) (xy 98.391943 -197.115734) (xy 98.33405 -197.131247) (xy 98.274628 -197.13907)
			(xy 98.214692 -197.13907) (xy 98.15527 -197.131247) (xy 98.097377 -197.115734) (xy 98.042004 -197.092798)
			(xy 97.990098 -197.062831) (xy 97.942548 -197.026344) (xy 97.900168 -196.983964) (xy 97.863681 -196.936414)
			(xy 97.833714 -196.884508) (xy 97.810778 -196.829135) (xy 97.795265 -196.771242) (xy 97.787442 -196.71182)
			(xy 96.279159 -196.71182) (xy 96.28071 -196.718154) (xy 96.320491 -196.914299) (xy 96.352393 -197.111878)
			(xy 96.376364 -197.310575) (xy 96.392366 -197.510073) (xy 96.400373 -197.710051) (xy 96.400874 -197.81012)
			(xy 96.400373 -197.910189) (xy 96.392366 -198.110167) (xy 96.376364 -198.309665) (xy 96.352393 -198.508362)
			(xy 96.320491 -198.705941) (xy 96.28071 -198.902086) (xy 96.233113 -199.096482) (xy 96.177776 -199.288818)
			(xy 96.114788 -199.478786) (xy 96.044251 -199.666082) (xy 95.966276 -199.850406) (xy 95.880989 -200.031462)
			(xy 95.788526 -200.208961) (xy 95.689035 -200.382619) (xy 95.582676 -200.552157) (xy 95.46962 -200.717303)
			(xy 95.350046 -200.877795) (xy 95.224147 -201.033373) (xy 95.092124 -201.18379) (xy 94.954188 -201.328804)
			(xy 94.810561 -201.468184) (xy 94.661473 -201.601705) (xy 94.507162 -201.729154) (xy 94.347875 -201.850328)
			(xy 94.183867 -201.965031) (xy 94.015402 -202.073081) (xy 93.842749 -202.174304) (xy 93.666184 -202.268538)
			(xy 93.48599 -202.355632) (xy 93.302455 -202.435448) (xy 93.115875 -202.507856) (xy 92.926546 -202.572741)
			(xy 92.734773 -202.629999) (xy 92.540863 -202.679538) (xy 92.345126 -202.72128) (xy 92.147876 -202.755157)
			(xy 91.949428 -202.781115) (xy 91.750101 -202.799112) (xy 91.550213 -202.80912) (xy 91.350085 -202.811122)
			(xy 91.150037 -202.805116) (xy 90.950389 -202.791111) (xy 90.751462 -202.769129) (xy 90.553573 -202.739205)
			(xy 90.35704 -202.701388) (xy 90.162178 -202.655739) (xy 89.969298 -202.602329) (xy 89.778709 -202.541245)
			(xy 89.590717 -202.472585) (xy 89.405622 -202.396458) (xy 89.223722 -202.312987) (xy 89.045306 -202.222304)
			(xy 88.870662 -202.124556) (xy 88.700069 -202.019899) (xy 88.533799 -201.9085) (xy 88.37212 -201.790538)
			(xy 88.215289 -201.666202) (xy 88.063559 -201.53569) (xy 87.917172 -201.399213) (xy 87.776363 -201.256987)
			(xy 87.641356 -201.109242) (xy 87.512369 -200.956214) (xy 87.389608 -200.798147) (xy 87.27327 -200.635296)
			(xy 87.16354 -200.46792) (xy 87.060595 -200.296288) (xy 86.964599 -200.120674) (xy 86.875706 -199.941361)
			(xy 86.794059 -199.758634) (xy 86.719787 -199.572787) (xy 86.653011 -199.384117) (xy 86.593837 -199.192927)
			(xy 86.54236 -198.999522) (xy 86.498662 -198.804213) (xy 86.462814 -198.607311) (xy 86.434872 -198.409133)
			(xy 86.414881 -198.209996) (xy 86.402874 -198.010218) (xy 86.39887 -197.81012) (xy 46.53026 -197.81012)
			(xy 46.53026 -201.54138) (xy 41.744904 -206.326736) (xy 64.48728 -206.326736) (xy 64.48728 -206.2668)
			(xy 64.495103 -206.207378) (xy 64.510616 -206.149485) (xy 64.533552 -206.094112) (xy 64.563519 -206.042206)
			(xy 64.600006 -205.994656) (xy 64.642386 -205.952276) (xy 64.689936 -205.915789) (xy 64.741842 -205.885822)
			(xy 64.797215 -205.862886) (xy 64.855108 -205.847373) (xy 64.91453 -205.83955) (xy 64.974466 -205.83955)
			(xy 65.033888 -205.847373) (xy 65.091781 -205.862886) (xy 65.147154 -205.885822) (xy 65.19906 -205.915789)
			(xy 65.24661 -205.952276) (xy 65.28899 -205.994656) (xy 65.325477 -206.042206) (xy 65.355444 -206.094112)
			(xy 65.37838 -206.149485) (xy 65.393893 -206.207378) (xy 65.401716 -206.2668) (xy 65.402206 -206.296768)
			(xy 65.401716 -206.326736) (xy 65.393893 -206.386158) (xy 65.37838 -206.444051) (xy 65.355444 -206.499424)
			(xy 65.325477 -206.55133) (xy 65.28899 -206.59888) (xy 65.24661 -206.64126) (xy 65.19906 -206.677747)
			(xy 65.147154 -206.707714) (xy 65.091781 -206.73065) (xy 65.033888 -206.746163) (xy 64.974466 -206.753986)
			(xy 64.91453 -206.753986) (xy 64.855108 -206.746163) (xy 64.797215 -206.73065) (xy 64.741842 -206.707714)
			(xy 64.689936 -206.677747) (xy 64.642386 -206.64126) (xy 64.600006 -206.59888) (xy 64.563519 -206.55133)
			(xy 64.533552 -206.499424) (xy 64.510616 -206.444051) (xy 64.495103 -206.386158) (xy 64.48728 -206.326736)
			(xy 41.744904 -206.326736) (xy 38.840668 -209.230972) (xy 64.52538 -209.230972) (xy 64.52538 -209.171036)
			(xy 64.533203 -209.111614) (xy 64.548716 -209.053721) (xy 64.571652 -208.998348) (xy 64.601619 -208.946442)
			(xy 64.638106 -208.898892) (xy 64.680486 -208.856512) (xy 64.728036 -208.820025) (xy 64.779942 -208.790058)
			(xy 64.835315 -208.767122) (xy 64.893208 -208.751609) (xy 64.95263 -208.743786) (xy 65.012566 -208.743786)
			(xy 65.071988 -208.751609) (xy 65.129881 -208.767122) (xy 65.185254 -208.790058) (xy 65.23716 -208.820025)
			(xy 65.28471 -208.856512) (xy 65.32709 -208.898892) (xy 65.363577 -208.946442) (xy 65.393544 -208.998348)
			(xy 65.41648 -209.053721) (xy 65.431993 -209.111614) (xy 65.439816 -209.171036) (xy 65.440306 -209.201004)
			(xy 65.439816 -209.230972) (xy 65.431993 -209.290394) (xy 65.41648 -209.348287) (xy 65.393544 -209.40366)
			(xy 65.363577 -209.455566) (xy 65.32709 -209.503116) (xy 65.28471 -209.545496) (xy 65.23716 -209.581983)
			(xy 65.185254 -209.61195) (xy 65.129881 -209.634886) (xy 65.071988 -209.650399) (xy 65.012566 -209.658222)
			(xy 64.95263 -209.658222) (xy 64.893208 -209.650399) (xy 64.835315 -209.634886) (xy 64.779942 -209.61195)
			(xy 64.728036 -209.581983) (xy 64.680486 -209.545496) (xy 64.638106 -209.503116) (xy 64.601619 -209.455566)
			(xy 64.571652 -209.40366) (xy 64.548716 -209.348287) (xy 64.533203 -209.290394) (xy 64.52538 -209.230972)
			(xy 38.840668 -209.230972) (xy 38.538912 -209.532728) (xy 38.538912 -210.09991) (xy 72.998592 -210.09991)
			(xy 73.002596 -209.899802) (xy 73.014604 -209.700014) (xy 73.034596 -209.500866) (xy 73.062539 -209.302678)
			(xy 73.098389 -209.105767) (xy 73.14209 -208.910447) (xy 73.193569 -208.717033) (xy 73.252746 -208.525833)
			(xy 73.319526 -208.337153) (xy 73.393801 -208.151297) (xy 73.475452 -207.968561) (xy 73.56435 -207.789238)
			(xy 73.66035 -207.613616) (xy 73.763301 -207.441975) (xy 73.873036 -207.274591) (xy 73.989381 -207.111731)
			(xy 74.112148 -206.953656) (xy 74.241141 -206.80062) (xy 74.376154 -206.652868) (xy 74.516971 -206.510635)
			(xy 74.663365 -206.374151) (xy 74.815103 -206.243632) (xy 74.971942 -206.11929) (xy 75.133629 -206.001322)
			(xy 75.299908 -205.889917) (xy 75.47051 -205.785255) (xy 75.645163 -205.687502) (xy 75.823587 -205.596815)
			(xy 76.005497 -205.513339) (xy 76.190601 -205.437208) (xy 76.378603 -205.368544) (xy 76.569201 -205.307457)
			(xy 76.762091 -205.254045) (xy 76.956963 -205.208393) (xy 77.153506 -205.170574) (xy 77.351405 -205.14065)
			(xy 77.550342 -205.118666) (xy 77.75 -205.10466) (xy 77.950058 -205.098654) (xy 78.150197 -205.100656)
			(xy 78.350095 -205.110665) (xy 78.549432 -205.128663) (xy 78.74789 -205.154622) (xy 78.94515 -205.1885)
			(xy 79.140897 -205.230244) (xy 79.334817 -205.279786) (xy 79.5266 -205.337047) (xy 79.715938 -205.401936)
			(xy 79.902528 -205.474348) (xy 80.086072 -205.554167) (xy 80.266275 -205.641266) (xy 80.442849 -205.735504)
			(xy 80.615511 -205.836733) (xy 80.783985 -205.944788) (xy 80.948001 -206.059497) (xy 81.107296 -206.180677)
			(xy 81.261615 -206.308132) (xy 81.410711 -206.441661) (xy 81.554345 -206.581047) (xy 81.692287 -206.726069)
			(xy 81.824317 -206.876493) (xy 81.950223 -207.03208) (xy 82.069802 -207.192579) (xy 82.182865 -207.357734)
			(xy 82.289229 -207.527281) (xy 82.388725 -207.700947) (xy 82.481192 -207.878455) (xy 82.566484 -208.059521)
			(xy 82.644463 -208.243854) (xy 82.715004 -208.431159) (xy 82.777995 -208.621137) (xy 82.833334 -208.813483)
			(xy 82.880934 -209.007888) (xy 82.920717 -209.204043) (xy 82.95262 -209.401633) (xy 82.976592 -209.60034)
			(xy 82.992595 -209.799848) (xy 83.000603 -209.999836) (xy 83.001104 -210.09991) (xy 83.000603 -210.199984)
			(xy 82.992595 -210.399972) (xy 82.976592 -210.59948) (xy 82.95262 -210.798187) (xy 82.920717 -210.995777)
			(xy 82.880934 -211.191932) (xy 82.833334 -211.386337) (xy 82.777995 -211.578683) (xy 82.715004 -211.768661)
			(xy 82.644463 -211.955966) (xy 82.566484 -212.140299) (xy 82.481192 -212.321365) (xy 82.388725 -212.498873)
			(xy 82.289229 -212.672539) (xy 82.182865 -212.842086) (xy 82.069802 -213.007241) (xy 81.950223 -213.16774)
			(xy 81.824317 -213.323327) (xy 81.692287 -213.473751) (xy 81.554345 -213.618773) (xy 81.410711 -213.758159)
			(xy 81.261615 -213.891688) (xy 81.107296 -214.019143) (xy 80.948001 -214.140323) (xy 80.783985 -214.255032)
			(xy 80.615511 -214.363087) (xy 80.442849 -214.464316) (xy 80.266275 -214.558554) (xy 80.086072 -214.645653)
			(xy 79.902528 -214.725472) (xy 79.715938 -214.797884) (xy 79.5266 -214.862773) (xy 79.334817 -214.920034)
			(xy 79.140897 -214.969576) (xy 78.94515 -215.01132) (xy 78.74789 -215.045198) (xy 78.549432 -215.071157)
			(xy 78.350095 -215.089155) (xy 78.150197 -215.099164) (xy 77.950058 -215.101166) (xy 77.75 -215.09516)
			(xy 77.550342 -215.081154) (xy 77.351405 -215.05917) (xy 77.153506 -215.029246) (xy 76.956963 -214.991427)
			(xy 76.762091 -214.945775) (xy 76.569201 -214.892363) (xy 76.378603 -214.831276) (xy 76.190601 -214.762612)
			(xy 76.005497 -214.686481) (xy 75.823587 -214.603005) (xy 75.645163 -214.512318) (xy 75.47051 -214.414565)
			(xy 75.299908 -214.309903) (xy 75.133629 -214.198498) (xy 74.971942 -214.08053) (xy 74.815103 -213.956188)
			(xy 74.663365 -213.825669) (xy 74.516971 -213.689185) (xy 74.376154 -213.546952) (xy 74.241141 -213.3992)
			(xy 74.112148 -213.246164) (xy 73.989381 -213.088089) (xy 73.873036 -212.925229) (xy 73.763301 -212.757845)
			(xy 73.66035 -212.586204) (xy 73.56435 -212.410582) (xy 73.475452 -212.231259) (xy 73.393801 -212.048523)
			(xy 73.319526 -211.862667) (xy 73.252746 -211.673987) (xy 73.193569 -211.482787) (xy 73.14209 -211.289373)
			(xy 73.098389 -211.094053) (xy 73.062539 -210.897142) (xy 73.034596 -210.698954) (xy 73.014604 -210.499806)
			(xy 73.002596 -210.300018) (xy 72.998592 -210.09991) (xy 38.538912 -210.09991) (xy 38.538912 -211.69376)
			(xy 38.52164 -211.711032) (xy 38.502082 -211.757768) (xy 38.502082 -211.864448) (xy 36.497514 -213.869016)
			(xy 30.534102 -213.869016) (xy 29.531818 -214.8713) (xy 29.531818 -215.258396) (xy 29.572204 -215.350598)
			(xy 29.588714 -215.367362) (xy 29.61042 -215.390048) (xy 29.648388 -215.440052) (xy 29.679561 -215.494553)
			(xy 29.703413 -215.552632) (xy 29.719543 -215.613311) (xy 29.727679 -215.675567) (xy 29.72816 -215.70696)
			(xy 29.72816 -216.659968) (xy 51.342036 -216.659968) (xy 52.994052 -216.659968) (xy 52.994052 -217.210408)
			(xy 60.170682 -217.210408) (xy 60.174568 -217.156054) (xy 60.186151 -217.102806) (xy 60.205194 -217.051748)
			(xy 60.231309 -217.003921) (xy 60.263966 -216.960297) (xy 60.302498 -216.921764) (xy 60.346123 -216.889108)
			(xy 60.39395 -216.862993) (xy 60.445008 -216.84395) (xy 60.498256 -216.832368) (xy 60.552611 -216.828482)
			(xy 60.606965 -216.832371) (xy 60.660212 -216.843956) (xy 60.711269 -216.863002) (xy 60.759095 -216.889119)
			(xy 60.781184 -216.905078) (xy 60.800196 -216.918674) (xy 60.842079 -216.939406) (xy 60.887047 -216.952132)
			(xy 60.933584 -216.956422) (xy 60.980121 -216.952132) (xy 61.025089 -216.939406) (xy 61.066972 -216.918674)
			(xy 61.085984 -216.905078) (xy 61.108086 -216.889136) (xy 61.155911 -216.863014) (xy 61.206968 -216.843965)
			(xy 61.260216 -216.832377) (xy 61.314571 -216.828485) (xy 61.368927 -216.832369) (xy 61.422177 -216.843949)
			(xy 61.473236 -216.86299) (xy 61.521066 -216.889105) (xy 61.564692 -216.92176) (xy 61.603226 -216.960293)
			(xy 61.635885 -217.003917) (xy 61.662001 -217.051745) (xy 61.681045 -217.102804) (xy 61.692628 -217.156053)
			(xy 61.696515 -217.210408) (xy 63.162275 -217.210408) (xy 63.166161 -217.156052) (xy 63.177744 -217.102803)
			(xy 63.196788 -217.051744) (xy 63.222904 -217.003915) (xy 63.255562 -216.96029) (xy 63.294096 -216.921756)
			(xy 63.337722 -216.8891) (xy 63.385552 -216.862984) (xy 63.436611 -216.843942) (xy 63.489861 -216.83236)
			(xy 63.544217 -216.828475) (xy 63.598573 -216.832365) (xy 63.651822 -216.843952) (xy 63.70288 -216.862999)
			(xy 63.750707 -216.889118) (xy 63.772796 -216.905078) (xy 63.791808 -216.918674) (xy 63.833691 -216.939406)
			(xy 63.878659 -216.952132) (xy 63.925196 -216.956422) (xy 63.971733 -216.952132) (xy 64.016701 -216.939406)
			(xy 64.058584 -216.918674) (xy 64.077596 -216.905078) (xy 64.099697 -216.889137) (xy 64.147522 -216.863017)
			(xy 64.198578 -216.84397) (xy 64.251824 -216.832383) (xy 64.306178 -216.828492) (xy 64.360532 -216.832377)
			(xy 64.41378 -216.843958) (xy 64.464838 -216.862999) (xy 64.512666 -216.889113) (xy 64.55629 -216.921768)
			(xy 64.594823 -216.9603) (xy 64.62748 -217.003923) (xy 64.653596 -217.05175) (xy 64.672639 -217.102807)
			(xy 64.684221 -217.156054) (xy 64.688108 -217.210408) (xy 64.684219 -217.264762) (xy 64.672634 -217.318009)
			(xy 64.653589 -217.369065) (xy 64.627471 -217.416891) (xy 64.594812 -217.460513) (xy 64.556278 -217.499043)
			(xy 64.512652 -217.531696) (xy 64.464822 -217.557808) (xy 64.413764 -217.576847) (xy 64.360516 -217.588426)
			(xy 64.306161 -217.592308) (xy 64.251808 -217.588415) (xy 64.198562 -217.576825) (xy 64.147507 -217.557776)
			(xy 64.099683 -217.531654) (xy 64.077596 -217.515694) (xy 64.058584 -217.502098) (xy 64.016701 -217.481366)
			(xy 63.971733 -217.46864) (xy 63.925196 -217.46435) (xy 63.878659 -217.46864) (xy 63.833691 -217.481366)
			(xy 63.791808 -217.502098) (xy 63.772796 -217.515694) (xy 63.750721 -217.531672) (xy 63.702895 -217.557794)
			(xy 63.651838 -217.576844) (xy 63.59859 -217.588433) (xy 63.544234 -217.592325) (xy 63.489878 -217.588442)
			(xy 63.436627 -217.576863) (xy 63.385567 -217.557823) (xy 63.337736 -217.531709) (xy 63.294109 -217.499055)
			(xy 63.255573 -217.460523) (xy 63.222914 -217.416899) (xy 63.196795 -217.369072) (xy 63.177749 -217.318013)
			(xy 63.166164 -217.264764) (xy 63.162275 -217.210408) (xy 61.696515 -217.210408) (xy 61.692626 -217.264764)
			(xy 61.68104 -217.318012) (xy 61.661994 -217.36907) (xy 61.635875 -217.416897) (xy 61.603215 -217.46052)
			(xy 61.564679 -217.499051) (xy 61.521052 -217.531705) (xy 61.473221 -217.557817) (xy 61.422161 -217.576856)
			(xy 61.36891 -217.588434) (xy 61.314554 -217.592315) (xy 61.260199 -217.588421) (xy 61.206952 -217.57683)
			(xy 61.155896 -217.557779) (xy 61.108072 -217.531655) (xy 61.085984 -217.515694) (xy 61.066972 -217.502098)
			(xy 61.025089 -217.481366) (xy 60.980121 -217.46864) (xy 60.933584 -217.46435) (xy 60.887047 -217.46864)
			(xy 60.842079 -217.481366) (xy 60.800196 -217.502098) (xy 60.781184 -217.515694) (xy 60.759109 -217.531671)
			(xy 60.711284 -217.557791) (xy 60.660228 -217.576839) (xy 60.606981 -217.588427) (xy 60.552627 -217.592318)
			(xy 60.498273 -217.588434) (xy 60.445024 -217.576855) (xy 60.393966 -217.557814) (xy 60.346137 -217.531701)
			(xy 60.302511 -217.499047) (xy 60.263977 -217.460516) (xy 60.231318 -217.416893) (xy 60.205201 -217.369067)
			(xy 60.186156 -217.31801) (xy 60.174571 -217.264763) (xy 60.170682 -217.210408) (xy 52.994052 -217.210408)
			(xy 52.994052 -218.311984) (xy 51.342036 -218.311984) (xy 51.342036 -216.659968) (xy 29.72816 -216.659968)
			(xy 29.72816 -217.526531) (xy 47.842414 -217.526531) (xy 47.842414 -217.445421) (xy 47.850364 -217.364702)
			(xy 47.866187 -217.285151) (xy 47.889732 -217.207535) (xy 47.920771 -217.132599) (xy 47.959006 -217.061067)
			(xy 48.004068 -216.993627) (xy 48.055523 -216.930928) (xy 48.112876 -216.873575) (xy 48.175575 -216.82212)
			(xy 48.243015 -216.777058) (xy 48.314547 -216.738823) (xy 48.389483 -216.707784) (xy 48.467099 -216.684239)
			(xy 48.54665 -216.668416) (xy 48.627369 -216.660466) (xy 48.708479 -216.660466) (xy 48.789198 -216.668416)
			(xy 48.868749 -216.684239) (xy 48.946365 -216.707784) (xy 49.021301 -216.738823) (xy 49.092833 -216.777058)
			(xy 49.160273 -216.82212) (xy 49.222972 -216.873575) (xy 49.280325 -216.930928) (xy 49.33178 -216.993627)
			(xy 49.376842 -217.061067) (xy 49.415077 -217.132599) (xy 49.446116 -217.207535) (xy 49.469661 -217.285151)
			(xy 49.485484 -217.364702) (xy 49.493434 -217.445421) (xy 49.493932 -217.485976) (xy 49.493434 -217.526531)
			(xy 49.485484 -217.60725) (xy 49.469661 -217.686801) (xy 49.446116 -217.764417) (xy 49.415077 -217.839353)
			(xy 49.376842 -217.910885) (xy 49.33178 -217.978325) (xy 49.280325 -218.041024) (xy 49.222972 -218.098377)
			(xy 49.160273 -218.149832) (xy 49.092833 -218.194894) (xy 49.021301 -218.233129) (xy 48.946365 -218.264168)
			(xy 48.868749 -218.287713) (xy 48.789198 -218.303536) (xy 48.708479 -218.311486) (xy 48.627369 -218.311486)
			(xy 48.54665 -218.303536) (xy 48.467099 -218.287713) (xy 48.389483 -218.264168) (xy 48.314547 -218.233129)
			(xy 48.243015 -218.194894) (xy 48.175575 -218.149832) (xy 48.112876 -218.098377) (xy 48.055523 -218.041024)
			(xy 48.004068 -217.978325) (xy 47.959006 -217.910885) (xy 47.920771 -217.839353) (xy 47.889732 -217.764417)
			(xy 47.866187 -217.686801) (xy 47.850364 -217.60725) (xy 47.842414 -217.526531) (xy 29.72816 -217.526531)
			(xy 29.72816 -219.173301) (xy 60.170691 -219.173301) (xy 60.174579 -219.118948) (xy 60.186162 -219.065702)
			(xy 60.205205 -219.014646) (xy 60.231321 -218.96682) (xy 60.263978 -218.923197) (xy 60.30251 -218.884667)
			(xy 60.346134 -218.852012) (xy 60.393961 -218.825899) (xy 60.445018 -218.806857) (xy 60.498265 -218.795276)
			(xy 60.552618 -218.791391) (xy 60.606971 -218.795282) (xy 60.660216 -218.806867) (xy 60.711271 -218.825913)
			(xy 60.759096 -218.852031) (xy 60.781184 -218.86799) (xy 60.800196 -218.881586) (xy 60.842079 -218.902318)
			(xy 60.887047 -218.915044) (xy 60.933584 -218.919334) (xy 60.980121 -218.915044) (xy 61.025089 -218.902318)
			(xy 61.066972 -218.881586) (xy 61.085984 -218.86799) (xy 61.108074 -218.852031) (xy 61.155901 -218.825908)
			(xy 61.206958 -218.806858) (xy 61.260208 -218.795269) (xy 61.314564 -218.791375) (xy 61.368921 -218.795258)
			(xy 61.422173 -218.806838) (xy 61.473234 -218.825879) (xy 61.521065 -218.851993) (xy 61.564693 -218.884648)
			(xy 61.603229 -218.923181) (xy 61.635889 -218.966806) (xy 61.662007 -219.014635) (xy 61.681052 -219.065694)
			(xy 61.692637 -219.118944) (xy 61.696525 -219.173301) (xy 63.162284 -219.173301) (xy 63.166172 -219.118947)
			(xy 63.177756 -219.065699) (xy 63.1968 -219.014641) (xy 63.222916 -218.966814) (xy 63.255574 -218.92319)
			(xy 63.294108 -218.884659) (xy 63.337734 -218.852004) (xy 63.385562 -218.82589) (xy 63.436621 -218.806849)
			(xy 63.48987 -218.795268) (xy 63.544225 -218.791384) (xy 63.598579 -218.795275) (xy 63.651826 -218.806863)
			(xy 63.702882 -218.82591) (xy 63.750708 -218.85203) (xy 63.772796 -218.86799) (xy 63.791808 -218.881586)
			(xy 63.833691 -218.902318) (xy 63.878659 -218.915044) (xy 63.925196 -218.919334) (xy 63.971733 -218.915044)
			(xy 64.016701 -218.902318) (xy 64.058584 -218.881586) (xy 64.077596 -218.86799) (xy 64.099686 -218.852032)
			(xy 64.147512 -218.825911) (xy 64.198568 -218.806863) (xy 64.251816 -218.795275) (xy 64.306171 -218.791383)
			(xy 64.360526 -218.795266) (xy 64.413776 -218.806846) (xy 64.464835 -218.825887) (xy 64.512665 -218.852001)
			(xy 64.556291 -218.884656) (xy 64.594826 -218.923188) (xy 64.627484 -218.966812) (xy 64.653601 -219.014639)
			(xy 64.672646 -219.065697) (xy 64.68423 -219.118946) (xy 64.688117 -219.173301) (xy 64.684229 -219.227656)
			(xy 64.672645 -219.280905) (xy 64.6536 -219.331963) (xy 64.627483 -219.37979) (xy 64.594824 -219.423414)
			(xy 64.556289 -219.461945) (xy 64.512663 -219.4946) (xy 64.464833 -219.520714) (xy 64.413774 -219.539754)
			(xy 64.360524 -219.551334) (xy 64.306168 -219.555217) (xy 64.251814 -219.551325) (xy 64.198566 -219.539737)
			(xy 64.14751 -219.520688) (xy 64.099684 -219.494566) (xy 64.077596 -219.478606) (xy 64.058584 -219.46501)
			(xy 64.016701 -219.444278) (xy 63.971733 -219.431552) (xy 63.925196 -219.427262) (xy 63.878659 -219.431552)
			(xy 63.833691 -219.444278) (xy 63.791808 -219.46501) (xy 63.772796 -219.478606) (xy 63.75071 -219.494568)
			(xy 63.702884 -219.520689) (xy 63.651828 -219.539737) (xy 63.598581 -219.551324) (xy 63.544227 -219.555216)
			(xy 63.489872 -219.551332) (xy 63.436623 -219.539752) (xy 63.385565 -219.520711) (xy 63.337736 -219.494597)
			(xy 63.29411 -219.461943) (xy 63.255576 -219.423411) (xy 63.222918 -219.379788) (xy 63.196801 -219.331961)
			(xy 63.177756 -219.280904) (xy 63.166172 -219.227656) (xy 63.162284 -219.173301) (xy 61.696525 -219.173301)
			(xy 61.692636 -219.227658) (xy 61.681052 -219.280908) (xy 61.662006 -219.331967) (xy 61.635887 -219.379796)
			(xy 61.603227 -219.423421) (xy 61.564691 -219.461953) (xy 61.521063 -219.494609) (xy 61.473232 -219.520722)
			(xy 61.42217 -219.539763) (xy 61.368919 -219.551342) (xy 61.314562 -219.555225) (xy 61.260205 -219.551331)
			(xy 61.206956 -219.539741) (xy 61.155899 -219.520691) (xy 61.108072 -219.494567) (xy 61.085984 -219.478606)
			(xy 61.066972 -219.46501) (xy 61.025089 -219.444278) (xy 60.980121 -219.431552) (xy 60.933584 -219.427262)
			(xy 60.887047 -219.431552) (xy 60.842079 -219.444278) (xy 60.800196 -219.46501) (xy 60.781184 -219.478606)
			(xy 60.759098 -219.494567) (xy 60.711274 -219.520686) (xy 60.660219 -219.539732) (xy 60.606973 -219.551318)
			(xy 60.55262 -219.555209) (xy 60.498267 -219.551324) (xy 60.44502 -219.539743) (xy 60.393963 -219.520702)
			(xy 60.346136 -219.494589) (xy 60.302512 -219.461935) (xy 60.263979 -219.423404) (xy 60.231322 -219.379782)
			(xy 60.205206 -219.331956) (xy 60.186163 -219.280901) (xy 60.174579 -219.227654) (xy 60.170691 -219.173301)
			(xy 29.72816 -219.173301) (xy 29.72816 -221.316798) (xy 60.170696 -221.316798) (xy 60.174584 -221.262445)
			(xy 60.186168 -221.2092) (xy 60.205211 -221.158145) (xy 60.231327 -221.110319) (xy 60.263984 -221.066698)
			(xy 60.302516 -221.028168) (xy 60.346139 -220.995514) (xy 60.393966 -220.969401) (xy 60.445022 -220.950361)
			(xy 60.498269 -220.938781) (xy 60.552621 -220.934896) (xy 60.606973 -220.938787) (xy 60.660218 -220.950373)
			(xy 60.711273 -220.969419) (xy 60.759096 -220.995537) (xy 60.781184 -221.011496) (xy 60.800196 -221.025092)
			(xy 60.842079 -221.045824) (xy 60.887047 -221.05855) (xy 60.933584 -221.06284) (xy 60.980121 -221.05855)
			(xy 61.025089 -221.045824) (xy 61.066972 -221.025092) (xy 61.085984 -221.011496) (xy 61.108069 -220.995529)
			(xy 61.155896 -220.969406) (xy 61.206954 -220.950355) (xy 61.260203 -220.938764) (xy 61.31456 -220.934871)
			(xy 61.368918 -220.938753) (xy 61.42217 -220.950332) (xy 61.473232 -220.969373) (xy 61.521065 -220.995487)
			(xy 61.564693 -221.028142) (xy 61.60323 -221.066675) (xy 61.635891 -221.1103) (xy 61.66201 -221.158129)
			(xy 61.681056 -221.209189) (xy 61.692641 -221.26244) (xy 61.696529 -221.316798) (xy 63.162289 -221.316798)
			(xy 63.166177 -221.262444) (xy 63.177761 -221.209196) (xy 63.196806 -221.15814) (xy 63.222922 -221.110313)
			(xy 63.25558 -221.066691) (xy 63.294114 -221.02816) (xy 63.337739 -220.995506) (xy 63.385568 -220.969393)
			(xy 63.436626 -220.950353) (xy 63.489874 -220.938773) (xy 63.544228 -220.934889) (xy 63.598582 -220.938781)
			(xy 63.651828 -220.950368) (xy 63.702884 -220.969416) (xy 63.750708 -220.995536) (xy 63.772796 -221.011496)
			(xy 63.791808 -221.025092) (xy 63.833691 -221.045824) (xy 63.878659 -221.05855) (xy 63.925196 -221.06284)
			(xy 63.971733 -221.05855) (xy 64.016701 -221.045824) (xy 64.058584 -221.025092) (xy 64.077596 -221.011496)
			(xy 64.099681 -220.99553) (xy 64.147507 -220.969408) (xy 64.198563 -220.950359) (xy 64.251812 -220.93877)
			(xy 64.306167 -220.934878) (xy 64.360524 -220.938761) (xy 64.413774 -220.950341) (xy 64.464834 -220.969381)
			(xy 64.512664 -220.995495) (xy 64.556291 -221.02815) (xy 64.594827 -221.066682) (xy 64.627486 -221.110306)
			(xy 64.653604 -221.158134) (xy 64.672649 -221.209193) (xy 64.684234 -221.262442) (xy 64.688122 -221.316798)
			(xy 64.684235 -221.371154) (xy 64.672651 -221.424403) (xy 64.653606 -221.475462) (xy 64.627489 -221.52329)
			(xy 64.59483 -221.566914) (xy 64.556295 -221.605447) (xy 64.512668 -221.638102) (xy 64.464838 -221.664217)
			(xy 64.413778 -221.683258) (xy 64.360528 -221.694838) (xy 64.306172 -221.698722) (xy 64.251816 -221.69483)
			(xy 64.198568 -221.683242) (xy 64.147511 -221.664194) (xy 64.099685 -221.638072) (xy 64.077596 -221.622112)
			(xy 64.058584 -221.608516) (xy 64.016701 -221.587784) (xy 63.971733 -221.575058) (xy 63.925196 -221.570768)
			(xy 63.878659 -221.575058) (xy 63.833691 -221.587784) (xy 63.791808 -221.608516) (xy 63.772796 -221.622112)
			(xy 63.750704 -221.638066) (xy 63.702879 -221.664186) (xy 63.651824 -221.683233) (xy 63.598577 -221.69482)
			(xy 63.544223 -221.698711) (xy 63.489869 -221.694827) (xy 63.436621 -221.683246) (xy 63.385563 -221.664205)
			(xy 63.337735 -221.638091) (xy 63.29411 -221.605437) (xy 63.255577 -221.566906) (xy 63.22292 -221.523282)
			(xy 63.196804 -221.475456) (xy 63.17776 -221.424399) (xy 63.166176 -221.371152) (xy 63.162289 -221.316798)
			(xy 61.696529 -221.316798) (xy 61.692642 -221.371155) (xy 61.681057 -221.424406) (xy 61.662012 -221.475466)
			(xy 61.635893 -221.523296) (xy 61.603233 -221.566921) (xy 61.564697 -221.605455) (xy 61.521069 -221.638111)
			(xy 61.473237 -221.664225) (xy 61.422175 -221.683266) (xy 61.368923 -221.694846) (xy 61.314565 -221.698729)
			(xy 61.260208 -221.694836) (xy 61.206958 -221.683247) (xy 61.1559 -221.664196) (xy 61.108073 -221.638073)
			(xy 61.085984 -221.622112) (xy 61.066972 -221.608516) (xy 61.025089 -221.587784) (xy 60.980121 -221.575058)
			(xy 60.933584 -221.570768) (xy 60.887047 -221.575058) (xy 60.842079 -221.587784) (xy 60.800196 -221.608516)
			(xy 60.781184 -221.622112) (xy 60.759092 -221.638065) (xy 60.711268 -221.664183) (xy 60.660214 -221.683228)
			(xy 60.606969 -221.694814) (xy 60.552617 -221.698704) (xy 60.498264 -221.694819) (xy 60.445018 -221.683238)
			(xy 60.393962 -221.664197) (xy 60.346135 -221.638083) (xy 60.302512 -221.605429) (xy 60.26398 -221.566898)
			(xy 60.231325 -221.523277) (xy 60.205209 -221.475451) (xy 60.186166 -221.424396) (xy 60.174583 -221.37115)
			(xy 60.170696 -221.316798) (xy 29.72816 -221.316798) (xy 29.72816 -229.16007) (xy 39.818564 -229.16007)
			(xy 39.819058 -229.102661) (xy 39.826902 -228.988113) (xy 39.842544 -228.874366) (xy 39.865911 -228.761952)
			(xy 39.896896 -228.651394) (xy 39.935352 -228.543209) (xy 39.981101 -228.4379) (xy 40.03393 -228.335958)
			(xy 40.093592 -228.237859) (xy 40.159809 -228.14406) (xy 40.232272 -228.054998) (xy 40.310645 -227.971089)
			(xy 40.39456 -227.892723) (xy 40.483627 -227.820266) (xy 40.577431 -227.754056) (xy 40.675535 -227.694402)
			(xy 40.777481 -227.641581) (xy 40.882793 -227.595839) (xy 40.990981 -227.557391) (xy 41.101541 -227.526415)
			(xy 41.213957 -227.503056) (xy 41.327705 -227.487423) (xy 41.442254 -227.479588) (xy 41.557072 -227.479588)
			(xy 41.671621 -227.487423) (xy 41.785369 -227.503056) (xy 41.897785 -227.526415) (xy 42.008345 -227.557391)
			(xy 42.116533 -227.595839) (xy 42.221845 -227.641581) (xy 42.323791 -227.694402) (xy 42.421895 -227.754056)
			(xy 42.501239 -227.81006) (xy 63.647577 -227.81006) (xy 63.651612 -227.734356) (xy 63.663671 -227.659511)
			(xy 63.683617 -227.58637) (xy 63.711224 -227.515765) (xy 63.74618 -227.448494) (xy 63.788088 -227.385319)
			(xy 63.836474 -227.326957) (xy 63.89079 -227.274069) (xy 63.950419 -227.227254) (xy 64.014687 -227.187042)
			(xy 64.082864 -227.15389) (xy 64.15418 -227.128172) (xy 64.227825 -227.11018) (xy 64.302965 -227.100118)
			(xy 64.378749 -227.098099) (xy 64.454319 -227.104148) (xy 64.528817 -227.118195) (xy 64.6014 -227.140081)
			(xy 64.671246 -227.169558) (xy 64.737563 -227.206293) (xy 64.799599 -227.249868) (xy 64.856652 -227.29979)
			(xy 64.908076 -227.355494) (xy 64.953287 -227.416349) (xy 64.991774 -227.481664) (xy 65.0231 -227.5507)
			(xy 65.04691 -227.622675) (xy 65.062935 -227.696773) (xy 65.070994 -227.772154) (xy 65.071498 -227.81006)
			(xy 66.187577 -227.81006) (xy 66.191612 -227.734356) (xy 66.203671 -227.659511) (xy 66.223617 -227.58637)
			(xy 66.251224 -227.515765) (xy 66.28618 -227.448494) (xy 66.328088 -227.385319) (xy 66.376474 -227.326957)
			(xy 66.43079 -227.274069) (xy 66.490419 -227.227254) (xy 66.554687 -227.187042) (xy 66.622864 -227.15389)
			(xy 66.69418 -227.128172) (xy 66.767825 -227.11018) (xy 66.842965 -227.100118) (xy 66.918749 -227.098099)
			(xy 66.994319 -227.104148) (xy 67.068817 -227.118195) (xy 67.1414 -227.140081) (xy 67.211246 -227.169558)
			(xy 67.277563 -227.206293) (xy 67.339599 -227.249868) (xy 67.396652 -227.29979) (xy 67.448076 -227.355494)
			(xy 67.493287 -227.416349) (xy 67.531774 -227.481664) (xy 67.5631 -227.5507) (xy 67.58691 -227.622675)
			(xy 67.602935 -227.696773) (xy 67.610994 -227.772154) (xy 67.611498 -227.81006) (xy 68.727577 -227.81006)
			(xy 68.731612 -227.734356) (xy 68.743671 -227.659511) (xy 68.763617 -227.58637) (xy 68.791224 -227.515765)
			(xy 68.82618 -227.448494) (xy 68.868088 -227.385319) (xy 68.916474 -227.326957) (xy 68.97079 -227.274069)
			(xy 69.030419 -227.227254) (xy 69.094687 -227.187042) (xy 69.162864 -227.15389) (xy 69.23418 -227.128172)
			(xy 69.307825 -227.11018) (xy 69.382965 -227.100118) (xy 69.458749 -227.098099) (xy 69.534319 -227.104148)
			(xy 69.608817 -227.118195) (xy 69.6814 -227.140081) (xy 69.751246 -227.169558) (xy 69.817563 -227.206293)
			(xy 69.879599 -227.249868) (xy 69.936652 -227.29979) (xy 69.988076 -227.355494) (xy 70.033287 -227.416349)
			(xy 70.071774 -227.481664) (xy 70.1031 -227.5507) (xy 70.12691 -227.622675) (xy 70.142935 -227.696773)
			(xy 70.150994 -227.772154) (xy 70.151498 -227.81006) (xy 71.267577 -227.81006) (xy 71.271612 -227.734356)
			(xy 71.283671 -227.659511) (xy 71.303617 -227.58637) (xy 71.331224 -227.515765) (xy 71.36618 -227.448494)
			(xy 71.408088 -227.385319) (xy 71.456474 -227.326957) (xy 71.51079 -227.274069) (xy 71.570419 -227.227254)
			(xy 71.634687 -227.187042) (xy 71.702864 -227.15389) (xy 71.77418 -227.128172) (xy 71.847825 -227.11018)
			(xy 71.922965 -227.100118) (xy 71.998749 -227.098099) (xy 72.074319 -227.104148) (xy 72.148817 -227.118195)
			(xy 72.2214 -227.140081) (xy 72.291246 -227.169558) (xy 72.357563 -227.206293) (xy 72.419599 -227.249868)
			(xy 72.476652 -227.29979) (xy 72.528076 -227.355494) (xy 72.573287 -227.416349) (xy 72.611774 -227.481664)
			(xy 72.6431 -227.5507) (xy 72.66691 -227.622675) (xy 72.682935 -227.696773) (xy 72.690994 -227.772154)
			(xy 72.691498 -227.81006) (xy 73.807577 -227.81006) (xy 73.811612 -227.734356) (xy 73.823671 -227.659511)
			(xy 73.843617 -227.58637) (xy 73.871224 -227.515765) (xy 73.90618 -227.448494) (xy 73.948088 -227.385319)
			(xy 73.996474 -227.326957) (xy 74.05079 -227.274069) (xy 74.110419 -227.227254) (xy 74.174687 -227.187042)
			(xy 74.242864 -227.15389) (xy 74.31418 -227.128172) (xy 74.387825 -227.11018) (xy 74.462965 -227.100118)
			(xy 74.538749 -227.098099) (xy 74.614319 -227.104148) (xy 74.688817 -227.118195) (xy 74.7614 -227.140081)
			(xy 74.831246 -227.169558) (xy 74.897563 -227.206293) (xy 74.959599 -227.249868) (xy 75.016652 -227.29979)
			(xy 75.068076 -227.355494) (xy 75.113287 -227.416349) (xy 75.151774 -227.481664) (xy 75.1831 -227.5507)
			(xy 75.20691 -227.622675) (xy 75.222935 -227.696773) (xy 75.230994 -227.772154) (xy 75.231498 -227.81006)
			(xy 76.347577 -227.81006) (xy 76.351612 -227.734356) (xy 76.363671 -227.659511) (xy 76.383617 -227.58637)
			(xy 76.411224 -227.515765) (xy 76.44618 -227.448494) (xy 76.488088 -227.385319) (xy 76.536474 -227.326957)
			(xy 76.59079 -227.274069) (xy 76.650419 -227.227254) (xy 76.714687 -227.187042) (xy 76.782864 -227.15389)
			(xy 76.85418 -227.128172) (xy 76.927825 -227.11018) (xy 77.002965 -227.100118) (xy 77.078749 -227.098099)
			(xy 77.154319 -227.104148) (xy 77.228817 -227.118195) (xy 77.3014 -227.140081) (xy 77.371246 -227.169558)
			(xy 77.437563 -227.206293) (xy 77.499599 -227.249868) (xy 77.556652 -227.29979) (xy 77.608076 -227.355494)
			(xy 77.653287 -227.416349) (xy 77.691774 -227.481664) (xy 77.7231 -227.5507) (xy 77.74691 -227.622675)
			(xy 77.762935 -227.696773) (xy 77.770994 -227.772154) (xy 77.771498 -227.81006) (xy 78.887577 -227.81006)
			(xy 78.891612 -227.734356) (xy 78.903671 -227.659511) (xy 78.923617 -227.58637) (xy 78.951224 -227.515765)
			(xy 78.98618 -227.448494) (xy 79.028088 -227.385319) (xy 79.076474 -227.326957) (xy 79.13079 -227.274069)
			(xy 79.190419 -227.227254) (xy 79.254687 -227.187042) (xy 79.322864 -227.15389) (xy 79.39418 -227.128172)
			(xy 79.467825 -227.11018) (xy 79.542965 -227.100118) (xy 79.618749 -227.098099) (xy 79.694319 -227.104148)
			(xy 79.768817 -227.118195) (xy 79.8414 -227.140081) (xy 79.911246 -227.169558) (xy 79.977563 -227.206293)
			(xy 80.039599 -227.249868) (xy 80.096652 -227.29979) (xy 80.148076 -227.355494) (xy 80.193287 -227.416349)
			(xy 80.231774 -227.481664) (xy 80.2631 -227.5507) (xy 80.28691 -227.622675) (xy 80.302935 -227.696773)
			(xy 80.310994 -227.772154) (xy 80.311498 -227.81006) (xy 81.427577 -227.81006) (xy 81.431612 -227.734356)
			(xy 81.443671 -227.659511) (xy 81.463617 -227.58637) (xy 81.491224 -227.515765) (xy 81.52618 -227.448494)
			(xy 81.568088 -227.385319) (xy 81.616474 -227.326957) (xy 81.67079 -227.274069) (xy 81.730419 -227.227254)
			(xy 81.794687 -227.187042) (xy 81.862864 -227.15389) (xy 81.93418 -227.128172) (xy 82.007825 -227.11018)
			(xy 82.082965 -227.100118) (xy 82.158749 -227.098099) (xy 82.234319 -227.104148) (xy 82.308817 -227.118195)
			(xy 82.3814 -227.140081) (xy 82.451246 -227.169558) (xy 82.517563 -227.206293) (xy 82.579599 -227.249868)
			(xy 82.585544 -227.25507) (xy 86.197697 -227.25507) (xy 86.201732 -227.179366) (xy 86.213791 -227.104521)
			(xy 86.233737 -227.03138) (xy 86.261344 -226.960775) (xy 86.2963 -226.893504) (xy 86.338208 -226.830329)
			(xy 86.386594 -226.771967) (xy 86.44091 -226.719079) (xy 86.500539 -226.672264) (xy 86.564807 -226.632052)
			(xy 86.632984 -226.5989) (xy 86.7043 -226.573182) (xy 86.777945 -226.55519) (xy 86.853085 -226.545128)
			(xy 86.928869 -226.543109) (xy 87.004439 -226.549158) (xy 87.078937 -226.563205) (xy 87.15152 -226.585091)
			(xy 87.221366 -226.614568) (xy 87.287683 -226.651303) (xy 87.349719 -226.694878) (xy 87.406772 -226.7448)
			(xy 87.458196 -226.800504) (xy 87.503407 -226.861359) (xy 87.541894 -226.926674) (xy 87.57322 -226.99571)
			(xy 87.59703 -227.067685) (xy 87.613055 -227.141783) (xy 87.621114 -227.217164) (xy 87.621618 -227.25507)
			(xy 87.621114 -227.292976) (xy 87.613055 -227.368357) (xy 87.59703 -227.442455) (xy 87.57322 -227.51443)
			(xy 87.541894 -227.583466) (xy 87.503407 -227.648781) (xy 87.458196 -227.709636) (xy 87.406772 -227.76534)
			(xy 87.349719 -227.815262) (xy 87.287683 -227.858837) (xy 87.221366 -227.895572) (xy 87.15152 -227.925049)
			(xy 87.078937 -227.946935) (xy 87.004439 -227.960982) (xy 86.928869 -227.967031) (xy 86.853085 -227.965012)
			(xy 86.777945 -227.95495) (xy 86.7043 -227.936958) (xy 86.632984 -227.91124) (xy 86.564807 -227.878088)
			(xy 86.500539 -227.837876) (xy 86.44091 -227.791061) (xy 86.386594 -227.738173) (xy 86.338208 -227.679811)
			(xy 86.2963 -227.616636) (xy 86.261344 -227.549365) (xy 86.233737 -227.47876) (xy 86.213791 -227.405619)
			(xy 86.201732 -227.330774) (xy 86.197697 -227.25507) (xy 82.585544 -227.25507) (xy 82.636652 -227.29979)
			(xy 82.688076 -227.355494) (xy 82.733287 -227.416349) (xy 82.771774 -227.481664) (xy 82.8031 -227.5507)
			(xy 82.82691 -227.622675) (xy 82.842935 -227.696773) (xy 82.850994 -227.772154) (xy 82.851498 -227.81006)
			(xy 82.850994 -227.847966) (xy 82.842935 -227.923347) (xy 82.82691 -227.997445) (xy 82.8031 -228.06942)
			(xy 82.771774 -228.138456) (xy 82.733287 -228.203771) (xy 82.688076 -228.264626) (xy 82.636652 -228.32033)
			(xy 82.579599 -228.370252) (xy 82.517563 -228.413827) (xy 82.451246 -228.450562) (xy 82.3814 -228.480039)
			(xy 82.308817 -228.501925) (xy 82.234319 -228.515972) (xy 82.158749 -228.522021) (xy 82.082965 -228.520002)
			(xy 82.007825 -228.50994) (xy 81.93418 -228.491948) (xy 81.862864 -228.46623) (xy 81.794687 -228.433078)
			(xy 81.730419 -228.392866) (xy 81.67079 -228.346051) (xy 81.616474 -228.293163) (xy 81.568088 -228.234801)
			(xy 81.52618 -228.171626) (xy 81.491224 -228.104355) (xy 81.463617 -228.03375) (xy 81.443671 -227.960609)
			(xy 81.431612 -227.885764) (xy 81.427577 -227.81006) (xy 80.311498 -227.81006) (xy 80.310994 -227.847966)
			(xy 80.302935 -227.923347) (xy 80.28691 -227.997445) (xy 80.2631 -228.06942) (xy 80.231774 -228.138456)
			(xy 80.193287 -228.203771) (xy 80.148076 -228.264626) (xy 80.096652 -228.32033) (xy 80.039599 -228.370252)
			(xy 79.977563 -228.413827) (xy 79.911246 -228.450562) (xy 79.8414 -228.480039) (xy 79.768817 -228.501925)
			(xy 79.694319 -228.515972) (xy 79.618749 -228.522021) (xy 79.542965 -228.520002) (xy 79.467825 -228.50994)
			(xy 79.39418 -228.491948) (xy 79.322864 -228.46623) (xy 79.254687 -228.433078) (xy 79.190419 -228.392866)
			(xy 79.13079 -228.346051) (xy 79.076474 -228.293163) (xy 79.028088 -228.234801) (xy 78.98618 -228.171626)
			(xy 78.951224 -228.104355) (xy 78.923617 -228.03375) (xy 78.903671 -227.960609) (xy 78.891612 -227.885764)
			(xy 78.887577 -227.81006) (xy 77.771498 -227.81006) (xy 77.770994 -227.847966) (xy 77.762935 -227.923347)
			(xy 77.74691 -227.997445) (xy 77.7231 -228.06942) (xy 77.691774 -228.138456) (xy 77.653287 -228.203771)
			(xy 77.608076 -228.264626) (xy 77.556652 -228.32033) (xy 77.499599 -228.370252) (xy 77.437563 -228.413827)
			(xy 77.371246 -228.450562) (xy 77.3014 -228.480039) (xy 77.228817 -228.501925) (xy 77.154319 -228.515972)
			(xy 77.078749 -228.522021) (xy 77.002965 -228.520002) (xy 76.927825 -228.50994) (xy 76.85418 -228.491948)
			(xy 76.782864 -228.46623) (xy 76.714687 -228.433078) (xy 76.650419 -228.392866) (xy 76.59079 -228.346051)
			(xy 76.536474 -228.293163) (xy 76.488088 -228.234801) (xy 76.44618 -228.171626) (xy 76.411224 -228.104355)
			(xy 76.383617 -228.03375) (xy 76.363671 -227.960609) (xy 76.351612 -227.885764) (xy 76.347577 -227.81006)
			(xy 75.231498 -227.81006) (xy 75.230994 -227.847966) (xy 75.222935 -227.923347) (xy 75.20691 -227.997445)
			(xy 75.1831 -228.06942) (xy 75.151774 -228.138456) (xy 75.113287 -228.203771) (xy 75.068076 -228.264626)
			(xy 75.016652 -228.32033) (xy 74.959599 -228.370252) (xy 74.897563 -228.413827) (xy 74.831246 -228.450562)
			(xy 74.7614 -228.480039) (xy 74.688817 -228.501925) (xy 74.614319 -228.515972) (xy 74.538749 -228.522021)
			(xy 74.462965 -228.520002) (xy 74.387825 -228.50994) (xy 74.31418 -228.491948) (xy 74.242864 -228.46623)
			(xy 74.174687 -228.433078) (xy 74.110419 -228.392866) (xy 74.05079 -228.346051) (xy 73.996474 -228.293163)
			(xy 73.948088 -228.234801) (xy 73.90618 -228.171626) (xy 73.871224 -228.104355) (xy 73.843617 -228.03375)
			(xy 73.823671 -227.960609) (xy 73.811612 -227.885764) (xy 73.807577 -227.81006) (xy 72.691498 -227.81006)
			(xy 72.690994 -227.847966) (xy 72.682935 -227.923347) (xy 72.66691 -227.997445) (xy 72.6431 -228.06942)
			(xy 72.611774 -228.138456) (xy 72.573287 -228.203771) (xy 72.528076 -228.264626) (xy 72.476652 -228.32033)
			(xy 72.419599 -228.370252) (xy 72.357563 -228.413827) (xy 72.291246 -228.450562) (xy 72.2214 -228.480039)
			(xy 72.148817 -228.501925) (xy 72.074319 -228.515972) (xy 71.998749 -228.522021) (xy 71.922965 -228.520002)
			(xy 71.847825 -228.50994) (xy 71.77418 -228.491948) (xy 71.702864 -228.46623) (xy 71.634687 -228.433078)
			(xy 71.570419 -228.392866) (xy 71.51079 -228.346051) (xy 71.456474 -228.293163) (xy 71.408088 -228.234801)
			(xy 71.36618 -228.171626) (xy 71.331224 -228.104355) (xy 71.303617 -228.03375) (xy 71.283671 -227.960609)
			(xy 71.271612 -227.885764) (xy 71.267577 -227.81006) (xy 70.151498 -227.81006) (xy 70.150994 -227.847966)
			(xy 70.142935 -227.923347) (xy 70.12691 -227.997445) (xy 70.1031 -228.06942) (xy 70.071774 -228.138456)
			(xy 70.033287 -228.203771) (xy 69.988076 -228.264626) (xy 69.936652 -228.32033) (xy 69.879599 -228.370252)
			(xy 69.817563 -228.413827) (xy 69.751246 -228.450562) (xy 69.6814 -228.480039) (xy 69.608817 -228.501925)
			(xy 69.534319 -228.515972) (xy 69.458749 -228.522021) (xy 69.382965 -228.520002) (xy 69.307825 -228.50994)
			(xy 69.23418 -228.491948) (xy 69.162864 -228.46623) (xy 69.094687 -228.433078) (xy 69.030419 -228.392866)
			(xy 68.97079 -228.346051) (xy 68.916474 -228.293163) (xy 68.868088 -228.234801) (xy 68.82618 -228.171626)
			(xy 68.791224 -228.104355) (xy 68.763617 -228.03375) (xy 68.743671 -227.960609) (xy 68.731612 -227.885764)
			(xy 68.727577 -227.81006) (xy 67.611498 -227.81006) (xy 67.610994 -227.847966) (xy 67.602935 -227.923347)
			(xy 67.58691 -227.997445) (xy 67.5631 -228.06942) (xy 67.531774 -228.138456) (xy 67.493287 -228.203771)
			(xy 67.448076 -228.264626) (xy 67.396652 -228.32033) (xy 67.339599 -228.370252) (xy 67.277563 -228.413827)
			(xy 67.211246 -228.450562) (xy 67.1414 -228.480039) (xy 67.068817 -228.501925) (xy 66.994319 -228.515972)
			(xy 66.918749 -228.522021) (xy 66.842965 -228.520002) (xy 66.767825 -228.50994) (xy 66.69418 -228.491948)
			(xy 66.622864 -228.46623) (xy 66.554687 -228.433078) (xy 66.490419 -228.392866) (xy 66.43079 -228.346051)
			(xy 66.376474 -228.293163) (xy 66.328088 -228.234801) (xy 66.28618 -228.171626) (xy 66.251224 -228.104355)
			(xy 66.223617 -228.03375) (xy 66.203671 -227.960609) (xy 66.191612 -227.885764) (xy 66.187577 -227.81006)
			(xy 65.071498 -227.81006) (xy 65.070994 -227.847966) (xy 65.062935 -227.923347) (xy 65.04691 -227.997445)
			(xy 65.0231 -228.06942) (xy 64.991774 -228.138456) (xy 64.953287 -228.203771) (xy 64.908076 -228.264626)
			(xy 64.856652 -228.32033) (xy 64.799599 -228.370252) (xy 64.737563 -228.413827) (xy 64.671246 -228.450562)
			(xy 64.6014 -228.480039) (xy 64.528817 -228.501925) (xy 64.454319 -228.515972) (xy 64.378749 -228.522021)
			(xy 64.302965 -228.520002) (xy 64.227825 -228.50994) (xy 64.15418 -228.491948) (xy 64.082864 -228.46623)
			(xy 64.014687 -228.433078) (xy 63.950419 -228.392866) (xy 63.89079 -228.346051) (xy 63.836474 -228.293163)
			(xy 63.788088 -228.234801) (xy 63.74618 -228.171626) (xy 63.711224 -228.104355) (xy 63.683617 -228.03375)
			(xy 63.663671 -227.960609) (xy 63.651612 -227.885764) (xy 63.647577 -227.81006) (xy 42.501239 -227.81006)
			(xy 42.515699 -227.820266) (xy 42.604766 -227.892723) (xy 42.688681 -227.971089) (xy 42.767054 -228.054998)
			(xy 42.839517 -228.14406) (xy 42.905734 -228.237859) (xy 42.965396 -228.335958) (xy 43.018225 -228.4379)
			(xy 43.056094 -228.52507) (xy 84.927697 -228.52507) (xy 84.931732 -228.449366) (xy 84.943791 -228.374521)
			(xy 84.963737 -228.30138) (xy 84.991344 -228.230775) (xy 85.0263 -228.163504) (xy 85.068208 -228.100329)
			(xy 85.116594 -228.041967) (xy 85.17091 -227.989079) (xy 85.230539 -227.942264) (xy 85.294807 -227.902052)
			(xy 85.362984 -227.8689) (xy 85.4343 -227.843182) (xy 85.507945 -227.82519) (xy 85.583085 -227.815128)
			(xy 85.658869 -227.813109) (xy 85.734439 -227.819158) (xy 85.808937 -227.833205) (xy 85.88152 -227.855091)
			(xy 85.951366 -227.884568) (xy 86.017683 -227.921303) (xy 86.079719 -227.964878) (xy 86.136772 -228.0148)
			(xy 86.188196 -228.070504) (xy 86.233407 -228.131359) (xy 86.271894 -228.196674) (xy 86.30322 -228.26571)
			(xy 86.32703 -228.337685) (xy 86.343055 -228.411783) (xy 86.351114 -228.487164) (xy 86.351618 -228.52507)
			(xy 86.351114 -228.562976) (xy 86.343055 -228.638357) (xy 86.32703 -228.712455) (xy 86.30322 -228.78443)
			(xy 86.271894 -228.853466) (xy 86.233407 -228.918781) (xy 86.188196 -228.979636) (xy 86.136772 -229.03534)
			(xy 86.079719 -229.085262) (xy 86.017683 -229.128837) (xy 85.951366 -229.165572) (xy 85.88152 -229.195049)
			(xy 85.808937 -229.216935) (xy 85.734439 -229.230982) (xy 85.658869 -229.237031) (xy 85.583085 -229.235012)
			(xy 85.507945 -229.22495) (xy 85.4343 -229.206958) (xy 85.362984 -229.18124) (xy 85.294807 -229.148088)
			(xy 85.230539 -229.107876) (xy 85.17091 -229.061061) (xy 85.116594 -229.008173) (xy 85.068208 -228.949811)
			(xy 85.0263 -228.886636) (xy 84.991344 -228.819365) (xy 84.963737 -228.74876) (xy 84.943791 -228.675619)
			(xy 84.931732 -228.600774) (xy 84.927697 -228.52507) (xy 43.056094 -228.52507) (xy 43.063974 -228.543209)
			(xy 43.10243 -228.651394) (xy 43.133415 -228.761952) (xy 43.156782 -228.874366) (xy 43.172424 -228.988113)
			(xy 43.180268 -229.102661) (xy 43.180762 -229.16007) (xy 43.180576 -229.193253) (xy 43.177909 -229.259567)
			(xy 43.175428 -229.292658) (xy 43.170272 -229.350942) (xy 43.152948 -229.466671) (xy 43.127616 -229.580914)
			(xy 43.094401 -229.693119) (xy 43.056327 -229.79507) (xy 86.197697 -229.79507) (xy 86.201732 -229.719366)
			(xy 86.213791 -229.644521) (xy 86.233737 -229.57138) (xy 86.261344 -229.500775) (xy 86.2963 -229.433504)
			(xy 86.338208 -229.370329) (xy 86.386594 -229.311967) (xy 86.44091 -229.259079) (xy 86.500539 -229.212264)
			(xy 86.564807 -229.172052) (xy 86.632984 -229.1389) (xy 86.7043 -229.113182) (xy 86.777945 -229.09519)
			(xy 86.853085 -229.085128) (xy 86.928869 -229.083109) (xy 87.004439 -229.089158) (xy 87.078937 -229.103205)
			(xy 87.15152 -229.125091) (xy 87.221366 -229.154568) (xy 87.287683 -229.191303) (xy 87.349719 -229.234878)
			(xy 87.406772 -229.2848) (xy 87.458196 -229.340504) (xy 87.503407 -229.401359) (xy 87.541894 -229.466674)
			(xy 87.57322 -229.53571) (xy 87.59703 -229.607685) (xy 87.613055 -229.681783) (xy 87.621114 -229.757164)
			(xy 87.621618 -229.79507) (xy 87.621114 -229.832976) (xy 87.613055 -229.908357) (xy 87.59703 -229.982455)
			(xy 87.57322 -230.05443) (xy 87.541894 -230.123466) (xy 87.503407 -230.188781) (xy 87.458196 -230.249636)
			(xy 87.406772 -230.30534) (xy 87.349719 -230.355262) (xy 87.287683 -230.398837) (xy 87.221366 -230.435572)
			(xy 87.15152 -230.465049) (xy 87.078937 -230.486935) (xy 87.004439 -230.500982) (xy 86.928869 -230.507031)
			(xy 86.853085 -230.505012) (xy 86.777945 -230.49495) (xy 86.7043 -230.476958) (xy 86.632984 -230.45124)
			(xy 86.564807 -230.418088) (xy 86.500539 -230.377876) (xy 86.44091 -230.331061) (xy 86.386594 -230.278173)
			(xy 86.338208 -230.219811) (xy 86.2963 -230.156636) (xy 86.261344 -230.089365) (xy 86.233737 -230.01876)
			(xy 86.213791 -229.945619) (xy 86.201732 -229.870774) (xy 86.197697 -229.79507) (xy 43.056327 -229.79507)
			(xy 43.053462 -229.802742) (xy 43.004999 -229.909253) (xy 42.949245 -230.012135) (xy 42.886471 -230.110891)
			(xy 42.816981 -230.205042) (xy 42.741111 -230.294132) (xy 42.659229 -230.377729) (xy 42.571732 -230.45543)
			(xy 42.500813 -230.51008) (xy 63.647577 -230.51008) (xy 63.651612 -230.434376) (xy 63.663671 -230.359531)
			(xy 63.683617 -230.28639) (xy 63.711224 -230.215785) (xy 63.74618 -230.148514) (xy 63.788088 -230.085339)
			(xy 63.836474 -230.026977) (xy 63.89079 -229.974089) (xy 63.950419 -229.927274) (xy 64.014687 -229.887062)
			(xy 64.082864 -229.85391) (xy 64.15418 -229.828192) (xy 64.227825 -229.8102) (xy 64.302965 -229.800138)
			(xy 64.378749 -229.798119) (xy 64.454319 -229.804168) (xy 64.528817 -229.818215) (xy 64.6014 -229.840101)
			(xy 64.671246 -229.869578) (xy 64.737563 -229.906313) (xy 64.799599 -229.949888) (xy 64.856652 -229.99981)
			(xy 64.908076 -230.055514) (xy 64.953287 -230.116369) (xy 64.991774 -230.181684) (xy 65.0231 -230.25072)
			(xy 65.04691 -230.322695) (xy 65.062935 -230.396793) (xy 65.070994 -230.472174) (xy 65.071498 -230.51008)
			(xy 66.187577 -230.51008) (xy 66.191612 -230.434376) (xy 66.203671 -230.359531) (xy 66.223617 -230.28639)
			(xy 66.251224 -230.215785) (xy 66.28618 -230.148514) (xy 66.328088 -230.085339) (xy 66.376474 -230.026977)
			(xy 66.43079 -229.974089) (xy 66.490419 -229.927274) (xy 66.554687 -229.887062) (xy 66.622864 -229.85391)
			(xy 66.69418 -229.828192) (xy 66.767825 -229.8102) (xy 66.842965 -229.800138) (xy 66.918749 -229.798119)
			(xy 66.994319 -229.804168) (xy 67.068817 -229.818215) (xy 67.1414 -229.840101) (xy 67.211246 -229.869578)
			(xy 67.277563 -229.906313) (xy 67.339599 -229.949888) (xy 67.396652 -229.99981) (xy 67.448076 -230.055514)
			(xy 67.493287 -230.116369) (xy 67.531774 -230.181684) (xy 67.5631 -230.25072) (xy 67.58691 -230.322695)
			(xy 67.602935 -230.396793) (xy 67.610994 -230.472174) (xy 67.611498 -230.51008) (xy 68.727577 -230.51008)
			(xy 68.731612 -230.434376) (xy 68.743671 -230.359531) (xy 68.763617 -230.28639) (xy 68.791224 -230.215785)
			(xy 68.82618 -230.148514) (xy 68.868088 -230.085339) (xy 68.916474 -230.026977) (xy 68.97079 -229.974089)
			(xy 69.030419 -229.927274) (xy 69.094687 -229.887062) (xy 69.162864 -229.85391) (xy 69.23418 -229.828192)
			(xy 69.307825 -229.8102) (xy 69.382965 -229.800138) (xy 69.458749 -229.798119) (xy 69.534319 -229.804168)
			(xy 69.608817 -229.818215) (xy 69.6814 -229.840101) (xy 69.751246 -229.869578) (xy 69.817563 -229.906313)
			(xy 69.879599 -229.949888) (xy 69.936652 -229.99981) (xy 69.988076 -230.055514) (xy 70.033287 -230.116369)
			(xy 70.071774 -230.181684) (xy 70.1031 -230.25072) (xy 70.12691 -230.322695) (xy 70.142935 -230.396793)
			(xy 70.150994 -230.472174) (xy 70.151498 -230.51008) (xy 71.267577 -230.51008) (xy 71.271612 -230.434376)
			(xy 71.283671 -230.359531) (xy 71.303617 -230.28639) (xy 71.331224 -230.215785) (xy 71.36618 -230.148514)
			(xy 71.408088 -230.085339) (xy 71.456474 -230.026977) (xy 71.51079 -229.974089) (xy 71.570419 -229.927274)
			(xy 71.634687 -229.887062) (xy 71.702864 -229.85391) (xy 71.77418 -229.828192) (xy 71.847825 -229.8102)
			(xy 71.922965 -229.800138) (xy 71.998749 -229.798119) (xy 72.074319 -229.804168) (xy 72.148817 -229.818215)
			(xy 72.2214 -229.840101) (xy 72.291246 -229.869578) (xy 72.357563 -229.906313) (xy 72.419599 -229.949888)
			(xy 72.476652 -229.99981) (xy 72.528076 -230.055514) (xy 72.573287 -230.116369) (xy 72.611774 -230.181684)
			(xy 72.6431 -230.25072) (xy 72.66691 -230.322695) (xy 72.682935 -230.396793) (xy 72.690994 -230.472174)
			(xy 72.691498 -230.51008) (xy 73.807577 -230.51008) (xy 73.811612 -230.434376) (xy 73.823671 -230.359531)
			(xy 73.843617 -230.28639) (xy 73.871224 -230.215785) (xy 73.90618 -230.148514) (xy 73.948088 -230.085339)
			(xy 73.996474 -230.026977) (xy 74.05079 -229.974089) (xy 74.110419 -229.927274) (xy 74.174687 -229.887062)
			(xy 74.242864 -229.85391) (xy 74.31418 -229.828192) (xy 74.387825 -229.8102) (xy 74.462965 -229.800138)
			(xy 74.538749 -229.798119) (xy 74.614319 -229.804168) (xy 74.688817 -229.818215) (xy 74.7614 -229.840101)
			(xy 74.831246 -229.869578) (xy 74.897563 -229.906313) (xy 74.959599 -229.949888) (xy 75.016652 -229.99981)
			(xy 75.068076 -230.055514) (xy 75.113287 -230.116369) (xy 75.151774 -230.181684) (xy 75.1831 -230.25072)
			(xy 75.20691 -230.322695) (xy 75.222935 -230.396793) (xy 75.230994 -230.472174) (xy 75.231498 -230.51008)
			(xy 76.347577 -230.51008) (xy 76.351612 -230.434376) (xy 76.363671 -230.359531) (xy 76.383617 -230.28639)
			(xy 76.411224 -230.215785) (xy 76.44618 -230.148514) (xy 76.488088 -230.085339) (xy 76.536474 -230.026977)
			(xy 76.59079 -229.974089) (xy 76.650419 -229.927274) (xy 76.714687 -229.887062) (xy 76.782864 -229.85391)
			(xy 76.85418 -229.828192) (xy 76.927825 -229.8102) (xy 77.002965 -229.800138) (xy 77.078749 -229.798119)
			(xy 77.154319 -229.804168) (xy 77.228817 -229.818215) (xy 77.3014 -229.840101) (xy 77.371246 -229.869578)
			(xy 77.437563 -229.906313) (xy 77.499599 -229.949888) (xy 77.556652 -229.99981) (xy 77.608076 -230.055514)
			(xy 77.653287 -230.116369) (xy 77.691774 -230.181684) (xy 77.7231 -230.25072) (xy 77.74691 -230.322695)
			(xy 77.762935 -230.396793) (xy 77.770994 -230.472174) (xy 77.771498 -230.51008) (xy 78.887577 -230.51008)
			(xy 78.891612 -230.434376) (xy 78.903671 -230.359531) (xy 78.923617 -230.28639) (xy 78.951224 -230.215785)
			(xy 78.98618 -230.148514) (xy 79.028088 -230.085339) (xy 79.076474 -230.026977) (xy 79.13079 -229.974089)
			(xy 79.190419 -229.927274) (xy 79.254687 -229.887062) (xy 79.322864 -229.85391) (xy 79.39418 -229.828192)
			(xy 79.467825 -229.8102) (xy 79.542965 -229.800138) (xy 79.618749 -229.798119) (xy 79.694319 -229.804168)
			(xy 79.768817 -229.818215) (xy 79.8414 -229.840101) (xy 79.911246 -229.869578) (xy 79.977563 -229.906313)
			(xy 80.039599 -229.949888) (xy 80.096652 -229.99981) (xy 80.148076 -230.055514) (xy 80.193287 -230.116369)
			(xy 80.231774 -230.181684) (xy 80.2631 -230.25072) (xy 80.28691 -230.322695) (xy 80.302935 -230.396793)
			(xy 80.310994 -230.472174) (xy 80.311498 -230.51008) (xy 81.427577 -230.51008) (xy 81.431612 -230.434376)
			(xy 81.443671 -230.359531) (xy 81.463617 -230.28639) (xy 81.491224 -230.215785) (xy 81.52618 -230.148514)
			(xy 81.568088 -230.085339) (xy 81.616474 -230.026977) (xy 81.67079 -229.974089) (xy 81.730419 -229.927274)
			(xy 81.794687 -229.887062) (xy 81.862864 -229.85391) (xy 81.93418 -229.828192) (xy 82.007825 -229.8102)
			(xy 82.082965 -229.800138) (xy 82.158749 -229.798119) (xy 82.234319 -229.804168) (xy 82.308817 -229.818215)
			(xy 82.3814 -229.840101) (xy 82.451246 -229.869578) (xy 82.517563 -229.906313) (xy 82.579599 -229.949888)
			(xy 82.636652 -229.99981) (xy 82.688076 -230.055514) (xy 82.733287 -230.116369) (xy 82.771774 -230.181684)
			(xy 82.8031 -230.25072) (xy 82.82691 -230.322695) (xy 82.842935 -230.396793) (xy 82.850994 -230.472174)
			(xy 82.851498 -230.51008) (xy 82.850994 -230.547986) (xy 82.842935 -230.623367) (xy 82.82691 -230.697465)
			(xy 82.8031 -230.76944) (xy 82.771774 -230.838476) (xy 82.733287 -230.903791) (xy 82.688076 -230.964646)
			(xy 82.636652 -231.02035) (xy 82.585544 -231.06507) (xy 84.927697 -231.06507) (xy 84.931732 -230.989366)
			(xy 84.943791 -230.914521) (xy 84.963737 -230.84138) (xy 84.991344 -230.770775) (xy 85.0263 -230.703504)
			(xy 85.068208 -230.640329) (xy 85.116594 -230.581967) (xy 85.17091 -230.529079) (xy 85.230539 -230.482264)
			(xy 85.294807 -230.442052) (xy 85.362984 -230.4089) (xy 85.4343 -230.383182) (xy 85.507945 -230.36519)
			(xy 85.583085 -230.355128) (xy 85.658869 -230.353109) (xy 85.734439 -230.359158) (xy 85.808937 -230.373205)
			(xy 85.88152 -230.395091) (xy 85.951366 -230.424568) (xy 86.017683 -230.461303) (xy 86.079719 -230.504878)
			(xy 86.136772 -230.5548) (xy 86.188196 -230.610504) (xy 86.233407 -230.671359) (xy 86.271894 -230.736674)
			(xy 86.30322 -230.80571) (xy 86.32703 -230.877685) (xy 86.343055 -230.951783) (xy 86.351114 -231.027164)
			(xy 86.351618 -231.06507) (xy 87.467697 -231.06507) (xy 87.471732 -230.989366) (xy 87.483791 -230.914521)
			(xy 87.503737 -230.84138) (xy 87.531344 -230.770775) (xy 87.5663 -230.703504) (xy 87.608208 -230.640329)
			(xy 87.656594 -230.581967) (xy 87.71091 -230.529079) (xy 87.770539 -230.482264) (xy 87.834807 -230.442052)
			(xy 87.902984 -230.4089) (xy 87.9743 -230.383182) (xy 88.047945 -230.36519) (xy 88.123085 -230.355128)
			(xy 88.198869 -230.353109) (xy 88.274439 -230.359158) (xy 88.348937 -230.373205) (xy 88.42152 -230.395091)
			(xy 88.491366 -230.424568) (xy 88.557683 -230.461303) (xy 88.619719 -230.504878) (xy 88.676772 -230.5548)
			(xy 88.728196 -230.610504) (xy 88.773407 -230.671359) (xy 88.811894 -230.736674) (xy 88.84322 -230.80571)
			(xy 88.86703 -230.877685) (xy 88.883055 -230.951783) (xy 88.891114 -231.027164) (xy 88.891618 -231.06507)
			(xy 90.007697 -231.06507) (xy 90.011732 -230.989366) (xy 90.023791 -230.914521) (xy 90.043737 -230.84138)
			(xy 90.071344 -230.770775) (xy 90.1063 -230.703504) (xy 90.148208 -230.640329) (xy 90.196594 -230.581967)
			(xy 90.25091 -230.529079) (xy 90.310539 -230.482264) (xy 90.374807 -230.442052) (xy 90.442984 -230.4089)
			(xy 90.5143 -230.383182) (xy 90.587945 -230.36519) (xy 90.663085 -230.355128) (xy 90.738869 -230.353109)
			(xy 90.814439 -230.359158) (xy 90.888937 -230.373205) (xy 90.96152 -230.395091) (xy 91.031366 -230.424568)
			(xy 91.097683 -230.461303) (xy 91.159719 -230.504878) (xy 91.165664 -230.51008) (xy 93.154506 -230.51008)
			(xy 93.158522 -230.39381) (xy 93.170549 -230.278095) (xy 93.190531 -230.163485) (xy 93.218373 -230.050526)
			(xy 93.253942 -229.939758) (xy 93.297068 -229.831707) (xy 93.347545 -229.726889) (xy 93.405134 -229.625804)
			(xy 93.46956 -229.528932) (xy 93.540515 -229.436736) (xy 93.617662 -229.349655) (xy 93.700633 -229.268104)
			(xy 93.789033 -229.192472) (xy 93.88244 -229.123118) (xy 93.980409 -229.060375) (xy 94.082473 -229.004539)
			(xy 94.188147 -228.955878) (xy 94.296926 -228.914624) (xy 94.408291 -228.880973) (xy 94.521714 -228.855085)
			(xy 94.636651 -228.837084) (xy 94.752557 -228.827055) (xy 94.868879 -228.825047) (xy 94.985062 -228.831069)
			(xy 95.100553 -228.845092) (xy 95.214801 -228.86705) (xy 95.327262 -228.896837) (xy 95.4374 -228.934312)
			(xy 95.54469 -228.979297) (xy 95.648621 -229.031576) (xy 95.748697 -229.090901) (xy 95.844443 -229.156989)
			(xy 95.9354 -229.229525) (xy 96.021136 -229.308164) (xy 96.101243 -229.39253) (xy 96.175339 -229.482222)
			(xy 96.243069 -229.576812) (xy 96.304113 -229.67585) (xy 96.358178 -229.778863) (xy 96.405008 -229.88536)
			(xy 96.444379 -229.994835) (xy 96.476103 -230.106765) (xy 96.500029 -230.220617) (xy 96.516043 -230.335849)
			(xy 96.52407 -230.451911) (xy 96.524572 -230.51008) (xy 96.52407 -230.568249) (xy 96.516043 -230.684311)
			(xy 96.500029 -230.799543) (xy 96.476103 -230.913395) (xy 96.444379 -231.025325) (xy 96.405008 -231.1348)
			(xy 96.358178 -231.241297) (xy 96.304113 -231.34431) (xy 96.243069 -231.443348) (xy 96.175339 -231.537938)
			(xy 96.101243 -231.62763) (xy 96.021136 -231.711996) (xy 95.9354 -231.790635) (xy 95.844443 -231.863171)
			(xy 95.748697 -231.929259) (xy 95.648621 -231.988584) (xy 95.54469 -232.040863) (xy 95.4374 -232.085848)
			(xy 95.327262 -232.123323) (xy 95.214801 -232.15311) (xy 95.100553 -232.175068) (xy 94.985062 -232.189091)
			(xy 94.868879 -232.195113) (xy 94.752557 -232.193105) (xy 94.636651 -232.183076) (xy 94.521714 -232.165075)
			(xy 94.408291 -232.139187) (xy 94.296926 -232.105536) (xy 94.188147 -232.064282) (xy 94.082473 -232.015621)
			(xy 93.980409 -231.959785) (xy 93.88244 -231.897042) (xy 93.789033 -231.827688) (xy 93.700633 -231.752056)
			(xy 93.617662 -231.670505) (xy 93.540515 -231.583424) (xy 93.46956 -231.491228) (xy 93.405134 -231.394356)
			(xy 93.347545 -231.293271) (xy 93.297068 -231.188453) (xy 93.253942 -231.080402) (xy 93.218373 -230.969634)
			(xy 93.190531 -230.856675) (xy 93.170549 -230.742065) (xy 93.158522 -230.62635) (xy 93.154506 -230.51008)
			(xy 91.165664 -230.51008) (xy 91.216772 -230.5548) (xy 91.268196 -230.610504) (xy 91.313407 -230.671359)
			(xy 91.351894 -230.736674) (xy 91.38322 -230.80571) (xy 91.40703 -230.877685) (xy 91.423055 -230.951783)
			(xy 91.431114 -231.027164) (xy 91.431618 -231.06507) (xy 91.431114 -231.102976) (xy 91.423055 -231.178357)
			(xy 91.40703 -231.252455) (xy 91.38322 -231.32443) (xy 91.351894 -231.393466) (xy 91.313407 -231.458781)
			(xy 91.268196 -231.519636) (xy 91.216772 -231.57534) (xy 91.159719 -231.625262) (xy 91.097683 -231.668837)
			(xy 91.031366 -231.705572) (xy 90.96152 -231.735049) (xy 90.888937 -231.756935) (xy 90.814439 -231.770982)
			(xy 90.738869 -231.777031) (xy 90.663085 -231.775012) (xy 90.587945 -231.76495) (xy 90.5143 -231.746958)
			(xy 90.442984 -231.72124) (xy 90.374807 -231.688088) (xy 90.310539 -231.647876) (xy 90.25091 -231.601061)
			(xy 90.196594 -231.548173) (xy 90.148208 -231.489811) (xy 90.1063 -231.426636) (xy 90.071344 -231.359365)
			(xy 90.043737 -231.28876) (xy 90.023791 -231.215619) (xy 90.011732 -231.140774) (xy 90.007697 -231.06507)
			(xy 88.891618 -231.06507) (xy 88.891114 -231.102976) (xy 88.883055 -231.178357) (xy 88.86703 -231.252455)
			(xy 88.84322 -231.32443) (xy 88.811894 -231.393466) (xy 88.773407 -231.458781) (xy 88.728196 -231.519636)
			(xy 88.676772 -231.57534) (xy 88.619719 -231.625262) (xy 88.557683 -231.668837) (xy 88.491366 -231.705572)
			(xy 88.42152 -231.735049) (xy 88.348937 -231.756935) (xy 88.274439 -231.770982) (xy 88.198869 -231.777031)
			(xy 88.123085 -231.775012) (xy 88.047945 -231.76495) (xy 87.9743 -231.746958) (xy 87.902984 -231.72124)
			(xy 87.834807 -231.688088) (xy 87.770539 -231.647876) (xy 87.71091 -231.601061) (xy 87.656594 -231.548173)
			(xy 87.608208 -231.489811) (xy 87.5663 -231.426636) (xy 87.531344 -231.359365) (xy 87.503737 -231.28876)
			(xy 87.483791 -231.215619) (xy 87.471732 -231.140774) (xy 87.467697 -231.06507) (xy 86.351618 -231.06507)
			(xy 86.351114 -231.102976) (xy 86.343055 -231.178357) (xy 86.32703 -231.252455) (xy 86.30322 -231.32443)
			(xy 86.271894 -231.393466) (xy 86.233407 -231.458781) (xy 86.188196 -231.519636) (xy 86.136772 -231.57534)
			(xy 86.079719 -231.625262) (xy 86.017683 -231.668837) (xy 85.951366 -231.705572) (xy 85.88152 -231.735049)
			(xy 85.808937 -231.756935) (xy 85.734439 -231.770982) (xy 85.658869 -231.777031) (xy 85.583085 -231.775012)
			(xy 85.507945 -231.76495) (xy 85.4343 -231.746958) (xy 85.362984 -231.72124) (xy 85.294807 -231.688088)
			(xy 85.230539 -231.647876) (xy 85.17091 -231.601061) (xy 85.116594 -231.548173) (xy 85.068208 -231.489811)
			(xy 85.0263 -231.426636) (xy 84.991344 -231.359365) (xy 84.963737 -231.28876) (xy 84.943791 -231.215619)
			(xy 84.931732 -231.140774) (xy 84.927697 -231.06507) (xy 82.585544 -231.06507) (xy 82.579599 -231.070272)
			(xy 82.517563 -231.113847) (xy 82.451246 -231.150582) (xy 82.3814 -231.180059) (xy 82.308817 -231.201945)
			(xy 82.234319 -231.215992) (xy 82.158749 -231.222041) (xy 82.082965 -231.220022) (xy 82.007825 -231.20996)
			(xy 81.93418 -231.191968) (xy 81.862864 -231.16625) (xy 81.794687 -231.133098) (xy 81.730419 -231.092886)
			(xy 81.67079 -231.046071) (xy 81.616474 -230.993183) (xy 81.568088 -230.934821) (xy 81.52618 -230.871646)
			(xy 81.491224 -230.804375) (xy 81.463617 -230.73377) (xy 81.443671 -230.660629) (xy 81.431612 -230.585784)
			(xy 81.427577 -230.51008) (xy 80.311498 -230.51008) (xy 80.310994 -230.547986) (xy 80.302935 -230.623367)
			(xy 80.28691 -230.697465) (xy 80.2631 -230.76944) (xy 80.231774 -230.838476) (xy 80.193287 -230.903791)
			(xy 80.148076 -230.964646) (xy 80.096652 -231.02035) (xy 80.039599 -231.070272) (xy 79.977563 -231.113847)
			(xy 79.911246 -231.150582) (xy 79.8414 -231.180059) (xy 79.768817 -231.201945) (xy 79.694319 -231.215992)
			(xy 79.618749 -231.222041) (xy 79.542965 -231.220022) (xy 79.467825 -231.20996) (xy 79.39418 -231.191968)
			(xy 79.322864 -231.16625) (xy 79.254687 -231.133098) (xy 79.190419 -231.092886) (xy 79.13079 -231.046071)
			(xy 79.076474 -230.993183) (xy 79.028088 -230.934821) (xy 78.98618 -230.871646) (xy 78.951224 -230.804375)
			(xy 78.923617 -230.73377) (xy 78.903671 -230.660629) (xy 78.891612 -230.585784) (xy 78.887577 -230.51008)
			(xy 77.771498 -230.51008) (xy 77.770994 -230.547986) (xy 77.762935 -230.623367) (xy 77.74691 -230.697465)
			(xy 77.7231 -230.76944) (xy 77.691774 -230.838476) (xy 77.653287 -230.903791) (xy 77.608076 -230.964646)
			(xy 77.556652 -231.02035) (xy 77.499599 -231.070272) (xy 77.437563 -231.113847) (xy 77.371246 -231.150582)
			(xy 77.3014 -231.180059) (xy 77.228817 -231.201945) (xy 77.154319 -231.215992) (xy 77.078749 -231.222041)
			(xy 77.002965 -231.220022) (xy 76.927825 -231.20996) (xy 76.85418 -231.191968) (xy 76.782864 -231.16625)
			(xy 76.714687 -231.133098) (xy 76.650419 -231.092886) (xy 76.59079 -231.046071) (xy 76.536474 -230.993183)
			(xy 76.488088 -230.934821) (xy 76.44618 -230.871646) (xy 76.411224 -230.804375) (xy 76.383617 -230.73377)
			(xy 76.363671 -230.660629) (xy 76.351612 -230.585784) (xy 76.347577 -230.51008) (xy 75.231498 -230.51008)
			(xy 75.230994 -230.547986) (xy 75.222935 -230.623367) (xy 75.20691 -230.697465) (xy 75.1831 -230.76944)
			(xy 75.151774 -230.838476) (xy 75.113287 -230.903791) (xy 75.068076 -230.964646) (xy 75.016652 -231.02035)
			(xy 74.959599 -231.070272) (xy 74.897563 -231.113847) (xy 74.831246 -231.150582) (xy 74.7614 -231.180059)
			(xy 74.688817 -231.201945) (xy 74.614319 -231.215992) (xy 74.538749 -231.222041) (xy 74.462965 -231.220022)
			(xy 74.387825 -231.20996) (xy 74.31418 -231.191968) (xy 74.242864 -231.16625) (xy 74.174687 -231.133098)
			(xy 74.110419 -231.092886) (xy 74.05079 -231.046071) (xy 73.996474 -230.993183) (xy 73.948088 -230.934821)
			(xy 73.90618 -230.871646) (xy 73.871224 -230.804375) (xy 73.843617 -230.73377) (xy 73.823671 -230.660629)
			(xy 73.811612 -230.585784) (xy 73.807577 -230.51008) (xy 72.691498 -230.51008) (xy 72.690994 -230.547986)
			(xy 72.682935 -230.623367) (xy 72.66691 -230.697465) (xy 72.6431 -230.76944) (xy 72.611774 -230.838476)
			(xy 72.573287 -230.903791) (xy 72.528076 -230.964646) (xy 72.476652 -231.02035) (xy 72.419599 -231.070272)
			(xy 72.357563 -231.113847) (xy 72.291246 -231.150582) (xy 72.2214 -231.180059) (xy 72.148817 -231.201945)
			(xy 72.074319 -231.215992) (xy 71.998749 -231.222041) (xy 71.922965 -231.220022) (xy 71.847825 -231.20996)
			(xy 71.77418 -231.191968) (xy 71.702864 -231.16625) (xy 71.634687 -231.133098) (xy 71.570419 -231.092886)
			(xy 71.51079 -231.046071) (xy 71.456474 -230.993183) (xy 71.408088 -230.934821) (xy 71.36618 -230.871646)
			(xy 71.331224 -230.804375) (xy 71.303617 -230.73377) (xy 71.283671 -230.660629) (xy 71.271612 -230.585784)
			(xy 71.267577 -230.51008) (xy 70.151498 -230.51008) (xy 70.150994 -230.547986) (xy 70.142935 -230.623367)
			(xy 70.12691 -230.697465) (xy 70.1031 -230.76944) (xy 70.071774 -230.838476) (xy 70.033287 -230.903791)
			(xy 69.988076 -230.964646) (xy 69.936652 -231.02035) (xy 69.879599 -231.070272) (xy 69.817563 -231.113847)
			(xy 69.751246 -231.150582) (xy 69.6814 -231.180059) (xy 69.608817 -231.201945) (xy 69.534319 -231.215992)
			(xy 69.458749 -231.222041) (xy 69.382965 -231.220022) (xy 69.307825 -231.20996) (xy 69.23418 -231.191968)
			(xy 69.162864 -231.16625) (xy 69.094687 -231.133098) (xy 69.030419 -231.092886) (xy 68.97079 -231.046071)
			(xy 68.916474 -230.993183) (xy 68.868088 -230.934821) (xy 68.82618 -230.871646) (xy 68.791224 -230.804375)
			(xy 68.763617 -230.73377) (xy 68.743671 -230.660629) (xy 68.731612 -230.585784) (xy 68.727577 -230.51008)
			(xy 67.611498 -230.51008) (xy 67.610994 -230.547986) (xy 67.602935 -230.623367) (xy 67.58691 -230.697465)
			(xy 67.5631 -230.76944) (xy 67.531774 -230.838476) (xy 67.493287 -230.903791) (xy 67.448076 -230.964646)
			(xy 67.396652 -231.02035) (xy 67.339599 -231.070272) (xy 67.277563 -231.113847) (xy 67.211246 -231.150582)
			(xy 67.1414 -231.180059) (xy 67.068817 -231.201945) (xy 66.994319 -231.215992) (xy 66.918749 -231.222041)
			(xy 66.842965 -231.220022) (xy 66.767825 -231.20996) (xy 66.69418 -231.191968) (xy 66.622864 -231.16625)
			(xy 66.554687 -231.133098) (xy 66.490419 -231.092886) (xy 66.43079 -231.046071) (xy 66.376474 -230.993183)
			(xy 66.328088 -230.934821) (xy 66.28618 -230.871646) (xy 66.251224 -230.804375) (xy 66.223617 -230.73377)
			(xy 66.203671 -230.660629) (xy 66.191612 -230.585784) (xy 66.187577 -230.51008) (xy 65.071498 -230.51008)
			(xy 65.070994 -230.547986) (xy 65.062935 -230.623367) (xy 65.04691 -230.697465) (xy 65.0231 -230.76944)
			(xy 64.991774 -230.838476) (xy 64.953287 -230.903791) (xy 64.908076 -230.964646) (xy 64.856652 -231.02035)
			(xy 64.799599 -231.070272) (xy 64.737563 -231.113847) (xy 64.671246 -231.150582) (xy 64.6014 -231.180059)
			(xy 64.528817 -231.201945) (xy 64.454319 -231.215992) (xy 64.378749 -231.222041) (xy 64.302965 -231.220022)
			(xy 64.227825 -231.20996) (xy 64.15418 -231.191968) (xy 64.082864 -231.16625) (xy 64.014687 -231.133098)
			(xy 63.950419 -231.092886) (xy 63.89079 -231.046071) (xy 63.836474 -230.993183) (xy 63.788088 -230.934821)
			(xy 63.74618 -230.871646) (xy 63.711224 -230.804375) (xy 63.683617 -230.73377) (xy 63.663671 -230.660629)
			(xy 63.651612 -230.585784) (xy 63.647577 -230.51008) (xy 42.500813 -230.51008) (xy 42.479042 -230.526857)
			(xy 42.381609 -230.591665) (xy 42.279905 -230.64954) (xy 42.174422 -230.700202) (xy 42.065671 -230.743404)
			(xy 41.954179 -230.778939) (xy 41.840485 -230.806634) (xy 41.725141 -230.826354) (xy 41.608704 -230.838005)
			(xy 41.491739 -230.84153) (xy 41.374812 -230.836912) (xy 41.258489 -230.824173) (xy 41.143334 -230.803375)
			(xy 41.029905 -230.774618) (xy 40.91875 -230.738042) (xy 40.810407 -230.693825) (xy 40.705403 -230.642179)
			(xy 40.604244 -230.583356) (xy 40.507421 -230.51764) (xy 40.415403 -230.445349) (xy 40.328636 -230.366834)
			(xy 40.247539 -230.282474) (xy 40.172506 -230.192679) (xy 40.103899 -230.097883) (xy 40.042051 -229.998544)
			(xy 39.987262 -229.895145) (xy 39.939796 -229.788186) (xy 39.899884 -229.678185) (xy 39.86772 -229.565674)
			(xy 39.843457 -229.451199) (xy 39.827215 -229.335313) (xy 39.819072 -229.218579) (xy 39.818564 -229.16007)
			(xy 29.72816 -229.16007) (xy 29.72816 -231.109266) (xy 29.729842 -231.131259) (xy 29.739825 -231.17422)
			(xy 29.75707 -231.214814) (xy 29.78106 -231.251824) (xy 29.811074 -231.284142) (xy 29.846214 -231.310797)
			(xy 29.885424 -231.330991) (xy 29.927531 -231.344117) (xy 29.971271 -231.349783) (xy 30.015332 -231.347819)
			(xy 30.058394 -231.338283) (xy 30.078934 -231.330246) (xy 30.118298 -231.313333) (xy 30.199474 -231.285911)
			(xy 30.282807 -231.265987) (xy 30.367608 -231.253727) (xy 30.453172 -231.249232) (xy 30.53879 -231.252539)
			(xy 30.623753 -231.263621) (xy 30.707355 -231.282387) (xy 30.788903 -231.30868) (xy 30.867721 -231.342282)
			(xy 30.943156 -231.382916) (xy 31.014581 -231.430243) (xy 31.081405 -231.483871) (xy 31.143073 -231.543356)
			(xy 31.199074 -231.608205) (xy 31.248943 -231.677879) (xy 31.292268 -231.7518) (xy 31.328688 -231.829357)
			(xy 31.357902 -231.909905) (xy 31.379667 -231.992776) (xy 31.393803 -232.077285) (xy 31.400193 -232.162728)
			(xy 31.398783 -232.248399) (xy 31.389586 -232.333586) (xy 31.372677 -232.417583) (xy 31.360872 -232.458768)
			(xy 31.355403 -232.481382) (xy 31.351838 -232.527766) (xy 31.356773 -232.574024) (xy 31.370043 -232.618612)
			(xy 31.391205 -232.660041) (xy 31.419552 -232.696927) (xy 31.454138 -232.72804) (xy 31.493808 -232.75234)
			(xy 31.537237 -232.769015) (xy 31.582976 -232.77751) (xy 31.606236 -232.778046) (xy 34.393124 -232.778046)
			(xy 34.416391 -232.777531) (xy 34.462149 -232.769068) (xy 34.505599 -232.752412) (xy 34.545289 -232.72812)
			(xy 34.579889 -232.697004) (xy 34.608243 -232.660107) (xy 34.629402 -232.618662) (xy 34.642657 -232.574056)
			(xy 34.647565 -232.527782) (xy 34.643962 -232.481388) (xy 34.638488 -232.458768) (xy 34.626465 -232.416698)
			(xy 34.609358 -232.330884) (xy 34.600297 -232.243852) (xy 34.599359 -232.156355) (xy 34.606554 -232.069149)
			(xy 34.621819 -231.982988) (xy 34.645022 -231.898618) (xy 34.675962 -231.816768) (xy 34.714372 -231.738147)
			(xy 34.759919 -231.663433) (xy 34.81221 -231.593274) (xy 34.870793 -231.528275) (xy 34.93516 -231.469)
			(xy 35.004755 -231.415961) (xy 35.078976 -231.369616) (xy 35.157182 -231.330366) (xy 35.238696 -231.298551)
			(xy 35.322812 -231.274445) (xy 35.408805 -231.258259) (xy 35.495929 -231.25013) (xy 35.583431 -231.25013)
			(xy 35.670555 -231.258259) (xy 35.756548 -231.274445) (xy 35.840664 -231.298551) (xy 35.922178 -231.330366)
			(xy 36.000384 -231.369616) (xy 36.074605 -231.415961) (xy 36.1442 -231.469) (xy 36.208567 -231.528275)
			(xy 36.26715 -231.593274) (xy 36.319441 -231.663433) (xy 36.364988 -231.738147) (xy 36.403398 -231.816768)
			(xy 36.434338 -231.898618) (xy 36.457541 -231.982988) (xy 36.472806 -232.069149) (xy 36.480001 -232.156355)
			(xy 36.479063 -232.243852) (xy 36.470002 -232.330884) (xy 36.452895 -232.416698) (xy 36.440872 -232.458768)
			(xy 36.435403 -232.481382) (xy 36.431838 -232.527766) (xy 36.436773 -232.574024) (xy 36.450043 -232.618612)
			(xy 36.471205 -232.660041) (xy 36.499552 -232.696927) (xy 36.534138 -232.72804) (xy 36.573808 -232.75234)
			(xy 36.617237 -232.769015) (xy 36.662976 -232.77751) (xy 36.686236 -232.778046) (xy 39.036498 -232.778046)
			(xy 40.399716 -234.141264) (xy 45.081444 -234.141264) (xy 46.528228 -235.588302) (xy 46.528228 -236.24438)
			(xy 81.805254 -236.24438) (xy 81.805254 -236.184444) (xy 81.813077 -236.125022) (xy 81.82859 -236.067129)
			(xy 81.851526 -236.011756) (xy 81.881493 -235.95985) (xy 81.91798 -235.9123) (xy 81.96036 -235.86992)
			(xy 82.00791 -235.833433) (xy 82.059816 -235.803466) (xy 82.115189 -235.78053) (xy 82.173082 -235.765017)
			(xy 82.232504 -235.757194) (xy 82.29244 -235.757194) (xy 82.351862 -235.765017) (xy 82.409755 -235.78053)
			(xy 82.465128 -235.803466) (xy 82.517034 -235.833433) (xy 82.564584 -235.86992) (xy 82.606964 -235.9123)
			(xy 82.643451 -235.95985) (xy 82.673418 -236.011756) (xy 82.696354 -236.067129) (xy 82.711867 -236.125022)
			(xy 82.71969 -236.184444) (xy 82.72018 -236.214412) (xy 82.71969 -236.24438) (xy 82.711867 -236.303802)
			(xy 82.696354 -236.361695) (xy 82.673418 -236.417068) (xy 82.643451 -236.468974) (xy 82.606964 -236.516524)
			(xy 82.564584 -236.558904) (xy 82.517034 -236.595391) (xy 82.465128 -236.625358) (xy 82.409755 -236.648294)
			(xy 82.351862 -236.663807) (xy 82.29244 -236.67163) (xy 82.232504 -236.67163) (xy 82.173082 -236.663807)
			(xy 82.115189 -236.648294) (xy 82.059816 -236.625358) (xy 82.00791 -236.595391) (xy 81.96036 -236.558904)
			(xy 81.91798 -236.516524) (xy 81.881493 -236.468974) (xy 81.851526 -236.417068) (xy 81.82859 -236.361695)
			(xy 81.813077 -236.303802) (xy 81.805254 -236.24438) (xy 46.528228 -236.24438) (xy 46.528228 -237.078516)
			(xy 83.002864 -237.078516) (xy 83.002864 -237.01858) (xy 83.010687 -236.959158) (xy 83.0262 -236.901265)
			(xy 83.049136 -236.845892) (xy 83.079103 -236.793986) (xy 83.11559 -236.746436) (xy 83.15797 -236.704056)
			(xy 83.20552 -236.667569) (xy 83.257426 -236.637602) (xy 83.312799 -236.614666) (xy 83.370692 -236.599153)
			(xy 83.430114 -236.59133) (xy 83.49005 -236.59133) (xy 83.549472 -236.599153) (xy 83.607365 -236.614666)
			(xy 83.662738 -236.637602) (xy 83.714644 -236.667569) (xy 83.762194 -236.704056) (xy 83.804574 -236.746436)
			(xy 83.841061 -236.793986) (xy 83.871028 -236.845892) (xy 83.893964 -236.901265) (xy 83.909477 -236.959158)
			(xy 83.9173 -237.01858) (xy 83.91779 -237.048548) (xy 83.9173 -237.078516) (xy 83.909477 -237.137938)
			(xy 83.893964 -237.195831) (xy 83.893845 -237.196118) (xy 86.831406 -237.196118) (xy 86.831406 -237.136182)
			(xy 86.839229 -237.07676) (xy 86.854742 -237.018867) (xy 86.877678 -236.963494) (xy 86.907645 -236.911588)
			(xy 86.944132 -236.864038) (xy 86.986512 -236.821658) (xy 87.034062 -236.785171) (xy 87.085968 -236.755204)
			(xy 87.141341 -236.732268) (xy 87.199234 -236.716755) (xy 87.258656 -236.708932) (xy 87.318592 -236.708932)
			(xy 87.378014 -236.716755) (xy 87.435907 -236.732268) (xy 87.49128 -236.755204) (xy 87.543186 -236.785171)
			(xy 87.590736 -236.821658) (xy 87.633116 -236.864038) (xy 87.669603 -236.911588) (xy 87.69957 -236.963494)
			(xy 87.722506 -237.018867) (xy 87.738019 -237.07676) (xy 87.745842 -237.136182) (xy 87.746332 -237.16615)
			(xy 87.745842 -237.196118) (xy 87.738019 -237.25554) (xy 87.722506 -237.313433) (xy 87.69957 -237.368806)
			(xy 87.669603 -237.420712) (xy 87.633116 -237.468262) (xy 87.590736 -237.510642) (xy 87.543186 -237.547129)
			(xy 87.49128 -237.577096) (xy 87.435907 -237.600032) (xy 87.378014 -237.615545) (xy 87.318592 -237.623368)
			(xy 87.258656 -237.623368) (xy 87.199234 -237.615545) (xy 87.141341 -237.600032) (xy 87.085968 -237.577096)
			(xy 87.034062 -237.547129) (xy 86.986512 -237.510642) (xy 86.944132 -237.468262) (xy 86.907645 -237.420712)
			(xy 86.877678 -237.368806) (xy 86.854742 -237.313433) (xy 86.839229 -237.25554) (xy 86.831406 -237.196118)
			(xy 83.893845 -237.196118) (xy 83.871028 -237.251204) (xy 83.841061 -237.30311) (xy 83.804574 -237.35066)
			(xy 83.762194 -237.39304) (xy 83.714644 -237.429527) (xy 83.662738 -237.459494) (xy 83.607365 -237.48243)
			(xy 83.549472 -237.497943) (xy 83.49005 -237.505766) (xy 83.430114 -237.505766) (xy 83.370692 -237.497943)
			(xy 83.312799 -237.48243) (xy 83.257426 -237.459494) (xy 83.20552 -237.429527) (xy 83.15797 -237.39304)
			(xy 83.11559 -237.35066) (xy 83.079103 -237.30311) (xy 83.049136 -237.251204) (xy 83.0262 -237.195831)
			(xy 83.010687 -237.137938) (xy 83.002864 -237.078516) (xy 46.528228 -237.078516) (xy 46.528228 -238.094516)
			(xy 84.927422 -238.094516) (xy 84.927422 -238.03458) (xy 84.935245 -237.975158) (xy 84.950758 -237.917265)
			(xy 84.973694 -237.861892) (xy 85.003661 -237.809986) (xy 85.040148 -237.762436) (xy 85.082528 -237.720056)
			(xy 85.130078 -237.683569) (xy 85.181984 -237.653602) (xy 85.237357 -237.630666) (xy 85.29525 -237.615153)
			(xy 85.354672 -237.60733) (xy 85.414608 -237.60733) (xy 85.47403 -237.615153) (xy 85.531923 -237.630666)
			(xy 85.587296 -237.653602) (xy 85.639202 -237.683569) (xy 85.686752 -237.720056) (xy 85.729132 -237.762436)
			(xy 85.765619 -237.809986) (xy 85.795586 -237.861892) (xy 85.818522 -237.917265) (xy 85.834035 -237.975158)
			(xy 85.841858 -238.03458) (xy 85.842348 -238.064548) (xy 85.841858 -238.094516) (xy 85.834035 -238.153938)
			(xy 85.818522 -238.211831) (xy 85.795586 -238.267204) (xy 85.765619 -238.31911) (xy 85.729132 -238.36666)
			(xy 85.686752 -238.40904) (xy 85.639202 -238.445527) (xy 85.587296 -238.475494) (xy 85.531923 -238.49843)
			(xy 85.47403 -238.513943) (xy 85.414608 -238.521766) (xy 85.354672 -238.521766) (xy 85.29525 -238.513943)
			(xy 85.237357 -238.49843) (xy 85.181984 -238.475494) (xy 85.130078 -238.445527) (xy 85.082528 -238.40904)
			(xy 85.040148 -238.36666) (xy 85.003661 -238.31911) (xy 84.973694 -238.267204) (xy 84.950758 -238.211831)
			(xy 84.935245 -238.153938) (xy 84.927422 -238.094516) (xy 46.528228 -238.094516) (xy 46.528228 -239.08918)
			(xy 80.45626 -239.08918) (xy 80.45626 -239.029244) (xy 80.464083 -238.969822) (xy 80.479596 -238.911929)
			(xy 80.502532 -238.856556) (xy 80.532499 -238.80465) (xy 80.568986 -238.7571) (xy 80.611366 -238.71472)
			(xy 80.658916 -238.678233) (xy 80.710822 -238.648266) (xy 80.766195 -238.62533) (xy 80.824088 -238.609817)
			(xy 80.88351 -238.601994) (xy 80.943446 -238.601994) (xy 81.002868 -238.609817) (xy 81.060761 -238.62533)
			(xy 81.116134 -238.648266) (xy 81.16804 -238.678233) (xy 81.21559 -238.71472) (xy 81.23699 -238.73612)
			(xy 82.510866 -238.73612) (xy 82.510866 -238.676184) (xy 82.518689 -238.616762) (xy 82.534202 -238.558869)
			(xy 82.557138 -238.503496) (xy 82.587105 -238.45159) (xy 82.623592 -238.40404) (xy 82.665972 -238.36166)
			(xy 82.713522 -238.325173) (xy 82.765428 -238.295206) (xy 82.820801 -238.27227) (xy 82.878694 -238.256757)
			(xy 82.938116 -238.248934) (xy 82.998052 -238.248934) (xy 83.057474 -238.256757) (xy 83.115367 -238.27227)
			(xy 83.17074 -238.295206) (xy 83.222646 -238.325173) (xy 83.270196 -238.36166) (xy 83.312576 -238.40404)
			(xy 83.349063 -238.45159) (xy 83.37903 -238.503496) (xy 83.401966 -238.558869) (xy 83.417479 -238.616762)
			(xy 83.425302 -238.676184) (xy 83.425792 -238.706152) (xy 83.425302 -238.73612) (xy 83.417479 -238.795542)
			(xy 83.401966 -238.853435) (xy 83.37903 -238.908808) (xy 83.349063 -238.960714) (xy 83.312576 -239.008264)
			(xy 83.270196 -239.050644) (xy 83.222646 -239.087131) (xy 83.17074 -239.117098) (xy 83.115367 -239.140034)
			(xy 83.057474 -239.155547) (xy 82.998052 -239.16337) (xy 82.938116 -239.16337) (xy 82.878694 -239.155547)
			(xy 82.820801 -239.140034) (xy 82.765428 -239.117098) (xy 82.713522 -239.087131) (xy 82.665972 -239.050644)
			(xy 82.623592 -239.008264) (xy 82.587105 -238.960714) (xy 82.557138 -238.908808) (xy 82.534202 -238.853435)
			(xy 82.518689 -238.795542) (xy 82.510866 -238.73612) (xy 81.23699 -238.73612) (xy 81.25797 -238.7571)
			(xy 81.294457 -238.80465) (xy 81.324424 -238.856556) (xy 81.34736 -238.911929) (xy 81.362873 -238.969822)
			(xy 81.370696 -239.029244) (xy 81.371186 -239.059212) (xy 81.370696 -239.08918) (xy 81.362873 -239.148602)
			(xy 81.34736 -239.206495) (xy 81.324424 -239.261868) (xy 81.294457 -239.313774) (xy 81.25797 -239.361324)
			(xy 81.21559 -239.403704) (xy 81.16804 -239.440191) (xy 81.116134 -239.470158) (xy 81.060761 -239.493094)
			(xy 81.002868 -239.508607) (xy 80.943446 -239.51643) (xy 80.88351 -239.51643) (xy 80.824088 -239.508607)
			(xy 80.766195 -239.493094) (xy 80.710822 -239.470158) (xy 80.658916 -239.440191) (xy 80.611366 -239.403704)
			(xy 80.568986 -239.361324) (xy 80.532499 -239.313774) (xy 80.502532 -239.261868) (xy 80.479596 -239.206495)
			(xy 80.464083 -239.148602) (xy 80.45626 -239.08918) (xy 46.528228 -239.08918) (xy 46.528228 -239.741452)
			(xy 84.00464 -239.741452) (xy 84.00464 -239.681516) (xy 84.012463 -239.622094) (xy 84.027976 -239.564201)
			(xy 84.050912 -239.508828) (xy 84.080879 -239.456922) (xy 84.117366 -239.409372) (xy 84.159746 -239.366992)
			(xy 84.207296 -239.330505) (xy 84.259202 -239.300538) (xy 84.314575 -239.277602) (xy 84.372468 -239.262089)
			(xy 84.43189 -239.254266) (xy 84.491826 -239.254266) (xy 84.551248 -239.262089) (xy 84.609141 -239.277602)
			(xy 84.664514 -239.300538) (xy 84.71642 -239.330505) (xy 84.76397 -239.366992) (xy 84.80635 -239.409372)
			(xy 84.842837 -239.456922) (xy 84.872804 -239.508828) (xy 84.89574 -239.564201) (xy 84.911253 -239.622094)
			(xy 84.919076 -239.681516) (xy 84.919566 -239.711484) (xy 84.919076 -239.741452) (xy 84.911253 -239.800874)
			(xy 84.89574 -239.858767) (xy 84.872804 -239.91414) (xy 84.842837 -239.966046) (xy 84.80635 -240.013596)
			(xy 84.76397 -240.055976) (xy 84.71642 -240.092463) (xy 84.664514 -240.12243) (xy 84.609141 -240.145366)
			(xy 84.551248 -240.160879) (xy 84.491826 -240.168702) (xy 84.43189 -240.168702) (xy 84.372468 -240.160879)
			(xy 84.314575 -240.145366) (xy 84.259202 -240.12243) (xy 84.207296 -240.092463) (xy 84.159746 -240.055976)
			(xy 84.117366 -240.013596) (xy 84.080879 -239.966046) (xy 84.050912 -239.91414) (xy 84.027976 -239.858767)
			(xy 84.012463 -239.800874) (xy 84.00464 -239.741452) (xy 46.528228 -239.741452) (xy 46.528228 -239.7633)
			(xy 52.53736 -239.7633) (xy 54.188868 -239.7633) (xy 54.188868 -240.340384) (xy 81.863674 -240.340384)
			(xy 81.863674 -240.280448) (xy 81.871497 -240.221026) (xy 81.88701 -240.163133) (xy 81.909946 -240.10776)
			(xy 81.939913 -240.055854) (xy 81.9764 -240.008304) (xy 82.01878 -239.965924) (xy 82.06633 -239.929437)
			(xy 82.118236 -239.89947) (xy 82.173609 -239.876534) (xy 82.231502 -239.861021) (xy 82.290924 -239.853198)
			(xy 82.35086 -239.853198) (xy 82.410282 -239.861021) (xy 82.468175 -239.876534) (xy 82.523548 -239.89947)
			(xy 82.575454 -239.929437) (xy 82.623004 -239.965924) (xy 82.665384 -240.008304) (xy 82.701871 -240.055854)
			(xy 82.731838 -240.10776) (xy 82.754774 -240.163133) (xy 82.770287 -240.221026) (xy 82.77811 -240.280448)
			(xy 82.7786 -240.310416) (xy 82.77811 -240.340384) (xy 82.770287 -240.399806) (xy 82.754774 -240.457699)
			(xy 82.731838 -240.513072) (xy 82.701871 -240.564978) (xy 82.665384 -240.612528) (xy 82.623004 -240.654908)
			(xy 82.575454 -240.691395) (xy 82.523548 -240.721362) (xy 82.468175 -240.744298) (xy 82.410282 -240.759811)
			(xy 82.35086 -240.767634) (xy 82.290924 -240.767634) (xy 82.231502 -240.759811) (xy 82.173609 -240.744298)
			(xy 82.118236 -240.721362) (xy 82.06633 -240.691395) (xy 82.01878 -240.654908) (xy 81.9764 -240.612528)
			(xy 81.939913 -240.564978) (xy 81.909946 -240.513072) (xy 81.88701 -240.457699) (xy 81.871497 -240.399806)
			(xy 81.863674 -240.340384) (xy 54.188868 -240.340384) (xy 54.188868 -241.133414) (xy 66.360686 -241.133414)
			(xy 66.364571 -241.079062) (xy 66.376152 -241.025815) (xy 66.395194 -240.974758) (xy 66.421307 -240.926931)
			(xy 66.453961 -240.883308) (xy 66.492492 -240.844775) (xy 66.536114 -240.812119) (xy 66.583939 -240.786002)
			(xy 66.634994 -240.766958) (xy 66.68824 -240.755374) (xy 66.742593 -240.751486) (xy 66.796946 -240.755372)
			(xy 66.850192 -240.766955) (xy 66.901249 -240.785997) (xy 66.949075 -240.812111) (xy 66.971164 -240.828068)
			(xy 66.990176 -240.841664) (xy 67.032059 -240.862396) (xy 67.077027 -240.875122) (xy 67.123564 -240.879412)
			(xy 67.170101 -240.875122) (xy 67.215069 -240.862396) (xy 67.256952 -240.841664) (xy 67.275964 -240.828068)
			(xy 67.298076 -240.812137) (xy 67.345902 -240.786014) (xy 67.39696 -240.766964) (xy 67.450209 -240.755374)
			(xy 67.504566 -240.751481) (xy 67.558923 -240.755364) (xy 67.612175 -240.766944) (xy 67.663236 -240.785986)
			(xy 67.711067 -240.8121) (xy 67.754695 -240.844757) (xy 67.79323 -240.883291) (xy 67.825889 -240.926916)
			(xy 67.852006 -240.974746) (xy 67.87105 -241.025806) (xy 67.882633 -241.079057) (xy 67.886519 -241.133414)
			(xy 69.352279 -241.133414) (xy 69.356164 -241.07906) (xy 69.367746 -241.025812) (xy 69.386788 -240.974754)
			(xy 69.412902 -240.926925) (xy 69.445558 -240.883301) (xy 69.48409 -240.844767) (xy 69.527713 -240.81211)
			(xy 69.575541 -240.785994) (xy 69.626598 -240.76695) (xy 69.679846 -240.755366) (xy 69.7342 -240.751479)
			(xy 69.788554 -240.755366) (xy 69.841802 -240.76695) (xy 69.892859 -240.785994) (xy 69.940687 -240.81211)
			(xy 69.962776 -240.828068) (xy 69.981788 -240.841664) (xy 70.023671 -240.862396) (xy 70.068639 -240.875122)
			(xy 70.115176 -240.879412) (xy 70.161713 -240.875122) (xy 70.206681 -240.862396) (xy 70.248564 -240.841664)
			(xy 70.267576 -240.828068) (xy 70.289687 -240.812138) (xy 70.337513 -240.786017) (xy 70.38857 -240.766968)
			(xy 70.441818 -240.75538) (xy 70.496173 -240.751488) (xy 70.550528 -240.755372) (xy 70.603778 -240.766953)
			(xy 70.654837 -240.785994) (xy 70.702667 -240.812109) (xy 70.746293 -240.844765) (xy 70.784827 -240.883298)
			(xy 70.817484 -240.926922) (xy 70.8436 -240.974751) (xy 70.858236 -241.013992) (xy 83.347034 -241.013992)
			(xy 83.347034 -240.954056) (xy 83.354857 -240.894634) (xy 83.37037 -240.836741) (xy 83.393306 -240.781368)
			(xy 83.423273 -240.729462) (xy 83.45976 -240.681912) (xy 83.50214 -240.639532) (xy 83.54969 -240.603045)
			(xy 83.601596 -240.573078) (xy 83.656969 -240.550142) (xy 83.714862 -240.534629) (xy 83.774284 -240.526806)
			(xy 83.83422 -240.526806) (xy 83.893642 -240.534629) (xy 83.951535 -240.550142) (xy 84.006908 -240.573078)
			(xy 84.058814 -240.603045) (xy 84.106364 -240.639532) (xy 84.148744 -240.681912) (xy 84.185231 -240.729462)
			(xy 84.215198 -240.781368) (xy 84.238134 -240.836741) (xy 84.253647 -240.894634) (xy 84.26147 -240.954056)
			(xy 84.26196 -240.984024) (xy 84.26147 -241.013992) (xy 84.253647 -241.073414) (xy 84.238134 -241.131307)
			(xy 84.215198 -241.18668) (xy 84.185231 -241.238586) (xy 84.148744 -241.286136) (xy 84.106364 -241.328516)
			(xy 84.058814 -241.365003) (xy 84.006908 -241.39497) (xy 83.951535 -241.417906) (xy 83.893642 -241.433419)
			(xy 83.83422 -241.441242) (xy 83.774284 -241.441242) (xy 83.714862 -241.433419) (xy 83.656969 -241.417906)
			(xy 83.601596 -241.39497) (xy 83.54969 -241.365003) (xy 83.50214 -241.328516) (xy 83.45976 -241.286136)
			(xy 83.423273 -241.238586) (xy 83.393306 -241.18668) (xy 83.37037 -241.131307) (xy 83.354857 -241.073414)
			(xy 83.347034 -241.013992) (xy 70.858236 -241.013992) (xy 70.862644 -241.02581) (xy 70.874226 -241.079059)
			(xy 70.878112 -241.133414) (xy 70.874222 -241.18777) (xy 70.862635 -241.241018) (xy 70.843588 -241.292075)
			(xy 70.817469 -241.339902) (xy 70.784808 -241.383524) (xy 70.746271 -241.422054) (xy 70.702643 -241.454707)
			(xy 70.654811 -241.480818) (xy 70.60375 -241.499855) (xy 70.5505 -241.511432) (xy 70.496144 -241.515312)
			(xy 70.441789 -241.511416) (xy 70.388542 -241.499824) (xy 70.337487 -241.480771) (xy 70.289663 -241.454646)
			(xy 70.267576 -241.438684) (xy 70.248564 -241.425088) (xy 70.206681 -241.404356) (xy 70.161713 -241.39163)
			(xy 70.115176 -241.38734) (xy 70.068639 -241.39163) (xy 70.023671 -241.404356) (xy 69.981788 -241.425088)
			(xy 69.962776 -241.438684) (xy 69.940711 -241.454674) (xy 69.892886 -241.480794) (xy 69.84183 -241.499842)
			(xy 69.788583 -241.51143) (xy 69.734229 -241.515321) (xy 69.679874 -241.511438) (xy 69.626625 -241.499858)
			(xy 69.575567 -241.480818) (xy 69.527738 -241.454705) (xy 69.484112 -241.422051) (xy 69.445577 -241.383521)
			(xy 69.412918 -241.339899) (xy 69.3868 -241.292073) (xy 69.367754 -241.241016) (xy 69.356168 -241.187769)
			(xy 69.352279 -241.133414) (xy 67.886519 -241.133414) (xy 67.882629 -241.187771) (xy 67.871042 -241.241021)
			(xy 67.851994 -241.29208) (xy 67.825873 -241.339908) (xy 67.793211 -241.383531) (xy 67.754673 -241.422062)
			(xy 67.711043 -241.454715) (xy 67.66321 -241.480826) (xy 67.612147 -241.499864) (xy 67.558895 -241.51144)
			(xy 67.504537 -241.515319) (xy 67.450181 -241.511422) (xy 67.396932 -241.499828) (xy 67.345876 -241.480774)
			(xy 67.298051 -241.454647) (xy 67.275964 -241.438684) (xy 67.256952 -241.425088) (xy 67.215069 -241.404356)
			(xy 67.170101 -241.39163) (xy 67.123564 -241.38734) (xy 67.077027 -241.39163) (xy 67.032059 -241.404356)
			(xy 66.990176 -241.425088) (xy 66.971164 -241.438684) (xy 66.949099 -241.454673) (xy 66.901275 -241.480791)
			(xy 66.85022 -241.499837) (xy 66.796974 -241.511424) (xy 66.742622 -241.515314) (xy 66.688269 -241.51143)
			(xy 66.635022 -241.49985) (xy 66.583965 -241.48081) (xy 66.536138 -241.454697) (xy 66.492513 -241.422044)
			(xy 66.45398 -241.383514) (xy 66.421323 -241.339893) (xy 66.395206 -241.292068) (xy 66.37616 -241.241013)
			(xy 66.364575 -241.187767) (xy 66.360686 -241.133414) (xy 54.188868 -241.133414) (xy 54.188868 -241.415316)
			(xy 52.53736 -241.415316) (xy 52.53736 -239.7633) (xy 46.528228 -239.7633) (xy 46.528228 -240.629863)
			(xy 49.037484 -240.629863) (xy 49.037484 -240.548753) (xy 49.045434 -240.468034) (xy 49.061257 -240.388483)
			(xy 49.084802 -240.310867) (xy 49.115841 -240.235931) (xy 49.154076 -240.164399) (xy 49.199138 -240.096959)
			(xy 49.250593 -240.03426) (xy 49.307946 -239.976907) (xy 49.370645 -239.925452) (xy 49.438085 -239.88039)
			(xy 49.509617 -239.842155) (xy 49.584553 -239.811116) (xy 49.662169 -239.787571) (xy 49.74172 -239.771748)
			(xy 49.822439 -239.763798) (xy 49.903549 -239.763798) (xy 49.984268 -239.771748) (xy 50.063819 -239.787571)
			(xy 50.141435 -239.811116) (xy 50.216371 -239.842155) (xy 50.287903 -239.88039) (xy 50.355343 -239.925452)
			(xy 50.418042 -239.976907) (xy 50.475395 -240.03426) (xy 50.52685 -240.096959) (xy 50.571912 -240.164399)
			(xy 50.610147 -240.235931) (xy 50.641186 -240.310867) (xy 50.664731 -240.388483) (xy 50.680554 -240.468034)
			(xy 50.688504 -240.548753) (xy 50.689002 -240.589308) (xy 50.688504 -240.629863) (xy 50.680554 -240.710582)
			(xy 50.664731 -240.790133) (xy 50.641186 -240.867749) (xy 50.610147 -240.942685) (xy 50.571912 -241.014217)
			(xy 50.52685 -241.081657) (xy 50.475395 -241.144356) (xy 50.418042 -241.201709) (xy 50.355343 -241.253164)
			(xy 50.287903 -241.298226) (xy 50.216371 -241.336461) (xy 50.141435 -241.3675) (xy 50.063819 -241.391045)
			(xy 49.984268 -241.406868) (xy 49.903549 -241.414818) (xy 49.822439 -241.414818) (xy 49.74172 -241.406868)
			(xy 49.662169 -241.391045) (xy 49.584553 -241.3675) (xy 49.509617 -241.336461) (xy 49.438085 -241.298226)
			(xy 49.370645 -241.253164) (xy 49.307946 -241.201709) (xy 49.250593 -241.144356) (xy 49.199138 -241.081657)
			(xy 49.154076 -241.014217) (xy 49.115841 -240.942685) (xy 49.084802 -240.867749) (xy 49.061257 -240.790133)
			(xy 49.045434 -240.710582) (xy 49.037484 -240.629863) (xy 46.528228 -240.629863) (xy 46.528228 -241.730526)
			(xy 81.184732 -241.730526) (xy 81.184732 -241.67059) (xy 81.192555 -241.611168) (xy 81.208068 -241.553275)
			(xy 81.231004 -241.497902) (xy 81.260971 -241.445996) (xy 81.297458 -241.398446) (xy 81.339838 -241.356066)
			(xy 81.387388 -241.319579) (xy 81.439294 -241.289612) (xy 81.494667 -241.266676) (xy 81.55256 -241.251163)
			(xy 81.611982 -241.24334) (xy 81.671918 -241.24334) (xy 81.73134 -241.251163) (xy 81.789233 -241.266676)
			(xy 81.844606 -241.289612) (xy 81.896512 -241.319579) (xy 81.944062 -241.356066) (xy 81.986442 -241.398446)
			(xy 82.022929 -241.445996) (xy 82.052896 -241.497902) (xy 82.075832 -241.553275) (xy 82.091345 -241.611168)
			(xy 82.099168 -241.67059) (xy 82.099658 -241.700558) (xy 82.099168 -241.730526) (xy 82.091345 -241.789948)
			(xy 82.075832 -241.847841) (xy 82.052896 -241.903214) (xy 82.022929 -241.95512) (xy 81.986442 -242.00267)
			(xy 81.944062 -242.04505) (xy 81.896512 -242.081537) (xy 81.844606 -242.111504) (xy 81.789233 -242.13444)
			(xy 81.73134 -242.149953) (xy 81.671918 -242.157776) (xy 81.611982 -242.157776) (xy 81.55256 -242.149953)
			(xy 81.494667 -242.13444) (xy 81.439294 -242.111504) (xy 81.387388 -242.081537) (xy 81.339838 -242.04505)
			(xy 81.297458 -242.00267) (xy 81.260971 -241.95512) (xy 81.231004 -241.903214) (xy 81.208068 -241.847841)
			(xy 81.192555 -241.789948) (xy 81.184732 -241.730526) (xy 46.528228 -241.730526) (xy 46.528228 -242.26012)
			(xy 86.39887 -242.26012) (xy 86.402874 -242.060022) (xy 86.414881 -241.860244) (xy 86.434872 -241.661107)
			(xy 86.462814 -241.462929) (xy 86.498662 -241.266027) (xy 86.54236 -241.070718) (xy 86.593837 -240.877313)
			(xy 86.653011 -240.686123) (xy 86.719787 -240.497453) (xy 86.794059 -240.311606) (xy 86.875706 -240.128879)
			(xy 86.964599 -239.949566) (xy 87.060595 -239.773952) (xy 87.16354 -239.60232) (xy 87.27327 -239.434944)
			(xy 87.389608 -239.272093) (xy 87.512369 -239.114026) (xy 87.641356 -238.960998) (xy 87.776363 -238.813253)
			(xy 87.917172 -238.671027) (xy 88.063559 -238.53455) (xy 88.215289 -238.404038) (xy 88.37212 -238.279702)
			(xy 88.533799 -238.16174) (xy 88.700069 -238.050341) (xy 88.870662 -237.945684) (xy 89.045306 -237.847936)
			(xy 89.223722 -237.757253) (xy 89.405622 -237.673782) (xy 89.590717 -237.597655) (xy 89.778709 -237.528995)
			(xy 89.969298 -237.467911) (xy 90.162178 -237.414501) (xy 90.35704 -237.368852) (xy 90.553573 -237.331035)
			(xy 90.751462 -237.301111) (xy 90.950389 -237.279129) (xy 91.150037 -237.265124) (xy 91.350085 -237.259118)
			(xy 91.550213 -237.26112) (xy 91.750101 -237.271128) (xy 91.949428 -237.289125) (xy 92.147876 -237.315083)
			(xy 92.345126 -237.34896) (xy 92.540863 -237.390702) (xy 92.734773 -237.440241) (xy 92.926546 -237.497499)
			(xy 93.115875 -237.562384) (xy 93.302455 -237.634792) (xy 93.48599 -237.714608) (xy 93.666184 -237.801702)
			(xy 93.842749 -237.895936) (xy 94.015402 -237.997159) (xy 94.183867 -238.105209) (xy 94.347875 -238.219912)
			(xy 94.507162 -238.341086) (xy 94.661473 -238.468535) (xy 94.810561 -238.602056) (xy 94.954188 -238.741436)
			(xy 95.092124 -238.88645) (xy 95.224147 -239.036867) (xy 95.350046 -239.192445) (xy 95.46962 -239.352937)
			(xy 95.582676 -239.518083) (xy 95.689035 -239.687621) (xy 95.788526 -239.861279) (xy 95.880989 -240.038778)
			(xy 95.966276 -240.219834) (xy 96.044251 -240.404158) (xy 96.114788 -240.591454) (xy 96.177776 -240.781422)
			(xy 96.233113 -240.973758) (xy 96.28071 -241.168154) (xy 96.320491 -241.364299) (xy 96.352393 -241.561878)
			(xy 96.376364 -241.760575) (xy 96.392366 -241.960073) (xy 96.400373 -242.160051) (xy 96.400874 -242.26012)
			(xy 96.400373 -242.360189) (xy 96.392366 -242.560167) (xy 96.376364 -242.759665) (xy 96.352393 -242.958362)
			(xy 96.320491 -243.155941) (xy 96.28071 -243.352086) (xy 96.233113 -243.546482) (xy 96.177776 -243.738818)
			(xy 96.114788 -243.928786) (xy 96.044251 -244.116082) (xy 95.966276 -244.300406) (xy 95.880989 -244.481462)
			(xy 95.788526 -244.658961) (xy 95.689035 -244.832619) (xy 95.582676 -245.002157) (xy 95.46962 -245.167303)
			(xy 95.350046 -245.327795) (xy 95.224147 -245.483373) (xy 95.092124 -245.63379) (xy 94.954188 -245.778804)
			(xy 94.810561 -245.918184) (xy 94.661473 -246.051705) (xy 94.507162 -246.179154) (xy 94.347875 -246.300328)
			(xy 94.183867 -246.415031) (xy 94.015402 -246.523081) (xy 93.842749 -246.624304) (xy 93.666184 -246.718538)
			(xy 93.48599 -246.805632) (xy 93.302455 -246.885448) (xy 93.115875 -246.957856) (xy 92.926546 -247.022741)
			(xy 92.734773 -247.079999) (xy 92.540863 -247.129538) (xy 92.345126 -247.17128) (xy 92.147876 -247.205157)
			(xy 91.949428 -247.231115) (xy 91.750101 -247.249112) (xy 91.550213 -247.25912) (xy 91.350085 -247.261122)
			(xy 91.150037 -247.255116) (xy 90.950389 -247.241111) (xy 90.751462 -247.219129) (xy 90.553573 -247.189205)
			(xy 90.35704 -247.151388) (xy 90.162178 -247.105739) (xy 89.969298 -247.052329) (xy 89.778709 -246.991245)
			(xy 89.590717 -246.922585) (xy 89.405622 -246.846458) (xy 89.223722 -246.762987) (xy 89.045306 -246.672304)
			(xy 88.870662 -246.574556) (xy 88.700069 -246.469899) (xy 88.533799 -246.3585) (xy 88.37212 -246.240538)
			(xy 88.215289 -246.116202) (xy 88.063559 -245.98569) (xy 87.917172 -245.849213) (xy 87.776363 -245.706987)
			(xy 87.641356 -245.559242) (xy 87.512369 -245.406214) (xy 87.389608 -245.248147) (xy 87.27327 -245.085296)
			(xy 87.16354 -244.91792) (xy 87.060595 -244.746288) (xy 86.964599 -244.570674) (xy 86.875706 -244.391361)
			(xy 86.794059 -244.208634) (xy 86.719787 -244.022787) (xy 86.653011 -243.834117) (xy 86.593837 -243.642927)
			(xy 86.54236 -243.449522) (xy 86.498662 -243.254213) (xy 86.462814 -243.057311) (xy 86.434872 -242.859133)
			(xy 86.414881 -242.659996) (xy 86.402874 -242.460218) (xy 86.39887 -242.26012) (xy 46.528228 -242.26012)
			(xy 46.528228 -243.804208) (xy 66.360694 -243.804208) (xy 66.36458 -243.749857) (xy 66.376162 -243.696611)
			(xy 66.395203 -243.645556) (xy 66.421317 -243.597731) (xy 66.453971 -243.554108) (xy 66.492501 -243.515577)
			(xy 66.536123 -243.482922) (xy 66.583948 -243.456807) (xy 66.635002 -243.437764) (xy 66.688248 -243.426181)
			(xy 66.742599 -243.422294) (xy 66.796951 -243.426181) (xy 66.850196 -243.437764) (xy 66.901251 -243.456806)
			(xy 66.949076 -243.482921) (xy 66.971164 -243.498878) (xy 66.990176 -243.512474) (xy 67.032059 -243.533206)
			(xy 67.077027 -243.545932) (xy 67.123564 -243.550222) (xy 67.170101 -243.545932) (xy 67.215069 -243.533206)
			(xy 67.256952 -243.512474) (xy 67.275964 -243.498878) (xy 67.298066 -243.482934) (xy 67.345893 -243.456809)
			(xy 67.396952 -243.437758) (xy 67.450202 -243.426167) (xy 67.50456 -243.422273) (xy 67.558919 -243.426155)
			(xy 67.612171 -243.437735) (xy 67.663234 -243.456776) (xy 67.711066 -243.482891) (xy 67.754695 -243.515547)
			(xy 67.793232 -243.554081) (xy 67.825892 -243.597707) (xy 67.852011 -243.645537) (xy 67.871056 -243.696598)
			(xy 67.88264 -243.74985) (xy 67.886527 -243.804208) (xy 69.352287 -243.804208) (xy 69.356173 -243.749855)
			(xy 69.367755 -243.696608) (xy 69.386798 -243.645552) (xy 69.412912 -243.597725) (xy 69.445568 -243.554101)
			(xy 69.4841 -243.51557) (xy 69.527723 -243.482914) (xy 69.575549 -243.456799) (xy 69.626606 -243.437756)
			(xy 69.679853 -243.426173) (xy 69.734206 -243.422287) (xy 69.788559 -243.426175) (xy 69.841806 -243.437759)
			(xy 69.892862 -243.456804) (xy 69.940687 -243.48292) (xy 69.962776 -243.498878) (xy 69.981788 -243.512474)
			(xy 70.023671 -243.533206) (xy 70.068639 -243.545932) (xy 70.115176 -243.550222) (xy 70.161713 -243.545932)
			(xy 70.206681 -243.533206) (xy 70.248564 -243.512474) (xy 70.267576 -243.498878) (xy 70.289678 -243.482935)
			(xy 70.337504 -243.456812) (xy 70.388562 -243.437762) (xy 70.44181 -243.426173) (xy 70.496167 -243.42228)
			(xy 70.550524 -243.426163) (xy 70.603775 -243.437743) (xy 70.654835 -243.456785) (xy 70.702666 -243.482899)
			(xy 70.746293 -243.515555) (xy 70.784829 -243.554088) (xy 70.817488 -243.597713) (xy 70.843605 -243.645542)
			(xy 70.86265 -243.696602) (xy 70.874233 -243.749852) (xy 70.87812 -243.804208) (xy 70.874231 -243.858565)
			(xy 70.862645 -243.911815) (xy 70.843598 -243.962873) (xy 70.817479 -244.010701) (xy 70.784818 -244.054325)
			(xy 70.746281 -244.092856) (xy 70.702652 -244.12551) (xy 70.65482 -244.151622) (xy 70.603758 -244.170661)
			(xy 70.550507 -244.182239) (xy 70.49615 -244.18612) (xy 70.441794 -244.182225) (xy 70.388545 -244.170633)
			(xy 70.337489 -244.151581) (xy 70.289664 -244.125456) (xy 70.267576 -244.109494) (xy 70.248564 -244.095898)
			(xy 70.206681 -244.075166) (xy 70.161713 -244.06244) (xy 70.115176 -244.05815) (xy 70.068639 -244.06244)
			(xy 70.023671 -244.075166) (xy 69.981788 -244.095898) (xy 69.962776 -244.109494) (xy 69.940702 -244.125471)
			(xy 69.892877 -244.151589) (xy 69.841822 -244.170636) (xy 69.788576 -244.182223) (xy 69.734223 -244.186113)
			(xy 69.679869 -244.182229) (xy 69.626622 -244.170649) (xy 69.575565 -244.151608) (xy 69.527737 -244.125495)
			(xy 69.484112 -244.092841) (xy 69.445579 -244.054311) (xy 69.412921 -244.010689) (xy 69.386805 -243.962864)
			(xy 69.36776 -243.911808) (xy 69.356175 -243.858562) (xy 69.352287 -243.804208) (xy 67.886527 -243.804208)
			(xy 67.882638 -243.858567) (xy 67.871051 -243.911818) (xy 67.852004 -243.962878) (xy 67.825883 -244.010707)
			(xy 67.793221 -244.054332) (xy 67.754683 -244.092864) (xy 67.711052 -244.125519) (xy 67.663218 -244.151631)
			(xy 67.612155 -244.17067) (xy 67.558902 -244.182247) (xy 67.504543 -244.186127) (xy 67.450185 -244.182231)
			(xy 67.396936 -244.170638) (xy 67.345878 -244.151584) (xy 67.298052 -244.125457) (xy 67.275964 -244.109494)
			(xy 67.256952 -244.095898) (xy 67.215069 -244.075166) (xy 67.170101 -244.06244) (xy 67.123564 -244.05815)
			(xy 67.077027 -244.06244) (xy 67.032059 -244.075166) (xy 66.990176 -244.095898) (xy 66.971164 -244.109494)
			(xy 66.94909 -244.12547) (xy 66.901266 -244.151587) (xy 66.850212 -244.170631) (xy 66.796967 -244.182217)
			(xy 66.742616 -244.186106) (xy 66.688264 -244.182221) (xy 66.635019 -244.17064) (xy 66.583963 -244.1516)
			(xy 66.536137 -244.125487) (xy 66.492514 -244.092834) (xy 66.453982 -244.054304) (xy 66.421326 -244.010683)
			(xy 66.39521 -243.962859) (xy 66.376166 -243.911805) (xy 66.364582 -243.85856) (xy 66.360694 -243.804208)
			(xy 46.528228 -243.804208) (xy 46.528228 -245.644886) (xy 66.360724 -245.644886) (xy 66.364613 -245.590538)
			(xy 66.376197 -245.537298) (xy 66.39524 -245.486248) (xy 66.421355 -245.438428) (xy 66.454009 -245.394811)
			(xy 66.492539 -245.356285) (xy 66.536159 -245.323635) (xy 66.583981 -245.297525) (xy 66.635033 -245.278487)
			(xy 66.688274 -245.266908) (xy 66.742622 -245.263024) (xy 66.796969 -245.266914) (xy 66.850209 -245.278499)
			(xy 66.901259 -245.297544) (xy 66.949078 -245.323659) (xy 66.971164 -245.339616) (xy 66.990176 -245.353212)
			(xy 67.032059 -245.373944) (xy 67.077027 -245.38667) (xy 67.123564 -245.39096) (xy 67.170101 -245.38667)
			(xy 67.215069 -245.373944) (xy 67.256952 -245.353212) (xy 67.275964 -245.339616) (xy 67.298031 -245.323621)
			(xy 67.34586 -245.297491) (xy 67.396921 -245.278435) (xy 67.450175 -245.26684) (xy 67.504537 -245.262943)
			(xy 67.5589 -245.266822) (xy 67.612158 -245.278399) (xy 67.663226 -245.297439) (xy 67.711064 -245.323553)
			(xy 67.754698 -245.356209) (xy 67.79324 -245.394744) (xy 67.825906 -245.438371) (xy 67.852029 -245.486204)
			(xy 67.871079 -245.537268) (xy 67.882667 -245.590523) (xy 67.886557 -245.644886) (xy 69.352317 -245.644886)
			(xy 69.356206 -245.590537) (xy 69.367791 -245.537295) (xy 69.386835 -245.486243) (xy 69.41295 -245.438422)
			(xy 69.445606 -245.394804) (xy 69.484137 -245.356278) (xy 69.527758 -245.323627) (xy 69.575583 -245.297517)
			(xy 69.626636 -245.278479) (xy 69.67988 -245.2669) (xy 69.734229 -245.263017) (xy 69.788577 -245.266908)
			(xy 69.841819 -245.278495) (xy 69.89287 -245.297541) (xy 69.94069 -245.323658) (xy 69.962776 -245.339616)
			(xy 69.981788 -245.353212) (xy 70.023671 -245.373944) (xy 70.068639 -245.38667) (xy 70.115176 -245.39096)
			(xy 70.161713 -245.38667) (xy 70.206681 -245.373944) (xy 70.248564 -245.353212) (xy 70.267576 -245.339616)
			(xy 70.289642 -245.323622) (xy 70.337471 -245.297494) (xy 70.388531 -245.278439) (xy 70.441784 -245.266846)
			(xy 70.496144 -245.26295) (xy 70.550505 -245.26683) (xy 70.603761 -245.278408) (xy 70.654827 -245.297447)
			(xy 70.702663 -245.323561) (xy 70.746296 -245.356217) (xy 70.784837 -245.394751) (xy 70.817501 -245.438377)
			(xy 70.843623 -245.486209) (xy 70.862672 -245.537271) (xy 70.87426 -245.590525) (xy 70.87815 -245.644886)
			(xy 70.874264 -245.699247) (xy 70.86268 -245.752501) (xy 70.843635 -245.803565) (xy 70.817516 -245.851398)
			(xy 70.784856 -245.895028) (xy 70.746318 -245.933564) (xy 70.702688 -245.966223) (xy 70.654853 -245.992341)
			(xy 70.603789 -246.011384) (xy 70.550534 -246.022966) (xy 70.496173 -246.02685) (xy 70.441812 -246.022958)
			(xy 70.388559 -246.011369) (xy 70.337497 -245.992318) (xy 70.289666 -245.966194) (xy 70.267576 -245.950232)
			(xy 70.248564 -245.936636) (xy 70.206681 -245.915904) (xy 70.161713 -245.903178) (xy 70.115176 -245.898888)
			(xy 70.068639 -245.903178) (xy 70.023671 -245.915904) (xy 69.981788 -245.936636) (xy 69.962776 -245.950232)
			(xy 69.940666 -245.966158) (xy 69.892843 -245.992271) (xy 69.841791 -246.011313) (xy 69.788549 -246.022896)
			(xy 69.7342 -246.026783) (xy 69.679851 -246.022896) (xy 69.626609 -246.011313) (xy 69.575557 -245.992271)
			(xy 69.527734 -245.966158) (xy 69.484115 -245.933504) (xy 69.445587 -245.894974) (xy 69.412935 -245.851354)
			(xy 69.386823 -245.80353) (xy 69.367783 -245.752478) (xy 69.356202 -245.699235) (xy 69.352317 -245.644886)
			(xy 67.886557 -245.644886) (xy 67.882671 -245.699248) (xy 67.871087 -245.752504) (xy 67.852041 -245.80357)
			(xy 67.825921 -245.851404) (xy 67.793259 -245.895035) (xy 67.75472 -245.933572) (xy 67.711088 -245.966232)
			(xy 67.663252 -245.992349) (xy 67.612186 -246.011392) (xy 67.558929 -246.022974) (xy 67.504566 -246.026857)
			(xy 67.450204 -246.022964) (xy 67.396949 -246.011373) (xy 67.345886 -245.992321) (xy 67.298055 -245.966195)
			(xy 67.275964 -245.950232) (xy 67.256952 -245.936636) (xy 67.215069 -245.915904) (xy 67.170101 -245.903178)
			(xy 67.123564 -245.898888) (xy 67.077027 -245.903178) (xy 67.032059 -245.915904) (xy 66.990176 -245.936636)
			(xy 66.971164 -245.950232) (xy 66.949054 -245.966157) (xy 66.901233 -245.992268) (xy 66.850182 -246.011309)
			(xy 66.79694 -246.02289) (xy 66.742593 -246.026776) (xy 66.688246 -246.022888) (xy 66.635005 -246.011305)
			(xy 66.583955 -245.992263) (xy 66.536134 -245.966149) (xy 66.492517 -245.933496) (xy 66.45399 -245.894967)
			(xy 66.421339 -245.851348) (xy 66.395228 -245.803526) (xy 66.376189 -245.752474) (xy 66.364609 -245.699233)
			(xy 66.360724 -245.644886) (xy 46.528228 -245.644886) (xy 46.528228 -245.693692) (xy 45.12437 -247.097296)
			(xy 45.029374 -247.097296) (xy 45.014115 -247.09775) (xy 44.984474 -247.105016) (xy 44.957413 -247.119124)
			(xy 44.934484 -247.139264) (xy 44.917005 -247.16428) (xy 44.91101 -247.178322) (xy 44.899476 -247.206599)
			(xy 44.86998 -247.260074) (xy 44.833637 -247.309152) (xy 44.791092 -247.352963) (xy 44.743099 -247.390729)
			(xy 44.690512 -247.421779) (xy 44.634264 -247.445562) (xy 44.575353 -247.461656) (xy 44.514825 -247.469775)
			(xy 44.453755 -247.469775) (xy 44.393227 -247.461656) (xy 44.334316 -247.445562) (xy 44.278068 -247.421779)
			(xy 44.225481 -247.390729) (xy 44.177488 -247.352963) (xy 44.134943 -247.309152) (xy 44.0986 -247.260074)
			(xy 44.069104 -247.206599) (xy 44.05757 -247.178322) (xy 44.051625 -247.16426) (xy 44.034126 -247.139252)
			(xy 44.011184 -247.119122) (xy 43.984113 -247.105023) (xy 43.954467 -247.097765) (xy 43.939206 -247.097296)
			(xy 43.049444 -247.097296) (xy 42.977816 -247.160034) (xy 42.971466 -247.207278) (xy 42.966122 -247.243269)
			(xy 42.948259 -247.313808) (xy 42.92246 -247.381846) (xy 42.88906 -247.446493) (xy 42.85718 -247.493974)
			(xy 66.323798 -247.493974) (xy 66.32769 -247.439619) (xy 66.339278 -247.386372) (xy 66.358326 -247.335317)
			(xy 66.384447 -247.287492) (xy 66.417109 -247.243871) (xy 66.455647 -247.205344) (xy 66.499276 -247.172693)
			(xy 66.547108 -247.146585) (xy 66.598168 -247.12755) (xy 66.651418 -247.115976) (xy 66.705774 -247.112098)
			(xy 66.760128 -247.115997) (xy 66.813373 -247.127591) (xy 66.864427 -247.146646) (xy 66.912248 -247.172773)
			(xy 66.934334 -247.188736) (xy 66.953346 -247.202332) (xy 66.995229 -247.223064) (xy 67.040197 -247.23579)
			(xy 67.086734 -247.24008) (xy 67.133271 -247.23579) (xy 67.178239 -247.223064) (xy 67.220122 -247.202332)
			(xy 67.239134 -247.188736) (xy 67.26118 -247.17272) (xy 67.309006 -247.146599) (xy 67.360062 -247.12755)
			(xy 67.41331 -247.115961) (xy 67.467665 -247.112069) (xy 67.522021 -247.115951) (xy 67.57527 -247.12753)
			(xy 67.62633 -247.146569) (xy 67.674161 -247.172682) (xy 67.717788 -247.205335) (xy 67.756325 -247.243865)
			(xy 67.788985 -247.287487) (xy 67.815105 -247.335314) (xy 67.834153 -247.386371) (xy 67.84574 -247.439619)
			(xy 67.849631 -247.493974) (xy 69.315391 -247.493974) (xy 69.319283 -247.439618) (xy 69.330871 -247.386369)
			(xy 69.349921 -247.335312) (xy 69.376043 -247.287486) (xy 69.408706 -247.243864) (xy 69.447245 -247.205336)
			(xy 69.490876 -247.172685) (xy 69.538709 -247.146576) (xy 69.589772 -247.127541) (xy 69.643024 -247.115968)
			(xy 69.697381 -247.112091) (xy 69.751736 -247.115991) (xy 69.804983 -247.127587) (xy 69.856037 -247.146643)
			(xy 69.90386 -247.172772) (xy 69.925946 -247.188736) (xy 69.944958 -247.202332) (xy 69.986841 -247.223064)
			(xy 70.031809 -247.23579) (xy 70.078346 -247.24008) (xy 70.124883 -247.23579) (xy 70.169851 -247.223064)
			(xy 70.211734 -247.202332) (xy 70.230746 -247.188736) (xy 70.252792 -247.172721) (xy 70.300617 -247.146602)
			(xy 70.351672 -247.127555) (xy 70.404918 -247.115967) (xy 70.459272 -247.112076) (xy 70.513626 -247.115959)
			(xy 70.566874 -247.127539) (xy 70.617932 -247.146578) (xy 70.665761 -247.17269) (xy 70.709386 -247.205343)
			(xy 70.747921 -247.243872) (xy 70.78058 -247.287493) (xy 70.806699 -247.335318) (xy 70.825746 -247.386374)
			(xy 70.837333 -247.43962) (xy 70.841224 -247.493974) (xy 70.83734 -247.548328) (xy 70.825761 -247.601575)
			(xy 70.806721 -247.652633) (xy 70.780609 -247.700462) (xy 70.747956 -247.744088) (xy 70.709426 -247.782622)
			(xy 70.665805 -247.815281) (xy 70.61798 -247.8414) (xy 70.566924 -247.860447) (xy 70.513678 -247.872033)
			(xy 70.459325 -247.875924) (xy 70.404971 -247.87204) (xy 70.351723 -247.86046) (xy 70.300665 -247.84142)
			(xy 70.252836 -247.815308) (xy 70.230746 -247.799352) (xy 70.211734 -247.785756) (xy 70.169851 -247.765024)
			(xy 70.124883 -247.752298) (xy 70.078346 -247.748008) (xy 70.031809 -247.752298) (xy 69.986841 -247.765024)
			(xy 69.944958 -247.785756) (xy 69.925946 -247.799352) (xy 69.903815 -247.815257) (xy 69.855989 -247.841379)
			(xy 69.804932 -247.860428) (xy 69.751684 -247.872017) (xy 69.697328 -247.875909) (xy 69.642971 -247.872025)
			(xy 69.589721 -247.860444) (xy 69.538661 -247.841402) (xy 69.490831 -247.815287) (xy 69.447205 -247.78263)
			(xy 69.408671 -247.744096) (xy 69.376014 -247.70047) (xy 69.349899 -247.65264) (xy 69.330856 -247.60158)
			(xy 69.319275 -247.54833) (xy 69.315391 -247.493974) (xy 67.849631 -247.493974) (xy 67.845748 -247.548329)
			(xy 67.834167 -247.601579) (xy 67.815127 -247.652638) (xy 67.789014 -247.700468) (xy 67.756359 -247.744095)
			(xy 67.717828 -247.78263) (xy 67.674205 -247.81529) (xy 67.626378 -247.841409) (xy 67.575321 -247.860455)
			(xy 67.522073 -247.872041) (xy 67.467718 -247.875931) (xy 67.413362 -247.872046) (xy 67.360113 -247.860465)
			(xy 67.309054 -247.841423) (xy 67.261225 -247.815309) (xy 67.239134 -247.799352) (xy 67.220122 -247.785756)
			(xy 67.178239 -247.765024) (xy 67.133271 -247.752298) (xy 67.086734 -247.748008) (xy 67.040197 -247.752298)
			(xy 66.995229 -247.765024) (xy 66.953346 -247.785756) (xy 66.934334 -247.799352) (xy 66.912204 -247.815255)
			(xy 66.864379 -247.841376) (xy 66.813323 -247.860424) (xy 66.760075 -247.872011) (xy 66.705721 -247.875902)
			(xy 66.651366 -247.872017) (xy 66.598118 -247.860435) (xy 66.54706 -247.841393) (xy 66.499232 -247.815278)
			(xy 66.455607 -247.782622) (xy 66.417075 -247.744089) (xy 66.384419 -247.700464) (xy 66.358304 -247.652635)
			(xy 66.339263 -247.601577) (xy 66.327682 -247.548328) (xy 66.323798 -247.493974) (xy 42.85718 -247.493974)
			(xy 42.848499 -247.506904) (xy 42.801305 -247.562289) (xy 42.748096 -247.611923) (xy 42.689568 -247.655158)
			(xy 42.626486 -247.691427) (xy 42.559676 -247.720257) (xy 42.490011 -247.74127) (xy 42.418403 -247.754192)
			(xy 42.345787 -247.758854) (xy 42.273114 -247.755194) (xy 42.201335 -247.743261) (xy 42.131387 -247.72321)
			(xy 42.064185 -247.695305) (xy 42.00061 -247.659908) (xy 41.941491 -247.617485) (xy 41.887603 -247.568589)
			(xy 41.863264 -247.541542) (xy 41.845992 -247.521984) (xy 41.741344 -247.471946) (xy 41.693592 -247.486932)
			(xy 41.668053 -247.494451) (xy 41.61553 -247.503155) (xy 41.562308 -247.504471) (xy 41.509419 -247.498374)
			(xy 41.457892 -247.484982) (xy 41.408728 -247.464556) (xy 41.362881 -247.437492) (xy 41.321243 -247.404317)
			(xy 41.284622 -247.365674) (xy 41.25373 -247.322314) (xy 41.229167 -247.275081) (xy 41.21141 -247.22489)
			(xy 41.205658 -247.198896) (xy 41.196768 -247.154446) (xy 41.126664 -247.097296) (xy 40.176958 -247.097296)
			(xy 39.1414 -248.1326) (xy 39.130052 -248.144749) (xy 39.113465 -248.173545) (xy 39.104876 -248.205647)
			(xy 39.104316 -248.222262) (xy 39.104316 -249.021342) (xy 43.99837 -249.021342) (xy 43.99837 -248.961406)
			(xy 44.006193 -248.901984) (xy 44.021706 -248.844091) (xy 44.044642 -248.788718) (xy 44.074609 -248.736812)
			(xy 44.111096 -248.689262) (xy 44.153476 -248.646882) (xy 44.201026 -248.610395) (xy 44.252932 -248.580428)
			(xy 44.308305 -248.557492) (xy 44.366198 -248.541979) (xy 44.42562 -248.534156) (xy 44.485556 -248.534156)
			(xy 44.544978 -248.541979) (xy 44.602871 -248.557492) (xy 44.658244 -248.580428) (xy 44.71015 -248.610395)
			(xy 44.7577 -248.646882) (xy 44.80008 -248.689262) (xy 44.836567 -248.736812) (xy 44.866534 -248.788718)
			(xy 44.88947 -248.844091) (xy 44.904983 -248.901984) (xy 44.912806 -248.961406) (xy 44.913296 -248.991374)
			(xy 44.912806 -249.021342) (xy 44.904983 -249.080764) (xy 44.88947 -249.138657) (xy 44.866534 -249.19403)
			(xy 44.836567 -249.245936) (xy 44.80008 -249.293486) (xy 44.7577 -249.335866) (xy 44.71015 -249.372353)
			(xy 44.658244 -249.40232) (xy 44.602871 -249.425256) (xy 44.544978 -249.440769) (xy 44.485556 -249.448592)
			(xy 44.42562 -249.448592) (xy 44.366198 -249.440769) (xy 44.308305 -249.425256) (xy 44.252932 -249.40232)
			(xy 44.201026 -249.372353) (xy 44.153476 -249.335866) (xy 44.111096 -249.293486) (xy 44.074609 -249.245936)
			(xy 44.044642 -249.19403) (xy 44.021706 -249.138657) (xy 44.006193 -249.080764) (xy 43.99837 -249.021342)
			(xy 39.104316 -249.021342) (xy 39.104316 -249.793496) (xy 41.197561 -249.793496) (xy 41.20145 -249.739136)
			(xy 41.213036 -249.685882) (xy 41.232083 -249.63482) (xy 41.258205 -249.586988) (xy 41.290868 -249.543362)
			(xy 41.329408 -249.504828) (xy 41.37304 -249.472172) (xy 41.420876 -249.446058) (xy 41.471941 -249.427018)
			(xy 41.525197 -249.415441) (xy 41.579558 -249.411561) (xy 41.633918 -249.415457) (xy 41.68717 -249.427051)
			(xy 41.738229 -249.446106) (xy 41.786057 -249.472234) (xy 41.808146 -249.488198) (xy 41.827158 -249.501794)
			(xy 41.869041 -249.522526) (xy 41.914009 -249.535252) (xy 41.960546 -249.539542) (xy 42.007083 -249.535252)
			(xy 42.052051 -249.522526) (xy 42.093934 -249.501794) (xy 42.112946 -249.488198) (xy 42.135027 -249.472234)
			(xy 42.18285 -249.44612) (xy 42.233903 -249.427077) (xy 42.287145 -249.415494) (xy 42.341495 -249.411606)
			(xy 42.395844 -249.415493) (xy 42.449087 -249.427074) (xy 42.50014 -249.446115) (xy 42.520122 -249.457026)
			(xy 66.323728 -249.457026) (xy 66.327613 -249.402662) (xy 66.339195 -249.349403) (xy 66.35824 -249.298335)
			(xy 66.38436 -249.250498) (xy 66.417022 -249.206865) (xy 66.455561 -249.168325) (xy 66.499193 -249.135663)
			(xy 66.54703 -249.109543) (xy 66.598098 -249.090497) (xy 66.651356 -249.078913) (xy 66.705721 -249.075028)
			(xy 66.760085 -249.078919) (xy 66.813342 -249.090509) (xy 66.864408 -249.10956) (xy 66.912242 -249.135685)
			(xy 66.934334 -249.151648) (xy 66.953346 -249.165244) (xy 66.995229 -249.185976) (xy 67.040197 -249.198702)
			(xy 67.086734 -249.202992) (xy 67.133271 -249.198702) (xy 67.178239 -249.185976) (xy 67.220122 -249.165244)
			(xy 67.239134 -249.151648) (xy 67.261263 -249.13575) (xy 67.309083 -249.109641) (xy 67.360133 -249.090603)
			(xy 67.413372 -249.079023) (xy 67.467718 -249.075139) (xy 67.522063 -249.079029) (xy 67.575301 -249.090613)
			(xy 67.626349 -249.109655) (xy 67.674167 -249.135769) (xy 67.717782 -249.168423) (xy 67.756306 -249.206951)
			(xy 67.788954 -249.25057) (xy 67.815063 -249.298391) (xy 67.8341 -249.349441) (xy 67.845678 -249.402681)
			(xy 67.849561 -249.457026) (xy 69.315321 -249.457026) (xy 69.319206 -249.40266) (xy 69.330789 -249.3494)
			(xy 69.349835 -249.298331) (xy 69.375955 -249.250492) (xy 69.408618 -249.206858) (xy 69.447159 -249.168317)
			(xy 69.490793 -249.135654) (xy 69.538632 -249.109534) (xy 69.589701 -249.090488) (xy 69.642961 -249.078905)
			(xy 69.697328 -249.075021) (xy 69.751694 -249.078913) (xy 69.804952 -249.090504) (xy 69.856019 -249.109557)
			(xy 69.903854 -249.135684) (xy 69.925946 -249.151648) (xy 69.944958 -249.165244) (xy 69.986841 -249.185976)
			(xy 70.031809 -249.198702) (xy 70.078346 -249.202992) (xy 70.124883 -249.198702) (xy 70.169851 -249.185976)
			(xy 70.211734 -249.165244) (xy 70.230746 -249.151648) (xy 70.252874 -249.135751) (xy 70.300694 -249.109644)
			(xy 70.351743 -249.090607) (xy 70.404981 -249.07903) (xy 70.459325 -249.075146) (xy 70.513668 -249.079037)
			(xy 70.566904 -249.090621) (xy 70.617951 -249.109664) (xy 70.665767 -249.135778) (xy 70.70938 -249.168431)
			(xy 70.747903 -249.206958) (xy 70.78055 -249.250576) (xy 70.806657 -249.298396) (xy 70.825693 -249.349444)
			(xy 70.837271 -249.402683) (xy 70.841154 -249.457026) (xy 70.837263 -249.51137) (xy 70.825678 -249.564606)
			(xy 70.806635 -249.615652) (xy 70.780521 -249.663468) (xy 70.747868 -249.707082) (xy 70.70934 -249.745604)
			(xy 70.665722 -249.778251) (xy 70.617903 -249.804358) (xy 70.566854 -249.823394) (xy 70.513616 -249.834971)
			(xy 70.459272 -249.838854) (xy 70.404928 -249.834963) (xy 70.351692 -249.823378) (xy 70.300646 -249.804334)
			(xy 70.25283 -249.77822) (xy 70.230746 -249.762264) (xy 70.211734 -249.748668) (xy 70.169851 -249.727936)
			(xy 70.124883 -249.71521) (xy 70.078346 -249.71092) (xy 70.031809 -249.71521) (xy 69.986841 -249.727936)
			(xy 69.944958 -249.748668) (xy 69.925946 -249.762264) (xy 69.903898 -249.778287) (xy 69.856067 -249.804421)
			(xy 69.805003 -249.823481) (xy 69.751746 -249.835079) (xy 69.697381 -249.838979) (xy 69.643014 -249.835102)
			(xy 69.589752 -249.823526) (xy 69.53868 -249.804488) (xy 69.490838 -249.778374) (xy 69.447199 -249.745717)
			(xy 69.408653 -249.707182) (xy 69.375983 -249.663552) (xy 69.349857 -249.615717) (xy 69.330804 -249.564651)
			(xy 69.319213 -249.511392) (xy 69.315321 -249.457026) (xy 67.849561 -249.457026) (xy 67.84567 -249.511371)
			(xy 67.834085 -249.56461) (xy 67.815041 -249.615657) (xy 67.788926 -249.663474) (xy 67.756271 -249.707089)
			(xy 67.717742 -249.745612) (xy 67.674123 -249.778259) (xy 67.626301 -249.804367) (xy 67.57525 -249.823402)
			(xy 67.522011 -249.834979) (xy 67.467665 -249.838861) (xy 67.41332 -249.834969) (xy 67.360082 -249.823383)
			(xy 67.309035 -249.804337) (xy 67.261218 -249.778221) (xy 67.239134 -249.762264) (xy 67.220122 -249.748668)
			(xy 67.178239 -249.727936) (xy 67.133271 -249.71521) (xy 67.086734 -249.71092) (xy 67.040197 -249.71521)
			(xy 66.995229 -249.727936) (xy 66.953346 -249.748668) (xy 66.934334 -249.762264) (xy 66.912286 -249.778286)
			(xy 66.864456 -249.804418) (xy 66.813393 -249.823476) (xy 66.760138 -249.835073) (xy 66.705774 -249.838972)
			(xy 66.651408 -249.835094) (xy 66.598149 -249.823518) (xy 66.547078 -249.804479) (xy 66.499238 -249.778366)
			(xy 66.455601 -249.745709) (xy 66.417056 -249.707175) (xy 66.384388 -249.663546) (xy 66.358262 -249.615713)
			(xy 66.33921 -249.564648) (xy 66.32762 -249.511391) (xy 66.323728 -249.457026) (xy 42.520122 -249.457026)
			(xy 42.547963 -249.472228) (xy 42.591584 -249.504881) (xy 42.630113 -249.543409) (xy 42.662767 -249.587029)
			(xy 42.688881 -249.634852) (xy 42.707923 -249.685904) (xy 42.719506 -249.739147) (xy 42.723394 -249.793496)
			(xy 42.719507 -249.847846) (xy 42.707925 -249.901089) (xy 42.688884 -249.952142) (xy 42.662771 -249.999965)
			(xy 42.630118 -250.043585) (xy 42.591589 -250.082114) (xy 42.547969 -250.114768) (xy 42.500146 -250.140882)
			(xy 42.449094 -250.159924) (xy 42.395851 -250.171506) (xy 42.341502 -250.175394) (xy 42.287152 -250.171507)
			(xy 42.233909 -250.159925) (xy 42.182857 -250.140883) (xy 42.135034 -250.11477) (xy 42.112946 -250.098814)
			(xy 42.093934 -250.085218) (xy 42.052051 -250.064486) (xy 42.007083 -250.05176) (xy 41.960546 -250.04747)
			(xy 41.914009 -250.05176) (xy 41.869041 -250.064486) (xy 41.827158 -250.085218) (xy 41.808146 -250.098814)
			(xy 41.786051 -250.11477) (xy 41.738223 -250.140897) (xy 41.687163 -250.159951) (xy 41.633911 -250.171544)
			(xy 41.579551 -250.175439) (xy 41.52519 -250.171558) (xy 41.471934 -250.15998) (xy 41.420869 -250.140939)
			(xy 41.373034 -250.114824) (xy 41.329403 -250.082167) (xy 41.290863 -250.043633) (xy 41.258201 -250.000006)
			(xy 41.23208 -249.952173) (xy 41.213034 -249.901111) (xy 41.201448 -249.847857) (xy 41.197561 -249.793496)
			(xy 39.104316 -249.793496) (xy 39.104316 -251.4793) (xy 44.18125 -251.4793) (xy 44.18125 -251.419364)
			(xy 44.189073 -251.359942) (xy 44.204586 -251.302049) (xy 44.227522 -251.246676) (xy 44.257489 -251.19477)
			(xy 44.293976 -251.14722) (xy 44.336356 -251.10484) (xy 44.383906 -251.068353) (xy 44.435812 -251.038386)
			(xy 44.491185 -251.01545) (xy 44.549078 -250.999937) (xy 44.6085 -250.992114) (xy 44.668436 -250.992114)
			(xy 44.727858 -250.999937) (xy 44.785751 -251.01545) (xy 44.841124 -251.038386) (xy 44.89303 -251.068353)
			(xy 44.94058 -251.10484) (xy 44.98296 -251.14722) (xy 45.019447 -251.19477) (xy 45.049414 -251.246676)
			(xy 45.07235 -251.302049) (xy 45.087863 -251.359942) (xy 45.095686 -251.419364) (xy 45.096176 -251.449332)
			(xy 45.095686 -251.4793) (xy 45.087863 -251.538722) (xy 45.07235 -251.596615) (xy 45.070731 -251.600523)
			(xy 66.323733 -251.600523) (xy 66.327618 -251.546159) (xy 66.339201 -251.492901) (xy 66.358246 -251.441834)
			(xy 66.384366 -251.393998) (xy 66.417028 -251.350366) (xy 66.455567 -251.311826) (xy 66.499199 -251.279165)
			(xy 66.547036 -251.253045) (xy 66.598103 -251.234001) (xy 66.65136 -251.222418) (xy 66.705725 -251.218533)
			(xy 66.760088 -251.222425) (xy 66.813344 -251.234014) (xy 66.864409 -251.253066) (xy 66.912242 -251.279191)
			(xy 66.934334 -251.295154) (xy 66.953346 -251.30875) (xy 66.995229 -251.329482) (xy 67.040197 -251.342208)
			(xy 67.086734 -251.346498) (xy 67.133271 -251.342208) (xy 67.178239 -251.329482) (xy 67.220122 -251.30875)
			(xy 67.239134 -251.295154) (xy 67.261257 -251.279248) (xy 67.309078 -251.253138) (xy 67.360128 -251.234099)
			(xy 67.413368 -251.222519) (xy 67.467714 -251.218634) (xy 67.52206 -251.222523) (xy 67.575299 -251.234107)
			(xy 67.626348 -251.25315) (xy 67.674167 -251.279263) (xy 67.717783 -251.311917) (xy 67.756307 -251.350445)
			(xy 67.788957 -251.394064) (xy 67.815066 -251.441886) (xy 67.834103 -251.492936) (xy 67.845682 -251.546177)
			(xy 67.849566 -251.600523) (xy 69.315325 -251.600523) (xy 69.319211 -251.546157) (xy 69.330794 -251.492898)
			(xy 69.34984 -251.441829) (xy 69.375961 -251.393992) (xy 69.408624 -251.350359) (xy 69.447165 -251.311818)
			(xy 69.490799 -251.279156) (xy 69.538637 -251.253037) (xy 69.589706 -251.233992) (xy 69.642966 -251.22241)
			(xy 69.697331 -251.218525) (xy 69.751697 -251.222419) (xy 69.804954 -251.23401) (xy 69.85602 -251.253063)
			(xy 69.903854 -251.27919) (xy 69.925946 -251.295154) (xy 69.944958 -251.30875) (xy 69.986841 -251.329482)
			(xy 70.031809 -251.342208) (xy 70.078346 -251.346498) (xy 70.124883 -251.342208) (xy 70.169851 -251.329482)
			(xy 70.211734 -251.30875) (xy 70.230746 -251.295154) (xy 70.252869 -251.279249) (xy 70.300689 -251.253141)
			(xy 70.351738 -251.234104) (xy 70.404976 -251.222525) (xy 70.459321 -251.218641) (xy 70.513665 -251.222531)
			(xy 70.566902 -251.234115) (xy 70.617949 -251.253158) (xy 70.665766 -251.279272) (xy 70.709381 -251.311925)
			(xy 70.747904 -251.350452) (xy 70.780552 -251.39407) (xy 70.80666 -251.441891) (xy 70.825697 -251.49294)
			(xy 70.837275 -251.546178) (xy 70.841159 -251.600523) (xy 70.837268 -251.654867) (xy 70.825684 -251.708104)
			(xy 70.806641 -251.759151) (xy 70.780527 -251.806968) (xy 70.747874 -251.850582) (xy 70.709346 -251.889105)
			(xy 70.665728 -251.921753) (xy 70.617908 -251.947861) (xy 70.566859 -251.966897) (xy 70.51362 -251.978475)
			(xy 70.459275 -251.982359) (xy 70.404931 -251.978468) (xy 70.351694 -251.966884) (xy 70.300647 -251.94784)
			(xy 70.25283 -251.921726) (xy 70.230746 -251.90577) (xy 70.211734 -251.892174) (xy 70.169851 -251.871442)
			(xy 70.124883 -251.858716) (xy 70.078346 -251.854426) (xy 70.031809 -251.858716) (xy 69.986841 -251.871442)
			(xy 69.944958 -251.892174) (xy 69.925946 -251.90577) (xy 69.903892 -251.921785) (xy 69.856061 -251.947918)
			(xy 69.804998 -251.966977) (xy 69.751742 -251.978575) (xy 69.697377 -251.982475) (xy 69.643011 -251.978597)
			(xy 69.58975 -251.967021) (xy 69.538679 -251.947982) (xy 69.490837 -251.921868) (xy 69.447199 -251.889211)
			(xy 69.408654 -251.850676) (xy 69.375986 -251.807047) (xy 69.349859 -251.759212) (xy 69.330807 -251.708146)
			(xy 69.319217 -251.654888) (xy 69.315325 -251.600523) (xy 67.849566 -251.600523) (xy 67.845676 -251.654869)
			(xy 67.834091 -251.708107) (xy 67.815047 -251.759156) (xy 67.788932 -251.806974) (xy 67.756277 -251.850589)
			(xy 67.717748 -251.889113) (xy 67.674128 -251.921761) (xy 67.626306 -251.947869) (xy 67.575255 -251.966906)
			(xy 67.522015 -251.978483) (xy 67.467668 -251.982366) (xy 67.413323 -251.978474) (xy 67.360084 -251.966888)
			(xy 67.309036 -251.947843) (xy 67.261219 -251.921727) (xy 67.239134 -251.90577) (xy 67.220122 -251.892174)
			(xy 67.178239 -251.871442) (xy 67.133271 -251.858716) (xy 67.086734 -251.854426) (xy 67.040197 -251.858716)
			(xy 66.995229 -251.871442) (xy 66.953346 -251.892174) (xy 66.934334 -251.90577) (xy 66.912281 -251.921784)
			(xy 66.864451 -251.947915) (xy 66.813388 -251.966973) (xy 66.760133 -251.978569) (xy 66.70577 -251.982467)
			(xy 66.651406 -251.978589) (xy 66.598146 -251.967012) (xy 66.547077 -251.947973) (xy 66.499237 -251.92186)
			(xy 66.455601 -251.889204) (xy 66.417057 -251.850669) (xy 66.38439 -251.807041) (xy 66.358265 -251.759207)
			(xy 66.339214 -251.708143) (xy 66.327624 -251.654886) (xy 66.323733 -251.600523) (xy 45.070731 -251.600523)
			(xy 45.049414 -251.651988) (xy 45.019447 -251.703894) (xy 44.98296 -251.751444) (xy 44.94058 -251.793824)
			(xy 44.89303 -251.830311) (xy 44.841124 -251.860278) (xy 44.785751 -251.883214) (xy 44.727858 -251.898727)
			(xy 44.668436 -251.90655) (xy 44.6085 -251.90655) (xy 44.549078 -251.898727) (xy 44.491185 -251.883214)
			(xy 44.435812 -251.860278) (xy 44.383906 -251.830311) (xy 44.336356 -251.793824) (xy 44.293976 -251.751444)
			(xy 44.257489 -251.703894) (xy 44.227522 -251.651988) (xy 44.204586 -251.596615) (xy 44.189073 -251.538722)
			(xy 44.18125 -251.4793) (xy 39.104316 -251.4793) (xy 39.104316 -252.461814) (xy 41.197537 -252.461814)
			(xy 41.201423 -252.40745) (xy 41.213008 -252.354193) (xy 41.232054 -252.303126) (xy 41.258175 -252.255291)
			(xy 41.290838 -252.211659) (xy 41.329379 -252.173121) (xy 41.373012 -252.140461) (xy 41.420849 -252.114344)
			(xy 41.471917 -252.0953) (xy 41.525175 -252.08372) (xy 41.57954 -252.079837) (xy 41.633903 -252.083731)
			(xy 41.687159 -252.095323) (xy 41.738223 -252.114377) (xy 41.786055 -252.140504) (xy 41.808146 -252.156468)
			(xy 41.827158 -252.170064) (xy 41.869041 -252.190796) (xy 41.914009 -252.203522) (xy 41.960546 -252.207812)
			(xy 42.007083 -252.203522) (xy 42.052051 -252.190796) (xy 42.093934 -252.170064) (xy 42.112946 -252.156468)
			(xy 42.135056 -252.140544) (xy 42.182877 -252.114434) (xy 42.233927 -252.095395) (xy 42.287167 -252.083815)
			(xy 42.341513 -252.07993) (xy 42.395858 -252.083819) (xy 42.449097 -252.095402) (xy 42.500146 -252.114444)
			(xy 42.547965 -252.140558) (xy 42.591582 -252.173211) (xy 42.630107 -252.211739) (xy 42.662757 -252.255357)
			(xy 42.688867 -252.303178) (xy 42.707905 -252.354228) (xy 42.719485 -252.407468) (xy 42.72337 -252.461814)
			(xy 42.719481 -252.51616) (xy 42.707897 -252.569399) (xy 42.688855 -252.620448) (xy 42.662741 -252.668267)
			(xy 42.630088 -252.711883) (xy 42.59156 -252.750408) (xy 42.547941 -252.783058) (xy 42.50012 -252.809167)
			(xy 42.44907 -252.828206) (xy 42.39583 -252.839785) (xy 42.341484 -252.84367) (xy 42.287138 -252.839781)
			(xy 42.233899 -252.828197) (xy 42.18285 -252.809154) (xy 42.135031 -252.78304) (xy 42.112946 -252.767084)
			(xy 42.093934 -252.753488) (xy 42.052051 -252.732756) (xy 42.007083 -252.72003) (xy 41.960546 -252.71574)
			(xy 41.914009 -252.72003) (xy 41.869041 -252.732756) (xy 41.827158 -252.753488) (xy 41.808146 -252.767084)
			(xy 41.786079 -252.78308) (xy 41.738249 -252.809211) (xy 41.687187 -252.828269) (xy 41.633932 -252.839865)
			(xy 41.579569 -252.843763) (xy 41.525204 -252.839885) (xy 41.471945 -252.828308) (xy 41.420876 -252.809268)
			(xy 41.373036 -252.783154) (xy 41.3294 -252.750497) (xy 41.290857 -252.711962) (xy 41.25819 -252.668334)
			(xy 41.232066 -252.6205) (xy 41.213016 -252.569435) (xy 41.201427 -252.516178) (xy 41.197537 -252.461814)
			(xy 39.104316 -252.461814) (xy 39.104316 -253.435608) (xy 44.106828 -253.435608) (xy 44.106828 -253.375672)
			(xy 44.114651 -253.31625) (xy 44.130164 -253.258357) (xy 44.1531 -253.202984) (xy 44.183067 -253.151078)
			(xy 44.219554 -253.103528) (xy 44.261934 -253.061148) (xy 44.309484 -253.024661) (xy 44.36139 -252.994694)
			(xy 44.416763 -252.971758) (xy 44.474656 -252.956245) (xy 44.534078 -252.948422) (xy 44.594014 -252.948422)
			(xy 44.653436 -252.956245) (xy 44.711329 -252.971758) (xy 44.766702 -252.994694) (xy 44.818608 -253.024661)
			(xy 44.866158 -253.061148) (xy 44.908538 -253.103528) (xy 44.945025 -253.151078) (xy 44.974992 -253.202984)
			(xy 44.997928 -253.258357) (xy 45.013441 -253.31625) (xy 45.021264 -253.375672) (xy 45.021754 -253.40564)
			(xy 45.021264 -253.435608) (xy 45.013441 -253.49503) (xy 44.997928 -253.552923) (xy 44.974992 -253.608296)
			(xy 44.945025 -253.660202) (xy 44.908538 -253.707752) (xy 44.866158 -253.750132) (xy 44.818608 -253.786619)
			(xy 44.766702 -253.816586) (xy 44.711329 -253.839522) (xy 44.653436 -253.855035) (xy 44.594014 -253.862858)
			(xy 44.534078 -253.862858) (xy 44.474656 -253.855035) (xy 44.416763 -253.839522) (xy 44.36139 -253.816586)
			(xy 44.309484 -253.786619) (xy 44.261934 -253.750132) (xy 44.219554 -253.707752) (xy 44.183067 -253.660202)
			(xy 44.1531 -253.608296) (xy 44.130164 -253.552923) (xy 44.114651 -253.49503) (xy 44.106828 -253.435608)
			(xy 39.104316 -253.435608) (xy 39.104316 -254.326574) (xy 77.665721 -254.326574) (xy 77.669612 -254.272225)
			(xy 77.681199 -254.218982) (xy 77.700245 -254.167931) (xy 77.726362 -254.120111) (xy 77.75902 -254.076494)
			(xy 77.797553 -254.037969) (xy 77.841177 -254.00532) (xy 77.889003 -253.979212) (xy 77.940058 -253.960176)
			(xy 77.993302 -253.948601) (xy 78.047652 -253.944721) (xy 78.102001 -253.948616) (xy 78.155242 -253.960206)
			(xy 78.206292 -253.979255) (xy 78.254111 -254.005376) (xy 78.276196 -254.021336) (xy 78.295208 -254.034932)
			(xy 78.337091 -254.055664) (xy 78.382059 -254.06839) (xy 78.428596 -254.07268) (xy 78.475133 -254.06839)
			(xy 78.520101 -254.055664) (xy 78.561984 -254.034932) (xy 78.580996 -254.021336) (xy 78.603043 -254.005316)
			(xy 78.650871 -253.979189) (xy 78.701931 -253.960135) (xy 78.755183 -253.948542) (xy 78.809543 -253.944646)
			(xy 78.863904 -253.948526) (xy 78.91716 -253.960103) (xy 78.968225 -253.979142) (xy 79.016062 -254.005255)
			(xy 79.059694 -254.03791) (xy 79.098235 -254.076443) (xy 79.1309 -254.120069) (xy 79.157023 -254.167899)
			(xy 79.176073 -254.21896) (xy 79.187662 -254.272213) (xy 79.191554 -254.326574) (xy 80.470113 -254.326574)
			(xy 80.474004 -254.272223) (xy 80.485591 -254.218979) (xy 80.504638 -254.167926) (xy 80.530757 -254.120104)
			(xy 80.563416 -254.076485) (xy 80.601951 -254.03796) (xy 80.645576 -254.00531) (xy 80.693405 -253.979202)
			(xy 80.744462 -253.960167) (xy 80.797708 -253.948592) (xy 80.85206 -253.944713) (xy 80.906411 -253.948609)
			(xy 80.959654 -253.9602) (xy 81.010705 -253.979252) (xy 81.058525 -254.005375) (xy 81.08061 -254.021336)
			(xy 81.099622 -254.034932) (xy 81.141505 -254.055664) (xy 81.186473 -254.06839) (xy 81.23301 -254.07268)
			(xy 81.279547 -254.06839) (xy 81.324515 -254.055664) (xy 81.366398 -254.034932) (xy 81.38541 -254.021336)
			(xy 81.407457 -254.005318) (xy 81.455284 -253.979193) (xy 81.506343 -253.960141) (xy 81.559593 -253.948549)
			(xy 81.613951 -253.944654) (xy 81.66831 -253.948535) (xy 81.721564 -253.960113) (xy 81.772627 -253.979152)
			(xy 81.820461 -254.005265) (xy 81.864092 -254.037919) (xy 81.902631 -254.076451) (xy 81.935295 -254.120075)
			(xy 81.961417 -254.167904) (xy 81.980466 -254.218964) (xy 81.992054 -254.272215) (xy 81.995946 -254.326574)
			(xy 81.992062 -254.380932) (xy 81.980481 -254.434185) (xy 81.961439 -254.485248) (xy 81.935323 -254.53308)
			(xy 81.902666 -254.576709) (xy 81.864132 -254.615246) (xy 81.820506 -254.647907) (xy 81.772675 -254.674026)
			(xy 81.721614 -254.693072) (xy 81.668363 -254.704657) (xy 81.614004 -254.708546) (xy 81.559645 -254.704658)
			(xy 81.506393 -254.693074) (xy 81.455332 -254.674029) (xy 81.407501 -254.647911) (xy 81.38541 -254.631952)
			(xy 81.366398 -254.618356) (xy 81.324515 -254.597624) (xy 81.279547 -254.584898) (xy 81.23301 -254.580608)
			(xy 81.186473 -254.584898) (xy 81.141505 -254.597624) (xy 81.099622 -254.618356) (xy 81.08061 -254.631952)
			(xy 81.05848 -254.647853) (xy 81.010657 -254.67397) (xy 80.959603 -254.693014) (xy 80.906359 -254.704599)
			(xy 80.852007 -254.708487) (xy 80.797656 -254.704601) (xy 80.744411 -254.693019) (xy 80.693357 -254.673976)
			(xy 80.645532 -254.647861) (xy 80.601911 -254.615206) (xy 80.563382 -254.576675) (xy 80.530728 -254.533052)
			(xy 80.504616 -254.485226) (xy 80.485576 -254.434171) (xy 80.473996 -254.380925) (xy 80.470113 -254.326574)
			(xy 79.191554 -254.326574) (xy 79.18767 -254.380934) (xy 79.176088 -254.434189) (xy 79.157045 -254.485253)
			(xy 79.130929 -254.533087) (xy 79.09827 -254.576717) (xy 79.059734 -254.615255) (xy 79.016106 -254.647916)
			(xy 78.968273 -254.674036) (xy 78.91721 -254.693082) (xy 78.863957 -254.704667) (xy 78.809596 -254.708554)
			(xy 78.755236 -254.704665) (xy 78.701982 -254.69308) (xy 78.650919 -254.674033) (xy 78.603087 -254.647912)
			(xy 78.580996 -254.631952) (xy 78.561984 -254.618356) (xy 78.520101 -254.597624) (xy 78.475133 -254.584898)
			(xy 78.428596 -254.580608) (xy 78.382059 -254.584898) (xy 78.337091 -254.597624) (xy 78.295208 -254.618356)
			(xy 78.276196 -254.631952) (xy 78.254067 -254.647852) (xy 78.206244 -254.673967) (xy 78.155192 -254.693009)
			(xy 78.101949 -254.704592) (xy 78.047599 -254.708479) (xy 77.99325 -254.704592) (xy 77.940007 -254.693009)
			(xy 77.888955 -254.673966) (xy 77.841132 -254.647852) (xy 77.797513 -254.615197) (xy 77.758986 -254.576666)
			(xy 77.726334 -254.533045) (xy 77.700223 -254.485221) (xy 77.681184 -254.434167) (xy 77.669605 -254.380923)
			(xy 77.665721 -254.326574) (xy 39.104316 -254.326574) (xy 39.104316 -254.906812) (xy 41.12777 -254.906812)
			(xy 41.131656 -254.852455) (xy 41.143239 -254.799205) (xy 41.162282 -254.748145) (xy 41.188399 -254.700315)
			(xy 41.221056 -254.656689) (xy 41.259591 -254.618155) (xy 41.303217 -254.585498) (xy 41.351047 -254.559381)
			(xy 41.402107 -254.540338) (xy 41.455357 -254.528756) (xy 41.509714 -254.52487) (xy 41.56407 -254.52876)
			(xy 41.61732 -254.540346) (xy 41.668378 -254.559393) (xy 41.716206 -254.585512) (xy 41.738296 -254.601472)
			(xy 41.757308 -254.615068) (xy 41.799191 -254.6358) (xy 41.844159 -254.648526) (xy 41.890696 -254.652816)
			(xy 41.937233 -254.648526) (xy 41.982201 -254.6358) (xy 42.024084 -254.615068) (xy 42.043096 -254.601472)
			(xy 42.065203 -254.585539) (xy 42.113028 -254.55942) (xy 42.164083 -254.540374) (xy 42.217329 -254.528787)
			(xy 42.271682 -254.524897) (xy 42.326035 -254.528782) (xy 42.379282 -254.540363) (xy 42.430339 -254.559405)
			(xy 42.478166 -254.585519) (xy 42.52179 -254.618174) (xy 42.560322 -254.656705) (xy 42.592978 -254.700329)
			(xy 42.619093 -254.748155) (xy 42.638135 -254.799212) (xy 42.649717 -254.852459) (xy 42.653603 -254.906812)
			(xy 42.649714 -254.961165) (xy 42.638128 -255.014411) (xy 42.619083 -255.065467) (xy 42.592965 -255.113292)
			(xy 42.560306 -255.156913) (xy 42.521772 -255.195442) (xy 42.478146 -255.228094) (xy 42.430317 -255.254205)
			(xy 42.379259 -255.273244) (xy 42.326011 -255.284821) (xy 42.271658 -255.288703) (xy 42.217305 -255.284809)
			(xy 42.16406 -255.27322) (xy 42.113006 -255.25417) (xy 42.065183 -255.228048) (xy 42.043096 -255.212088)
			(xy 42.024084 -255.198492) (xy 41.982201 -255.17776) (xy 41.937233 -255.165034) (xy 41.890696 -255.160744)
			(xy 41.844159 -255.165034) (xy 41.799191 -255.17776) (xy 41.757308 -255.198492) (xy 41.738296 -255.212088)
			(xy 41.716227 -255.228075) (xy 41.6684 -255.254197) (xy 41.617343 -255.273247) (xy 41.564094 -255.284837)
			(xy 41.509738 -255.28873) (xy 41.455381 -255.284848) (xy 41.40213 -255.273269) (xy 41.351068 -255.254229)
			(xy 41.303237 -255.228115) (xy 41.259609 -255.195461) (xy 41.221072 -255.156929) (xy 41.188411 -255.113305)
			(xy 41.162292 -255.065477) (xy 41.143245 -255.014418) (xy 41.131659 -254.961169) (xy 41.12777 -254.906812)
			(xy 39.104316 -254.906812) (xy 39.104316 -256.247388) (xy 44.170074 -256.247388) (xy 44.170074 -256.187452)
			(xy 44.177897 -256.12803) (xy 44.19341 -256.070137) (xy 44.216346 -256.014764) (xy 44.246313 -255.962858)
			(xy 44.2828 -255.915308) (xy 44.32518 -255.872928) (xy 44.37273 -255.836441) (xy 44.424636 -255.806474)
			(xy 44.480009 -255.783538) (xy 44.537902 -255.768025) (xy 44.597324 -255.760202) (xy 44.65726 -255.760202)
			(xy 44.716682 -255.768025) (xy 44.774575 -255.783538) (xy 44.829948 -255.806474) (xy 44.881854 -255.836441)
			(xy 44.90607 -255.855023) (xy 77.615846 -255.855023) (xy 77.619731 -255.800662) (xy 77.631313 -255.747407)
			(xy 77.650357 -255.696343) (xy 77.676474 -255.648509) (xy 77.709134 -255.604878) (xy 77.74767 -255.566341)
			(xy 77.791299 -255.53368) (xy 77.839133 -255.507561) (xy 77.890197 -255.488516) (xy 77.943451 -255.476932)
			(xy 77.997812 -255.473046) (xy 78.052173 -255.476936) (xy 78.105427 -255.488523) (xy 78.156489 -255.507571)
			(xy 78.204321 -255.533693) (xy 78.226412 -255.549654) (xy 78.245424 -255.56325) (xy 78.287307 -255.583982)
			(xy 78.332275 -255.596708) (xy 78.378812 -255.600998) (xy 78.425349 -255.596708) (xy 78.470317 -255.583982)
			(xy 78.5122 -255.56325) (xy 78.531212 -255.549654) (xy 78.553336 -255.533746) (xy 78.601158 -255.507632)
			(xy 78.65221 -255.488591) (xy 78.705453 -255.477008) (xy 78.759802 -255.473121) (xy 78.814151 -255.477009)
			(xy 78.867393 -255.488591) (xy 78.918445 -255.507634) (xy 78.966267 -255.533748) (xy 79.009886 -255.566403)
			(xy 79.048413 -255.604932) (xy 79.081065 -255.648553) (xy 79.107176 -255.696377) (xy 79.126215 -255.74743)
			(xy 79.137795 -255.800674) (xy 79.141679 -255.855023) (xy 80.420237 -255.855023) (xy 80.424123 -255.80066)
			(xy 80.435705 -255.747403) (xy 80.45475 -255.696337) (xy 80.480869 -255.648502) (xy 80.51353 -255.60487)
			(xy 80.552068 -255.566332) (xy 80.595699 -255.53367) (xy 80.643535 -255.507551) (xy 80.6946 -255.488506)
			(xy 80.747857 -255.476923) (xy 80.80222 -255.473037) (xy 80.856583 -255.476929) (xy 80.909838 -255.488517)
			(xy 80.960902 -255.507568) (xy 81.008734 -255.533692) (xy 81.030826 -255.549654) (xy 81.049838 -255.56325)
			(xy 81.091721 -255.583982) (xy 81.136689 -255.596708) (xy 81.183226 -255.600998) (xy 81.229763 -255.596708)
			(xy 81.274731 -255.583982) (xy 81.316614 -255.56325) (xy 81.335626 -255.549654) (xy 81.357749 -255.533748)
			(xy 81.405571 -255.507636) (xy 81.456621 -255.488596) (xy 81.509862 -255.477015) (xy 81.56421 -255.473129)
			(xy 81.618556 -255.477018) (xy 81.671797 -255.488601) (xy 81.722847 -255.507644) (xy 81.770667 -255.533758)
			(xy 81.814284 -255.566412) (xy 81.852809 -255.604941) (xy 81.88546 -255.64856) (xy 81.91157 -255.696383)
			(xy 81.930608 -255.747434) (xy 81.942187 -255.800676) (xy 81.946071 -255.855023) (xy 81.94218 -255.90937)
			(xy 81.930595 -255.96261) (xy 81.911551 -256.013659) (xy 81.885435 -256.061478) (xy 81.85278 -256.105094)
			(xy 81.814249 -256.143618) (xy 81.770629 -256.176267) (xy 81.722805 -256.202375) (xy 81.671753 -256.221412)
			(xy 81.618511 -256.232989) (xy 81.564164 -256.236871) (xy 81.509817 -256.232978) (xy 81.456578 -256.221391)
			(xy 81.405529 -256.202345) (xy 81.357711 -256.176228) (xy 81.335626 -256.16027) (xy 81.316614 -256.146674)
			(xy 81.274731 -256.125942) (xy 81.229763 -256.113216) (xy 81.183226 -256.108926) (xy 81.136689 -256.113216)
			(xy 81.091721 -256.125942) (xy 81.049838 -256.146674) (xy 81.030826 -256.16027) (xy 81.008773 -256.176283)
			(xy 80.960943 -256.202413) (xy 80.909882 -256.22147) (xy 80.856628 -256.233065) (xy 80.802266 -256.236963)
			(xy 80.747902 -256.233083) (xy 80.694644 -256.221507) (xy 80.643576 -256.202468) (xy 80.595738 -256.176354)
			(xy 80.552103 -256.143698) (xy 80.51356 -256.105164) (xy 80.480893 -256.061537) (xy 80.454769 -256.013704)
			(xy 80.435718 -255.962641) (xy 80.424129 -255.909385) (xy 80.420237 -255.855023) (xy 79.141679 -255.855023)
			(xy 79.137788 -255.909372) (xy 79.126203 -255.962613) (xy 79.107157 -256.013664) (xy 79.08104 -256.061485)
			(xy 79.048384 -256.105102) (xy 79.009852 -256.143627) (xy 78.966229 -256.176277) (xy 78.918403 -256.202385)
			(xy 78.867349 -256.221421) (xy 78.814105 -256.232998) (xy 78.759756 -256.236879) (xy 78.705407 -256.232985)
			(xy 78.652166 -256.221397) (xy 78.601116 -256.202349) (xy 78.553297 -256.176229) (xy 78.531212 -256.16027)
			(xy 78.5122 -256.146674) (xy 78.470317 -256.125942) (xy 78.425349 -256.113216) (xy 78.378812 -256.108926)
			(xy 78.332275 -256.113216) (xy 78.287307 -256.125942) (xy 78.245424 -256.146674) (xy 78.226412 -256.16027)
			(xy 78.204359 -256.176282) (xy 78.156531 -256.20241) (xy 78.10547 -256.221464) (xy 78.052218 -256.233058)
			(xy 77.997858 -256.236954) (xy 77.943496 -256.233074) (xy 77.89024 -256.221497) (xy 77.839174 -256.202458)
			(xy 77.791338 -256.176345) (xy 77.747705 -256.143689) (xy 77.709164 -256.105156) (xy 77.676499 -256.06153)
			(xy 77.650376 -256.013699) (xy 77.631326 -255.962637) (xy 77.619737 -255.909383) (xy 77.615846 -255.855023)
			(xy 44.90607 -255.855023) (xy 44.929404 -255.872928) (xy 44.971784 -255.915308) (xy 45.008271 -255.962858)
			(xy 45.038238 -256.014764) (xy 45.061174 -256.070137) (xy 45.076687 -256.12803) (xy 45.08451 -256.187452)
			(xy 45.085 -256.21742) (xy 45.08451 -256.247388) (xy 45.076687 -256.30681) (xy 45.061174 -256.364703)
			(xy 45.038238 -256.420076) (xy 45.008271 -256.471982) (xy 44.971784 -256.519532) (xy 44.929404 -256.561912)
			(xy 44.881854 -256.598399) (xy 44.829948 -256.628366) (xy 44.774575 -256.651302) (xy 44.716682 -256.666815)
			(xy 44.65726 -256.674638) (xy 44.597324 -256.674638) (xy 44.537902 -256.666815) (xy 44.480009 -256.651302)
			(xy 44.424636 -256.628366) (xy 44.37273 -256.598399) (xy 44.32518 -256.561912) (xy 44.2828 -256.519532)
			(xy 44.246313 -256.471982) (xy 44.216346 -256.420076) (xy 44.19341 -256.364703) (xy 44.177897 -256.30681)
			(xy 44.170074 -256.247388) (xy 39.104316 -256.247388) (xy 39.104316 -256.869705) (xy 41.127779 -256.869705)
			(xy 41.131667 -256.815349) (xy 41.14325 -256.762101) (xy 41.162294 -256.711042) (xy 41.18841 -256.663214)
			(xy 41.221068 -256.61959) (xy 41.259602 -256.581058) (xy 41.303228 -256.548402) (xy 41.351057 -256.522287)
			(xy 41.402116 -256.503245) (xy 41.455365 -256.491664) (xy 41.509721 -256.487779) (xy 41.564076 -256.49167)
			(xy 41.617324 -256.503257) (xy 41.668381 -256.522304) (xy 41.716207 -256.548424) (xy 41.738296 -256.564384)
			(xy 41.757308 -256.57798) (xy 41.799191 -256.598712) (xy 41.844159 -256.611438) (xy 41.890696 -256.615728)
			(xy 41.937233 -256.611438) (xy 41.982201 -256.598712) (xy 42.024084 -256.57798) (xy 42.043096 -256.564384)
			(xy 42.065192 -256.548435) (xy 42.113017 -256.522314) (xy 42.164073 -256.503266) (xy 42.21732 -256.491679)
			(xy 42.271674 -256.487787) (xy 42.326029 -256.491672) (xy 42.379278 -256.503252) (xy 42.430337 -256.522293)
			(xy 42.478165 -256.548407) (xy 42.521791 -256.581062) (xy 42.560324 -256.619594) (xy 42.592982 -256.663217)
			(xy 42.619098 -256.711045) (xy 42.638142 -256.762102) (xy 42.649725 -256.81535) (xy 42.653613 -256.869705)
			(xy 42.649724 -256.924059) (xy 42.638139 -256.977307) (xy 42.619094 -257.028364) (xy 42.592977 -257.076191)
			(xy 42.560318 -257.119814) (xy 42.521783 -257.158344) (xy 42.478157 -257.190998) (xy 42.430328 -257.217111)
			(xy 42.379269 -257.236151) (xy 42.32602 -257.24773) (xy 42.271665 -257.251613) (xy 42.217311 -257.24772)
			(xy 42.164064 -257.236131) (xy 42.113008 -257.217082) (xy 42.065184 -257.19096) (xy 42.043096 -257.175)
			(xy 42.024084 -257.161404) (xy 41.982201 -257.140672) (xy 41.937233 -257.127946) (xy 41.890696 -257.123656)
			(xy 41.844159 -257.127946) (xy 41.799191 -257.140672) (xy 41.757308 -257.161404) (xy 41.738296 -257.175)
			(xy 41.716215 -257.19097) (xy 41.66839 -257.217092) (xy 41.617333 -257.23614) (xy 41.564086 -257.247728)
			(xy 41.509731 -257.251621) (xy 41.455375 -257.247737) (xy 41.402125 -257.236157) (xy 41.351066 -257.217117)
			(xy 41.303236 -257.191003) (xy 41.259609 -257.158349) (xy 41.221075 -257.119817) (xy 41.188416 -257.076194)
			(xy 41.162298 -257.028366) (xy 41.143253 -256.977309) (xy 41.131668 -256.92406) (xy 41.127779 -256.869705)
			(xy 39.104316 -256.869705) (xy 39.104316 -257.579914) (xy 77.632351 -257.579914) (xy 77.636237 -257.525554)
			(xy 77.647821 -257.472299) (xy 77.666866 -257.421236) (xy 77.692984 -257.373403) (xy 77.725645 -257.329774)
			(xy 77.764182 -257.291237) (xy 77.807812 -257.258578) (xy 77.855646 -257.232461) (xy 77.906711 -257.213417)
			(xy 77.959965 -257.201836) (xy 78.014326 -257.197951) (xy 78.068687 -257.201843) (xy 78.12194 -257.213432)
			(xy 78.173001 -257.232483) (xy 78.220832 -257.258606) (xy 78.242922 -257.274568) (xy 78.261934 -257.288164)
			(xy 78.303817 -257.308896) (xy 78.348785 -257.321622) (xy 78.395322 -257.325912) (xy 78.441859 -257.321622)
			(xy 78.486827 -257.308896) (xy 78.52871 -257.288164) (xy 78.547722 -257.274568) (xy 78.569832 -257.258642)
			(xy 78.617655 -257.232528) (xy 78.668707 -257.213486) (xy 78.72195 -257.201903) (xy 78.776299 -257.198016)
			(xy 78.830648 -257.201903) (xy 78.883891 -257.213485) (xy 78.934943 -257.232527) (xy 78.982766 -257.258641)
			(xy 79.026385 -257.291295) (xy 79.064914 -257.329825) (xy 79.097566 -257.373445) (xy 79.123678 -257.421269)
			(xy 79.142718 -257.472322) (xy 79.154299 -257.525565) (xy 79.158184 -257.579914) (xy 80.436743 -257.579914)
			(xy 80.440629 -257.525552) (xy 80.452213 -257.472296) (xy 80.471259 -257.42123) (xy 80.497379 -257.373396)
			(xy 80.530041 -257.329765) (xy 80.56858 -257.291228) (xy 80.612212 -257.258568) (xy 80.660048 -257.232451)
			(xy 80.711114 -257.213408) (xy 80.764371 -257.201826) (xy 80.818734 -257.197943) (xy 80.873096 -257.201836)
			(xy 80.926351 -257.213427) (xy 80.977414 -257.232479) (xy 81.025245 -257.258605) (xy 81.047336 -257.274568)
			(xy 81.066348 -257.288164) (xy 81.108231 -257.308896) (xy 81.153199 -257.321622) (xy 81.199736 -257.325912)
			(xy 81.246273 -257.321622) (xy 81.291241 -257.308896) (xy 81.333124 -257.288164) (xy 81.352136 -257.274568)
			(xy 81.374246 -257.258643) (xy 81.422067 -257.232532) (xy 81.473118 -257.213491) (xy 81.52636 -257.20191)
			(xy 81.580707 -257.198024) (xy 81.635054 -257.201912) (xy 81.688295 -257.213495) (xy 81.739345 -257.232537)
			(xy 81.787166 -257.258651) (xy 81.830783 -257.291304) (xy 81.86931 -257.329833) (xy 81.901961 -257.373452)
			(xy 81.928072 -257.421274) (xy 81.947111 -257.472326) (xy 81.958691 -257.525567) (xy 81.962576 -257.579914)
			(xy 81.958687 -257.634262) (xy 81.947103 -257.687502) (xy 81.92806 -257.738552) (xy 81.901945 -257.786372)
			(xy 81.869291 -257.829989) (xy 81.830761 -257.868515) (xy 81.787141 -257.901165) (xy 81.739319 -257.927275)
			(xy 81.688267 -257.946313) (xy 81.635026 -257.957892) (xy 81.580678 -257.961776) (xy 81.526331 -257.957886)
			(xy 81.473091 -257.946301) (xy 81.422041 -257.927256) (xy 81.374222 -257.901141) (xy 81.352136 -257.885184)
			(xy 81.333124 -257.871588) (xy 81.291241 -257.850856) (xy 81.246273 -257.83813) (xy 81.199736 -257.83384)
			(xy 81.153199 -257.83813) (xy 81.108231 -257.850856) (xy 81.066348 -257.871588) (xy 81.047336 -257.885184)
			(xy 81.025269 -257.901179) (xy 80.97744 -257.927309) (xy 80.926379 -257.946365) (xy 80.873125 -257.95796)
			(xy 80.818763 -257.961857) (xy 80.7644 -257.957978) (xy 80.711142 -257.946401) (xy 80.660074 -257.927361)
			(xy 80.612236 -257.901247) (xy 80.568602 -257.868591) (xy 80.53006 -257.830056) (xy 80.497394 -257.786429)
			(xy 80.471271 -257.738596) (xy 80.452221 -257.687532) (xy 80.440633 -257.634277) (xy 80.436743 -257.579914)
			(xy 79.158184 -257.579914) (xy 79.154295 -257.634263) (xy 79.14271 -257.687506) (xy 79.123666 -257.738557)
			(xy 79.097551 -257.786379) (xy 79.064895 -257.829997) (xy 79.026364 -257.868524) (xy 78.982742 -257.901174)
			(xy 78.934917 -257.927285) (xy 78.883863 -257.946323) (xy 78.83062 -257.957901) (xy 78.77627 -257.961784)
			(xy 78.721921 -257.957893) (xy 78.668679 -257.946306) (xy 78.617629 -257.92726) (xy 78.569808 -257.901142)
			(xy 78.547722 -257.885184) (xy 78.52871 -257.871588) (xy 78.486827 -257.850856) (xy 78.441859 -257.83813)
			(xy 78.395322 -257.83384) (xy 78.348785 -257.83813) (xy 78.303817 -257.850856) (xy 78.261934 -257.871588)
			(xy 78.242922 -257.885184) (xy 78.220856 -257.901178) (xy 78.173027 -257.927306) (xy 78.121967 -257.94636)
			(xy 78.068715 -257.957953) (xy 78.014355 -257.961849) (xy 77.959994 -257.957969) (xy 77.906738 -257.946391)
			(xy 77.855673 -257.927351) (xy 77.807837 -257.901238) (xy 77.764204 -257.868582) (xy 77.725664 -257.830048)
			(xy 77.693 -257.786422) (xy 77.666878 -257.73859) (xy 77.647829 -257.687528) (xy 77.636241 -257.634275)
			(xy 77.632351 -257.579914) (xy 39.104316 -257.579914) (xy 39.104316 -259.388864) (xy 39.104813 -259.411901)
			(xy 39.113113 -259.457222) (xy 39.129447 -259.500304) (xy 39.15328 -259.539736) (xy 39.183832 -259.574225)
			(xy 39.2201 -259.602641) (xy 39.260897 -259.624053) (xy 39.304885 -259.63776) (xy 39.350624 -259.643312)
			(xy 39.396614 -259.640528) (xy 39.441349 -259.629498) (xy 39.483363 -259.610584) (xy 39.521278 -259.584406)
			(xy 39.537894 -259.568442) (xy 39.899844 -259.206492) (xy 40.876982 -259.206492) (xy 40.899997 -259.206006)
			(xy 40.945279 -259.197747) (xy 40.988337 -259.181477) (xy 41.027765 -259.157728) (xy 41.062279 -259.127273)
			(xy 41.090751 -259.091106) (xy 41.112253 -259.050408) (xy 41.126083 -259.006506) (xy 41.129458 -258.983734)
			(xy 41.131996 -258.956949) (xy 41.143648 -258.904422) (xy 41.162564 -258.854054) (xy 41.18837 -258.806844)
			(xy 41.220553 -258.763728) (xy 41.258475 -258.725561) (xy 41.301384 -258.693102) (xy 41.348428 -258.666993)
			(xy 41.398673 -258.647754) (xy 41.451123 -258.635765) (xy 41.504738 -258.631265) (xy 41.558453 -258.634343)
			(xy 41.611202 -258.644937) (xy 41.636696 -258.653534) (xy 41.651598 -258.658291) (xy 41.682737 -258.661185)
			(xy 41.713646 -258.656427) (xy 41.742472 -258.644301) (xy 41.767489 -258.625534) (xy 41.777666 -258.613656)
			(xy 41.80084 -258.585824) (xy 41.852497 -258.53506) (xy 41.909591 -258.490498) (xy 41.971381 -258.452717)
			(xy 42.037067 -258.422206) (xy 42.105795 -258.399362) (xy 42.176676 -258.38448) (xy 42.248788 -258.377753)
			(xy 42.321198 -258.379269) (xy 42.392966 -258.389009) (xy 42.463161 -258.406845) (xy 42.530873 -258.432547)
			(xy 42.595224 -258.465781) (xy 42.655378 -258.506116) (xy 42.710557 -258.553029) (xy 42.760043 -258.605911)
			(xy 42.803196 -258.664077) (xy 42.839456 -258.726773) (xy 42.868352 -258.793184) (xy 42.88951 -258.862451)
			(xy 42.902655 -258.933674) (xy 42.90568 -258.969764) (xy 42.907839 -258.993555) (xy 42.919917 -259.039769)
			(xy 42.940418 -259.082912) (xy 42.96862 -259.121463) (xy 43.00353 -259.154065) (xy 43.043917 -259.179569)
			(xy 43.088358 -259.197077) (xy 43.135289 -259.205971) (xy 43.159172 -259.206492) (xy 43.446446 -259.206492)
			(xy 43.617896 -259.035296) (xy 43.656474 -258.997416) (xy 43.738249 -258.926674) (xy 43.824907 -258.862005)
			(xy 43.915998 -258.803744) (xy 44.011047 -258.752195) (xy 44.06011 -258.72948) (xy 44.081027 -258.719477)
			(xy 44.119124 -258.693062) (xy 44.151801 -258.660177) (xy 44.177972 -258.621911) (xy 44.196772 -258.579535)
			(xy 44.207577 -258.534452) (xy 44.210028 -258.488158) (xy 44.204044 -258.442186) (xy 44.189824 -258.398062)
			(xy 44.179236 -258.377436) (xy 44.163715 -258.351043) (xy 44.139092 -258.294983) (xy 44.122165 -258.23614)
			(xy 44.113236 -258.175565) (xy 44.112466 -258.114341) (xy 44.119867 -258.053561) (xy 44.135307 -257.99431)
			(xy 44.158511 -257.937648) (xy 44.189064 -257.884587) (xy 44.22642 -257.836073) (xy 44.269912 -257.792975)
			(xy 44.318763 -257.756062) (xy 44.372101 -257.725993) (xy 44.428972 -257.703306) (xy 44.48836 -257.688406)
			(xy 44.549206 -257.681558) (xy 44.61042 -257.682886) (xy 44.640754 -257.687064) (xy 44.669391 -257.691982)
			(xy 44.725211 -257.708121) (xy 44.77854 -257.731196) (xy 44.828519 -257.760835) (xy 44.874344 -257.796562)
			(xy 44.915279 -257.837801) (xy 44.933362 -257.860546) (xy 44.951656 -257.885207) (xy 44.982182 -257.938486)
			(xy 45.005312 -257.995366) (xy 45.020632 -258.054828) (xy 45.027866 -258.115804) (xy 45.026886 -258.1772)
			(xy 45.017708 -258.237913) (xy 45.000498 -258.296856) (xy 44.98848 -258.325112) (xy 44.979366 -258.346929)
			(xy 44.968502 -258.39294) (xy 44.96633 -258.440167) (xy 44.972926 -258.486981) (xy 44.988061 -258.531769)
			(xy 45.011215 -258.572988) (xy 45.04159 -258.609216) (xy 45.078137 -258.639205) (xy 45.119599 -258.661922)
			(xy 45.141896 -258.66979) (xy 45.193676 -258.687168) (xy 45.294805 -258.728453) (xy 45.39266 -258.776991)
			(xy 45.486723 -258.832522) (xy 45.576494 -258.894753) (xy 45.661498 -258.963353) (xy 45.741282 -259.037959)
			(xy 45.815424 -259.118174) (xy 45.883531 -259.203573) (xy 45.913205 -259.246913) (xy 77.64538 -259.246913)
			(xy 77.649266 -259.192559) (xy 77.660848 -259.139311) (xy 77.67989 -259.088253) (xy 77.706004 -259.040425)
			(xy 77.73866 -258.996801) (xy 77.777192 -258.958268) (xy 77.820815 -258.925611) (xy 77.868642 -258.899495)
			(xy 77.919699 -258.880451) (xy 77.972947 -258.868868) (xy 78.027301 -258.86498) (xy 78.081655 -258.868868)
			(xy 78.134903 -258.880452) (xy 78.18596 -258.899496) (xy 78.233787 -258.925612) (xy 78.255876 -258.94157)
			(xy 78.274888 -258.955166) (xy 78.316771 -258.975898) (xy 78.361739 -258.988624) (xy 78.408276 -258.992914)
			(xy 78.454813 -258.988624) (xy 78.499781 -258.975898) (xy 78.541664 -258.955166) (xy 78.560676 -258.94157)
			(xy 78.582785 -258.925638) (xy 78.630611 -258.899516) (xy 78.681668 -258.880467) (xy 78.734916 -258.868879)
			(xy 78.789272 -258.864987) (xy 78.843627 -258.868871) (xy 78.896877 -258.880451) (xy 78.947937 -258.899492)
			(xy 78.995767 -258.925607) (xy 79.039393 -258.958263) (xy 79.077927 -258.996796) (xy 79.110585 -259.04042)
			(xy 79.136701 -259.088249) (xy 79.155745 -259.139308) (xy 79.167327 -259.192557) (xy 79.171213 -259.246913)
			(xy 80.449772 -259.246913) (xy 80.453658 -259.192557) (xy 80.46524 -259.139307) (xy 80.484283 -259.088248)
			(xy 80.510399 -259.040418) (xy 80.543056 -258.996793) (xy 80.581589 -258.958259) (xy 80.625215 -258.925601)
			(xy 80.673044 -258.899485) (xy 80.724103 -258.880441) (xy 80.777353 -258.868858) (xy 80.831709 -258.864972)
			(xy 80.886065 -258.868861) (xy 80.939314 -258.880446) (xy 80.990373 -258.899492) (xy 81.0382 -258.925611)
			(xy 81.06029 -258.94157) (xy 81.079302 -258.955166) (xy 81.121185 -258.975898) (xy 81.166153 -258.988624)
			(xy 81.21269 -258.992914) (xy 81.259227 -258.988624) (xy 81.304195 -258.975898) (xy 81.346078 -258.955166)
			(xy 81.36509 -258.94157) (xy 81.387199 -258.925639) (xy 81.435024 -258.899519) (xy 81.486079 -258.880472)
			(xy 81.539326 -258.868886) (xy 81.593679 -258.864995) (xy 81.648033 -258.86888) (xy 81.701281 -258.880461)
			(xy 81.752339 -258.899502) (xy 81.800166 -258.925617) (xy 81.843791 -258.958272) (xy 81.882323 -258.996804)
			(xy 81.914979 -259.040427) (xy 81.941095 -259.088255) (xy 81.960137 -259.139312) (xy 81.971719 -259.192559)
			(xy 81.975605 -259.246913) (xy 81.971715 -259.301267) (xy 81.96013 -259.354514) (xy 81.941084 -259.405569)
			(xy 81.914965 -259.453395) (xy 81.882306 -259.497016) (xy 81.843771 -259.535545) (xy 81.800144 -259.568198)
			(xy 81.752315 -259.594309) (xy 81.701256 -259.613347) (xy 81.648007 -259.624924) (xy 81.593653 -259.628805)
			(xy 81.5393 -259.624911) (xy 81.486054 -259.61332) (xy 81.435 -259.59427) (xy 81.387177 -259.568147)
			(xy 81.36509 -259.552186) (xy 81.346078 -259.53859) (xy 81.304195 -259.517858) (xy 81.259227 -259.505132)
			(xy 81.21269 -259.500842) (xy 81.166153 -259.505132) (xy 81.121185 -259.517858) (xy 81.079302 -259.53859)
			(xy 81.06029 -259.552186) (xy 81.038223 -259.568175) (xy 80.990397 -259.594297) (xy 80.93934 -259.613346)
			(xy 80.886091 -259.624935) (xy 80.831736 -259.628828) (xy 80.777379 -259.624945) (xy 80.724129 -259.613366)
			(xy 80.673068 -259.594326) (xy 80.625237 -259.568213) (xy 80.581609 -259.535559) (xy 80.543073 -259.497027)
			(xy 80.510413 -259.453404) (xy 80.484294 -259.405576) (xy 80.465247 -259.354518) (xy 80.453662 -259.301269)
			(xy 80.449772 -259.246913) (xy 79.171213 -259.246913) (xy 79.167324 -259.301269) (xy 79.155737 -259.354517)
			(xy 79.13669 -259.405575) (xy 79.110571 -259.453402) (xy 79.07791 -259.497024) (xy 79.039373 -259.535554)
			(xy 78.995744 -259.568207) (xy 78.947913 -259.594319) (xy 78.896852 -259.613356) (xy 78.843601 -259.624933)
			(xy 78.789245 -259.628813) (xy 78.73489 -259.624918) (xy 78.681643 -259.613326) (xy 78.630587 -259.594273)
			(xy 78.582763 -259.568148) (xy 78.560676 -259.552186) (xy 78.541664 -259.53859) (xy 78.499781 -259.517858)
			(xy 78.454813 -259.505132) (xy 78.408276 -259.500842) (xy 78.361739 -259.505132) (xy 78.316771 -259.517858)
			(xy 78.274888 -259.53859) (xy 78.255876 -259.552186) (xy 78.233809 -259.568174) (xy 78.185984 -259.594293)
			(xy 78.134928 -259.613341) (xy 78.081681 -259.624928) (xy 78.027328 -259.62882) (xy 77.972973 -259.624936)
			(xy 77.919725 -259.613356) (xy 77.868666 -259.594316) (xy 77.820837 -259.568203) (xy 77.777212 -259.535549)
			(xy 77.738677 -259.497019) (xy 77.706019 -259.453397) (xy 77.679901 -259.405571) (xy 77.660855 -259.354514)
			(xy 77.64927 -259.301267) (xy 77.64538 -259.246913) (xy 45.913205 -259.246913) (xy 45.945241 -259.293703)
			(xy 46.000227 -259.388086) (xy 46.048197 -259.486221) (xy 46.088896 -259.587587) (xy 46.122109 -259.691647)
			(xy 46.14766 -259.797849) (xy 46.165412 -259.905628) (xy 46.175272 -260.014414) (xy 46.177187 -260.123629)
			(xy 46.171148 -260.232693) (xy 46.157186 -260.341029) (xy 46.135375 -260.448061) (xy 46.105831 -260.553221)
			(xy 46.068711 -260.655952) (xy 46.024212 -260.755709) (xy 45.972569 -260.851962) (xy 45.955661 -260.878616)
			(xy 77.628883 -260.878616) (xy 77.632768 -260.824262) (xy 77.644349 -260.771015) (xy 77.663391 -260.719958)
			(xy 77.689504 -260.672131) (xy 77.722159 -260.628506) (xy 77.760689 -260.589974) (xy 77.804312 -260.557316)
			(xy 77.852138 -260.5312) (xy 77.903193 -260.512156) (xy 77.95644 -260.500572) (xy 78.010793 -260.496683)
			(xy 78.065146 -260.50057) (xy 78.118393 -260.512152) (xy 78.16945 -260.531194) (xy 78.217277 -260.557309)
			(xy 78.239366 -260.573266) (xy 78.258378 -260.586862) (xy 78.300261 -260.607594) (xy 78.345229 -260.62032)
			(xy 78.391766 -260.62461) (xy 78.438303 -260.62032) (xy 78.483271 -260.607594) (xy 78.525154 -260.586862)
			(xy 78.544166 -260.573266) (xy 78.566279 -260.557338) (xy 78.614106 -260.531215) (xy 78.665163 -260.512166)
			(xy 78.718412 -260.500576) (xy 78.772768 -260.496684) (xy 78.827125 -260.500567) (xy 78.880376 -260.512148)
			(xy 78.931437 -260.531189) (xy 78.979267 -260.557304) (xy 79.022894 -260.58996) (xy 79.061429 -260.628494)
			(xy 79.094087 -260.672119) (xy 79.120204 -260.719949) (xy 79.139248 -260.771009) (xy 79.15083 -260.824259)
			(xy 79.154716 -260.878616) (xy 80.433275 -260.878616) (xy 80.43716 -260.82426) (xy 80.448742 -260.771011)
			(xy 80.467784 -260.719953) (xy 80.493899 -260.672124) (xy 80.526555 -260.628498) (xy 80.565087 -260.589964)
			(xy 80.608711 -260.557307) (xy 80.656539 -260.53119) (xy 80.707597 -260.512146) (xy 80.760846 -260.500562)
			(xy 80.815201 -260.496675) (xy 80.869556 -260.500562) (xy 80.922805 -260.512146) (xy 80.973863 -260.531191)
			(xy 81.02169 -260.557308) (xy 81.04378 -260.573266) (xy 81.062792 -260.586862) (xy 81.104675 -260.607594)
			(xy 81.149643 -260.62032) (xy 81.19618 -260.62461) (xy 81.242717 -260.62032) (xy 81.287685 -260.607594)
			(xy 81.329568 -260.586862) (xy 81.34858 -260.573266) (xy 81.370693 -260.557339) (xy 81.418518 -260.531219)
			(xy 81.469574 -260.512171) (xy 81.522822 -260.500583) (xy 81.577176 -260.496692) (xy 81.631531 -260.500577)
			(xy 81.68478 -260.512158) (xy 81.735838 -260.531199) (xy 81.783667 -260.557314) (xy 81.827292 -260.58997)
			(xy 81.865825 -260.628502) (xy 81.898482 -260.672126) (xy 81.924597 -260.719954) (xy 81.94364 -260.771012)
			(xy 81.955222 -260.824261) (xy 81.959108 -260.878616) (xy 81.955218 -260.93297) (xy 81.943631 -260.986218)
			(xy 81.924585 -261.037274) (xy 81.898465 -261.0851) (xy 81.865805 -261.128722) (xy 81.827268 -261.167251)
			(xy 81.783641 -261.199903) (xy 81.73581 -261.226014) (xy 81.68475 -261.245051) (xy 81.6315 -261.256628)
			(xy 81.577145 -261.260508) (xy 81.522791 -261.256612) (xy 81.469544 -261.24502) (xy 81.41849 -261.225968)
			(xy 81.370667 -261.199844) (xy 81.34858 -261.183882) (xy 81.329568 -261.170286) (xy 81.287685 -261.149554)
			(xy 81.242717 -261.136828) (xy 81.19618 -261.132538) (xy 81.149643 -261.136828) (xy 81.104675 -261.149554)
			(xy 81.062792 -261.170286) (xy 81.04378 -261.183882) (xy 81.021717 -261.199875) (xy 80.973891 -261.225996)
			(xy 80.922835 -261.245045) (xy 80.869587 -261.256633) (xy 80.815232 -261.260525) (xy 80.760877 -261.256642)
			(xy 80.707627 -261.245063) (xy 80.656568 -261.226023) (xy 80.608738 -261.19991) (xy 80.565111 -261.167256)
			(xy 80.526575 -261.128725) (xy 80.493916 -261.085103) (xy 80.467797 -261.037276) (xy 80.448751 -260.986219)
			(xy 80.437165 -260.932971) (xy 80.433275 -260.878616) (xy 79.154716 -260.878616) (xy 79.150826 -260.932972)
			(xy 79.139239 -260.986221) (xy 79.120191 -261.03728) (xy 79.094071 -261.085107) (xy 79.061409 -261.12873)
			(xy 79.022871 -261.16726) (xy 78.979241 -261.199913) (xy 78.931408 -261.226024) (xy 78.880346 -261.245061)
			(xy 78.827094 -261.256637) (xy 78.772737 -261.260516) (xy 78.718381 -261.256619) (xy 78.665133 -261.245026)
			(xy 78.614077 -261.225972) (xy 78.566253 -261.199845) (xy 78.544166 -261.183882) (xy 78.525154 -261.170286)
			(xy 78.483271 -261.149554) (xy 78.438303 -261.136828) (xy 78.391766 -261.132538) (xy 78.345229 -261.136828)
			(xy 78.300261 -261.149554) (xy 78.258378 -261.170286) (xy 78.239366 -261.183882) (xy 78.217303 -261.199874)
			(xy 78.169478 -261.225993) (xy 78.118423 -261.245039) (xy 78.065177 -261.256626) (xy 78.010824 -261.260517)
			(xy 77.956471 -261.256633) (xy 77.903223 -261.245053) (xy 77.852166 -261.226013) (xy 77.804338 -261.1999)
			(xy 77.760713 -261.167247) (xy 77.722179 -261.128717) (xy 77.689521 -261.085096) (xy 77.663404 -261.03727)
			(xy 77.644358 -260.986215) (xy 77.632773 -260.932969) (xy 77.628883 -260.878616) (xy 45.955661 -260.878616)
			(xy 45.914058 -260.9442) (xy 45.848987 -261.031935) (xy 45.813726 -261.073646) (xy 45.803302 -261.086603)
			(xy 45.788874 -261.116552) (xy 45.782654 -261.149208) (xy 45.785063 -261.182363) (xy 45.795937 -261.213777)
			(xy 45.804836 -261.227824) (xy 45.835438 -261.273903) (xy 45.890564 -261.369815) (xy 45.924363 -261.440168)
			(xy 52.335176 -261.440168) (xy 53.987192 -261.440168) (xy 53.987192 -262.564417) (xy 77.595733 -262.564417)
			(xy 77.59962 -262.510052) (xy 77.611204 -262.456794) (xy 77.63025 -262.405727) (xy 77.656371 -262.357891)
			(xy 77.689034 -262.314259) (xy 77.727575 -262.275721) (xy 77.771208 -262.24306) (xy 77.819046 -262.216942)
			(xy 77.870114 -262.197898) (xy 77.923373 -262.186317) (xy 77.977737 -262.182433) (xy 78.032101 -262.186327)
			(xy 78.085358 -262.197919) (xy 78.136422 -262.216973) (xy 78.184255 -262.2431) (xy 78.206346 -262.259064)
			(xy 78.225358 -262.27266) (xy 78.267241 -262.293392) (xy 78.312209 -262.306118) (xy 78.358746 -262.310408)
			(xy 78.405283 -262.306118) (xy 78.450251 -262.293392) (xy 78.492134 -262.27266) (xy 78.511146 -262.259064)
			(xy 78.533259 -262.243146) (xy 78.58108 -262.217036) (xy 78.63213 -262.197998) (xy 78.685369 -262.186418)
			(xy 78.739715 -262.182533) (xy 78.79406 -262.186422) (xy 78.847299 -262.198006) (xy 78.898347 -262.217048)
			(xy 78.946166 -262.243162) (xy 78.989781 -262.275815) (xy 79.028306 -262.314343) (xy 79.060955 -262.357961)
			(xy 79.087065 -262.405782) (xy 79.106103 -262.456832) (xy 79.117682 -262.510071) (xy 79.121567 -262.564417)
			(xy 80.400285 -262.564417) (xy 80.40417 -262.510064) (xy 80.415751 -262.456817) (xy 80.434792 -262.405761)
			(xy 80.460905 -262.357934) (xy 80.493558 -262.31431) (xy 80.532088 -262.275777) (xy 80.57571 -262.24312)
			(xy 80.623535 -262.217003) (xy 80.67459 -262.197959) (xy 80.727836 -262.186374) (xy 80.782188 -262.182485)
			(xy 80.836541 -262.186371) (xy 80.889788 -262.197952) (xy 80.940844 -262.216994) (xy 80.988671 -262.243108)
			(xy 81.01076 -262.259064) (xy 81.029772 -262.27266) (xy 81.071655 -262.293392) (xy 81.116623 -262.306118)
			(xy 81.16316 -262.310408) (xy 81.209697 -262.306118) (xy 81.254665 -262.293392) (xy 81.296548 -262.27266)
			(xy 81.31556 -262.259064) (xy 81.337675 -262.243138) (xy 81.385502 -262.217015) (xy 81.43656 -262.197964)
			(xy 81.489809 -262.186375) (xy 81.544166 -262.182482) (xy 81.598524 -262.186365) (xy 81.651775 -262.197945)
			(xy 81.702836 -262.216987) (xy 81.750667 -262.243102) (xy 81.794295 -262.275758) (xy 81.83283 -262.314292)
			(xy 81.865489 -262.357918) (xy 81.891606 -262.405748) (xy 81.91065 -262.456809) (xy 81.922232 -262.510059)
			(xy 81.926118 -262.564417) (xy 81.922228 -262.618774) (xy 81.91064 -262.672024) (xy 81.891592 -262.723082)
			(xy 81.865471 -262.77091) (xy 81.832808 -262.814533) (xy 81.79427 -262.853064) (xy 81.750639 -262.885716)
			(xy 81.702806 -262.911827) (xy 81.651743 -262.930864) (xy 81.59849 -262.94244) (xy 81.544132 -262.946318)
			(xy 81.489776 -262.94242) (xy 81.436528 -262.930826) (xy 81.385471 -262.911771) (xy 81.337647 -262.885643)
			(xy 81.31556 -262.86968) (xy 81.296548 -262.856084) (xy 81.254665 -262.835352) (xy 81.209697 -262.822626)
			(xy 81.16316 -262.818336) (xy 81.116623 -262.822626) (xy 81.071655 -262.835352) (xy 81.029772 -262.856084)
			(xy 81.01076 -262.86968) (xy 80.988699 -262.885674) (xy 80.940875 -262.911792) (xy 80.88982 -262.930838)
			(xy 80.836575 -262.942424) (xy 80.782222 -262.946315) (xy 80.727869 -262.942431) (xy 80.674622 -262.930851)
			(xy 80.623566 -262.911811) (xy 80.575738 -262.885698) (xy 80.532114 -262.853045) (xy 80.493581 -262.814516)
			(xy 80.460923 -262.770895) (xy 80.434806 -262.72307) (xy 80.41576 -262.672015) (xy 80.404175 -262.618769)
			(xy 80.400285 -262.564417) (xy 79.121567 -262.564417) (xy 79.117677 -262.618762) (xy 79.106093 -262.672001)
			(xy 79.087051 -262.723049) (xy 79.060937 -262.770867) (xy 79.028284 -262.814483) (xy 78.989756 -262.853007)
			(xy 78.946137 -262.885656) (xy 78.898317 -262.911766) (xy 78.847267 -262.930803) (xy 78.794027 -262.942382)
			(xy 78.739681 -262.946267) (xy 78.685336 -262.942377) (xy 78.632098 -262.930793) (xy 78.581049 -262.91175)
			(xy 78.533231 -262.885636) (xy 78.511146 -262.86968) (xy 78.492134 -262.856084) (xy 78.450251 -262.835352)
			(xy 78.405283 -262.822626) (xy 78.358746 -262.818336) (xy 78.312209 -262.822626) (xy 78.267241 -262.835352)
			(xy 78.225358 -262.856084) (xy 78.206346 -262.86968) (xy 78.184283 -262.885682) (xy 78.136453 -262.911813)
			(xy 78.08539 -262.930871) (xy 78.032135 -262.942468) (xy 77.977771 -262.946366) (xy 77.923406 -262.942488)
			(xy 77.870146 -262.930911) (xy 77.819077 -262.911872) (xy 77.771236 -262.885758) (xy 77.7276 -262.853101)
			(xy 77.689056 -262.814566) (xy 77.656389 -262.770937) (xy 77.630264 -262.723103) (xy 77.611213 -262.672038)
			(xy 77.599624 -262.618781) (xy 77.595733 -262.564417) (xy 53.987192 -262.564417) (xy 53.987192 -263.092184)
			(xy 52.335176 -263.092184) (xy 52.335176 -261.440168) (xy 45.924363 -261.440168) (xy 45.938469 -261.46953)
			(xy 45.978891 -261.572506) (xy 46.011612 -261.678182) (xy 46.036453 -261.785982) (xy 46.053279 -261.89532)
			(xy 46.061999 -262.005602) (xy 46.062564 -262.116226) (xy 46.054972 -262.226591) (xy 46.043476 -262.306731)
			(xy 48.835554 -262.306731) (xy 48.835554 -262.225621) (xy 48.843504 -262.144902) (xy 48.859327 -262.065351)
			(xy 48.882872 -261.987735) (xy 48.913911 -261.912799) (xy 48.952146 -261.841267) (xy 48.997208 -261.773827)
			(xy 49.048663 -261.711128) (xy 49.106016 -261.653775) (xy 49.168715 -261.60232) (xy 49.236155 -261.557258)
			(xy 49.307687 -261.519023) (xy 49.382623 -261.487984) (xy 49.460239 -261.464439) (xy 49.53979 -261.448616)
			(xy 49.620509 -261.440666) (xy 49.701619 -261.440666) (xy 49.782338 -261.448616) (xy 49.861889 -261.464439)
			(xy 49.939505 -261.487984) (xy 50.014441 -261.519023) (xy 50.085973 -261.557258) (xy 50.153413 -261.60232)
			(xy 50.216112 -261.653775) (xy 50.273465 -261.711128) (xy 50.32492 -261.773827) (xy 50.369982 -261.841267)
			(xy 50.408217 -261.912799) (xy 50.439256 -261.987735) (xy 50.462801 -262.065351) (xy 50.478624 -262.144902)
			(xy 50.486574 -262.225621) (xy 50.487072 -262.266176) (xy 50.486574 -262.306731) (xy 50.478624 -262.38745)
			(xy 50.462801 -262.467001) (xy 50.439256 -262.544617) (xy 50.408217 -262.619553) (xy 50.369982 -262.691085)
			(xy 50.32492 -262.758525) (xy 50.273465 -262.821224) (xy 50.216112 -262.878577) (xy 50.153413 -262.930032)
			(xy 50.085973 -262.975094) (xy 50.014441 -263.013329) (xy 49.939505 -263.044368) (xy 49.861889 -263.067913)
			(xy 49.782338 -263.083736) (xy 49.701619 -263.091686) (xy 49.620509 -263.091686) (xy 49.53979 -263.083736)
			(xy 49.460239 -263.067913) (xy 49.382623 -263.044368) (xy 49.307687 -263.013329) (xy 49.236155 -262.975094)
			(xy 49.168715 -262.930032) (xy 49.106016 -262.878577) (xy 49.048663 -262.821224) (xy 48.997208 -262.758525)
			(xy 48.952146 -262.691085) (xy 48.913911 -262.619553) (xy 48.882872 -262.544617) (xy 48.859327 -262.467001)
			(xy 48.843504 -262.38745) (xy 48.835554 -262.306731) (xy 46.043476 -262.306731) (xy 46.039264 -262.336095)
			(xy 46.015526 -262.444144) (xy 45.983886 -262.550148) (xy 45.944518 -262.653532) (xy 45.897635 -262.753731)
			(xy 45.843492 -262.850202) (xy 45.782385 -262.942418) (xy 45.714645 -263.029879) (xy 45.640641 -263.112107)
			(xy 45.560777 -263.188655) (xy 45.475487 -263.259108) (xy 45.385234 -263.323081) (xy 45.290511 -263.380225)
			(xy 45.191833 -263.430231) (xy 45.089736 -263.472826) (xy 44.984778 -263.507778) (xy 44.877528 -263.534897)
			(xy 44.76857 -263.554036) (xy 44.658498 -263.565089) (xy 44.547911 -263.567997) (xy 44.43741 -263.562745)
			(xy 44.327598 -263.54936) (xy 44.21907 -263.527915) (xy 44.11242 -263.498528) (xy 44.008225 -263.461359)
			(xy 43.907055 -263.416608) (xy 43.809459 -263.364521) (xy 43.715969 -263.305381) (xy 43.627094 -263.239509)
			(xy 43.543316 -263.167264) (xy 43.50385 -263.128506) (xy 43.355006 -262.979916) (xy 41.463214 -262.979916)
			(xy 40.55364 -263.88949) (xy 40.55364 -266.451584) (xy 84.80474 -266.451584) (xy 84.80474 -266.391648)
			(xy 84.812563 -266.332226) (xy 84.828076 -266.274333) (xy 84.851012 -266.21896) (xy 84.880979 -266.167054)
			(xy 84.917466 -266.119504) (xy 84.959846 -266.077124) (xy 85.007396 -266.040637) (xy 85.059302 -266.01067)
			(xy 85.114675 -265.987734) (xy 85.172568 -265.972221) (xy 85.23199 -265.964398) (xy 85.291926 -265.964398)
			(xy 85.351348 -265.972221) (xy 85.409241 -265.987734) (xy 85.464614 -266.01067) (xy 85.51652 -266.040637)
			(xy 85.56407 -266.077124) (xy 85.60645 -266.119504) (xy 85.642937 -266.167054) (xy 85.651764 -266.182344)
			(xy 87.319594 -266.182344) (xy 87.319594 -266.122408) (xy 87.327417 -266.062986) (xy 87.34293 -266.005093)
			(xy 87.365866 -265.94972) (xy 87.395833 -265.897814) (xy 87.43232 -265.850264) (xy 87.4747 -265.807884)
			(xy 87.52225 -265.771397) (xy 87.574156 -265.74143) (xy 87.629529 -265.718494) (xy 87.687422 -265.702981)
			(xy 87.746844 -265.695158) (xy 87.80678 -265.695158) (xy 87.866202 -265.702981) (xy 87.924095 -265.718494)
			(xy 87.979468 -265.74143) (xy 88.031374 -265.771397) (xy 88.078924 -265.807884) (xy 88.121304 -265.850264)
			(xy 88.157791 -265.897814) (xy 88.187758 -265.94972) (xy 88.210694 -266.005093) (xy 88.226207 -266.062986)
			(xy 88.23403 -266.122408) (xy 88.23452 -266.152376) (xy 88.23403 -266.182344) (xy 88.226207 -266.241766)
			(xy 88.210694 -266.299659) (xy 88.187758 -266.355032) (xy 88.157791 -266.406938) (xy 88.121304 -266.454488)
			(xy 88.078924 -266.496868) (xy 88.031374 -266.533355) (xy 87.979468 -266.563322) (xy 87.924095 -266.586258)
			(xy 87.866202 -266.601771) (xy 87.80678 -266.609594) (xy 87.746844 -266.609594) (xy 87.687422 -266.601771)
			(xy 87.629529 -266.586258) (xy 87.574156 -266.563322) (xy 87.52225 -266.533355) (xy 87.4747 -266.496868)
			(xy 87.43232 -266.454488) (xy 87.395833 -266.406938) (xy 87.365866 -266.355032) (xy 87.34293 -266.299659)
			(xy 87.327417 -266.241766) (xy 87.319594 -266.182344) (xy 85.651764 -266.182344) (xy 85.672904 -266.21896)
			(xy 85.69584 -266.274333) (xy 85.711353 -266.332226) (xy 85.719176 -266.391648) (xy 85.719666 -266.421616)
			(xy 85.719176 -266.451584) (xy 85.711353 -266.511006) (xy 85.69584 -266.568899) (xy 85.672904 -266.624272)
			(xy 85.642937 -266.676178) (xy 85.60645 -266.723728) (xy 85.56407 -266.766108) (xy 85.51652 -266.802595)
			(xy 85.464614 -266.832562) (xy 85.409241 -266.855498) (xy 85.351348 -266.871011) (xy 85.291926 -266.878834)
			(xy 85.23199 -266.878834) (xy 85.172568 -266.871011) (xy 85.114675 -266.855498) (xy 85.059302 -266.832562)
			(xy 85.007396 -266.802595) (xy 84.959846 -266.766108) (xy 84.917466 -266.723728) (xy 84.880979 -266.676178)
			(xy 84.851012 -266.624272) (xy 84.828076 -266.568899) (xy 84.812563 -266.511006) (xy 84.80474 -266.451584)
			(xy 40.55364 -266.451584) (xy 40.55364 -267.558516) (xy 78.200994 -267.558516) (xy 78.200994 -267.49858)
			(xy 78.208817 -267.439158) (xy 78.22433 -267.381265) (xy 78.247266 -267.325892) (xy 78.277233 -267.273986)
			(xy 78.31372 -267.226436) (xy 78.3561 -267.184056) (xy 78.40365 -267.147569) (xy 78.455556 -267.117602)
			(xy 78.510929 -267.094666) (xy 78.568822 -267.079153) (xy 78.628244 -267.07133) (xy 78.68818 -267.07133)
			(xy 78.747602 -267.079153) (xy 78.805495 -267.094666) (xy 78.860868 -267.117602) (xy 78.912774 -267.147569)
			(xy 78.960324 -267.184056) (xy 79.002704 -267.226436) (xy 79.039191 -267.273986) (xy 79.069158 -267.325892)
			(xy 79.092094 -267.381265) (xy 79.107607 -267.439158) (xy 79.11543 -267.49858) (xy 79.11553 -267.504668)
			(xy 80.21115 -267.504668) (xy 80.21115 -267.444732) (xy 80.218973 -267.38531) (xy 80.234486 -267.327417)
			(xy 80.257422 -267.272044) (xy 80.287389 -267.220138) (xy 80.323876 -267.172588) (xy 80.366256 -267.130208)
			(xy 80.413806 -267.093721) (xy 80.465712 -267.063754) (xy 80.521085 -267.040818) (xy 80.578978 -267.025305)
			(xy 80.6384 -267.017482) (xy 80.698336 -267.017482) (xy 80.757758 -267.025305) (xy 80.815651 -267.040818)
			(xy 80.871024 -267.063754) (xy 80.92293 -267.093721) (xy 80.97048 -267.130208) (xy 81.01286 -267.172588)
			(xy 81.021319 -267.183612) (xy 81.901266 -267.183612) (xy 81.901266 -267.123676) (xy 81.909089 -267.064254)
			(xy 81.924602 -267.006361) (xy 81.947538 -266.950988) (xy 81.977505 -266.899082) (xy 82.013992 -266.851532)
			(xy 82.056372 -266.809152) (xy 82.103922 -266.772665) (xy 82.155828 -266.742698) (xy 82.211201 -266.719762)
			(xy 82.269094 -266.704249) (xy 82.328516 -266.696426) (xy 82.388452 -266.696426) (xy 82.447874 -266.704249)
			(xy 82.505767 -266.719762) (xy 82.56114 -266.742698) (xy 82.613046 -266.772665) (xy 82.660596 -266.809152)
			(xy 82.702976 -266.851532) (xy 82.739463 -266.899082) (xy 82.76943 -266.950988) (xy 82.792366 -267.006361)
			(xy 82.807879 -267.064254) (xy 82.815702 -267.123676) (xy 82.816192 -267.153644) (xy 82.815702 -267.183612)
			(xy 82.807879 -267.243034) (xy 82.792366 -267.300927) (xy 82.76943 -267.3563) (xy 82.739463 -267.408206)
			(xy 82.702976 -267.455756) (xy 82.660596 -267.498136) (xy 82.613046 -267.534623) (xy 82.56114 -267.56459)
			(xy 82.505767 -267.587526) (xy 82.447874 -267.603039) (xy 82.388452 -267.610862) (xy 82.328516 -267.610862)
			(xy 82.269094 -267.603039) (xy 82.211201 -267.587526) (xy 82.155828 -267.56459) (xy 82.103922 -267.534623)
			(xy 82.056372 -267.498136) (xy 82.013992 -267.455756) (xy 81.977505 -267.408206) (xy 81.947538 -267.3563)
			(xy 81.924602 -267.300927) (xy 81.909089 -267.243034) (xy 81.901266 -267.183612) (xy 81.021319 -267.183612)
			(xy 81.049347 -267.220138) (xy 81.079314 -267.272044) (xy 81.10225 -267.327417) (xy 81.117763 -267.38531)
			(xy 81.125586 -267.444732) (xy 81.126076 -267.4747) (xy 81.125586 -267.504668) (xy 81.117763 -267.56409)
			(xy 81.10225 -267.621983) (xy 81.079314 -267.677356) (xy 81.049347 -267.729262) (xy 81.01286 -267.776812)
			(xy 80.97048 -267.819192) (xy 80.92293 -267.855679) (xy 80.871024 -267.885646) (xy 80.815651 -267.908582)
			(xy 80.757758 -267.924095) (xy 80.698336 -267.931918) (xy 80.6384 -267.931918) (xy 80.578978 -267.924095)
			(xy 80.521085 -267.908582) (xy 80.465712 -267.885646) (xy 80.413806 -267.855679) (xy 80.366256 -267.819192)
			(xy 80.323876 -267.776812) (xy 80.287389 -267.729262) (xy 80.257422 -267.677356) (xy 80.234486 -267.621983)
			(xy 80.218973 -267.56409) (xy 80.21115 -267.504668) (xy 79.11553 -267.504668) (xy 79.11592 -267.528548)
			(xy 79.11543 -267.558516) (xy 79.107607 -267.617938) (xy 79.092094 -267.675831) (xy 79.069158 -267.731204)
			(xy 79.039191 -267.78311) (xy 79.002704 -267.83066) (xy 78.960324 -267.87304) (xy 78.912774 -267.909527)
			(xy 78.860868 -267.939494) (xy 78.805495 -267.96243) (xy 78.747602 -267.977943) (xy 78.68818 -267.985766)
			(xy 78.628244 -267.985766) (xy 78.568822 -267.977943) (xy 78.510929 -267.96243) (xy 78.455556 -267.939494)
			(xy 78.40365 -267.909527) (xy 78.3561 -267.87304) (xy 78.31372 -267.83066) (xy 78.277233 -267.78311)
			(xy 78.247266 -267.731204) (xy 78.22433 -267.675831) (xy 78.208817 -267.617938) (xy 78.200994 -267.558516)
			(xy 40.55364 -267.558516) (xy 40.55364 -271.80286) (xy 40.554082 -271.824808) (xy 40.561583 -271.868058)
			(xy 40.576402 -271.909375) (xy 40.5981 -271.947533) (xy 40.62603 -271.981395) (xy 40.659363 -272.009956)
			(xy 40.697107 -272.032365) (xy 40.73814 -272.047956) (xy 40.781241 -272.056266) (xy 40.825129 -272.057048)
			(xy 40.868499 -272.050277) (xy 40.889428 -272.043652) (xy 40.9447 -272.022678) (xy 41.057611 -271.987616)
			(xy 41.172707 -271.960573) (xy 41.289419 -271.941683) (xy 41.407169 -271.93104) (xy 41.466262 -271.929352)
			(xy 41.547796 -271.929606) (xy 41.606684 -271.931807) (xy 41.723964 -271.943435) (xy 41.840142 -271.963247)
			(xy 41.954647 -271.991147) (xy 42.066916 -272.026998) (xy 42.1764 -272.070623) (xy 42.282559 -272.121808)
			(xy 42.384873 -272.180303) (xy 42.482839 -272.245819) (xy 42.501206 -272.26006) (xy 63.647577 -272.26006)
			(xy 63.651612 -272.184356) (xy 63.663671 -272.109511) (xy 63.683617 -272.03637) (xy 63.711224 -271.965765)
			(xy 63.74618 -271.898494) (xy 63.788088 -271.835319) (xy 63.836474 -271.776957) (xy 63.89079 -271.724069)
			(xy 63.950419 -271.677254) (xy 64.014687 -271.637042) (xy 64.082864 -271.60389) (xy 64.15418 -271.578172)
			(xy 64.227825 -271.56018) (xy 64.302965 -271.550118) (xy 64.378749 -271.548099) (xy 64.454319 -271.554148)
			(xy 64.528817 -271.568195) (xy 64.6014 -271.590081) (xy 64.671246 -271.619558) (xy 64.737563 -271.656293)
			(xy 64.799599 -271.699868) (xy 64.856652 -271.74979) (xy 64.908076 -271.805494) (xy 64.953287 -271.866349)
			(xy 64.991774 -271.931664) (xy 65.0231 -272.0007) (xy 65.04691 -272.072675) (xy 65.062935 -272.146773)
			(xy 65.070994 -272.222154) (xy 65.071498 -272.26006) (xy 66.187577 -272.26006) (xy 66.191612 -272.184356)
			(xy 66.203671 -272.109511) (xy 66.223617 -272.03637) (xy 66.251224 -271.965765) (xy 66.28618 -271.898494)
			(xy 66.328088 -271.835319) (xy 66.376474 -271.776957) (xy 66.43079 -271.724069) (xy 66.490419 -271.677254)
			(xy 66.554687 -271.637042) (xy 66.622864 -271.60389) (xy 66.69418 -271.578172) (xy 66.767825 -271.56018)
			(xy 66.842965 -271.550118) (xy 66.918749 -271.548099) (xy 66.994319 -271.554148) (xy 67.068817 -271.568195)
			(xy 67.1414 -271.590081) (xy 67.211246 -271.619558) (xy 67.277563 -271.656293) (xy 67.339599 -271.699868)
			(xy 67.396652 -271.74979) (xy 67.448076 -271.805494) (xy 67.493287 -271.866349) (xy 67.531774 -271.931664)
			(xy 67.5631 -272.0007) (xy 67.58691 -272.072675) (xy 67.602935 -272.146773) (xy 67.610994 -272.222154)
			(xy 67.611498 -272.26006) (xy 68.727577 -272.26006) (xy 68.731612 -272.184356) (xy 68.743671 -272.109511)
			(xy 68.763617 -272.03637) (xy 68.791224 -271.965765) (xy 68.82618 -271.898494) (xy 68.868088 -271.835319)
			(xy 68.916474 -271.776957) (xy 68.97079 -271.724069) (xy 69.030419 -271.677254) (xy 69.094687 -271.637042)
			(xy 69.162864 -271.60389) (xy 69.23418 -271.578172) (xy 69.307825 -271.56018) (xy 69.382965 -271.550118)
			(xy 69.458749 -271.548099) (xy 69.534319 -271.554148) (xy 69.608817 -271.568195) (xy 69.6814 -271.590081)
			(xy 69.751246 -271.619558) (xy 69.817563 -271.656293) (xy 69.879599 -271.699868) (xy 69.936652 -271.74979)
			(xy 69.988076 -271.805494) (xy 70.033287 -271.866349) (xy 70.071774 -271.931664) (xy 70.1031 -272.0007)
			(xy 70.12691 -272.072675) (xy 70.142935 -272.146773) (xy 70.150994 -272.222154) (xy 70.151498 -272.26006)
			(xy 71.267577 -272.26006) (xy 71.271612 -272.184356) (xy 71.283671 -272.109511) (xy 71.303617 -272.03637)
			(xy 71.331224 -271.965765) (xy 71.36618 -271.898494) (xy 71.408088 -271.835319) (xy 71.456474 -271.776957)
			(xy 71.51079 -271.724069) (xy 71.570419 -271.677254) (xy 71.634687 -271.637042) (xy 71.702864 -271.60389)
			(xy 71.77418 -271.578172) (xy 71.847825 -271.56018) (xy 71.922965 -271.550118) (xy 71.998749 -271.548099)
			(xy 72.074319 -271.554148) (xy 72.148817 -271.568195) (xy 72.2214 -271.590081) (xy 72.291246 -271.619558)
			(xy 72.357563 -271.656293) (xy 72.419599 -271.699868) (xy 72.476652 -271.74979) (xy 72.528076 -271.805494)
			(xy 72.573287 -271.866349) (xy 72.611774 -271.931664) (xy 72.6431 -272.0007) (xy 72.66691 -272.072675)
			(xy 72.682935 -272.146773) (xy 72.690994 -272.222154) (xy 72.691498 -272.26006) (xy 73.807577 -272.26006)
			(xy 73.811612 -272.184356) (xy 73.823671 -272.109511) (xy 73.843617 -272.03637) (xy 73.871224 -271.965765)
			(xy 73.90618 -271.898494) (xy 73.948088 -271.835319) (xy 73.996474 -271.776957) (xy 74.05079 -271.724069)
			(xy 74.110419 -271.677254) (xy 74.174687 -271.637042) (xy 74.242864 -271.60389) (xy 74.31418 -271.578172)
			(xy 74.387825 -271.56018) (xy 74.462965 -271.550118) (xy 74.538749 -271.548099) (xy 74.614319 -271.554148)
			(xy 74.688817 -271.568195) (xy 74.7614 -271.590081) (xy 74.831246 -271.619558) (xy 74.897563 -271.656293)
			(xy 74.959599 -271.699868) (xy 75.016652 -271.74979) (xy 75.068076 -271.805494) (xy 75.113287 -271.866349)
			(xy 75.151774 -271.931664) (xy 75.1831 -272.0007) (xy 75.20691 -272.072675) (xy 75.222935 -272.146773)
			(xy 75.230994 -272.222154) (xy 75.231498 -272.26006) (xy 76.347577 -272.26006) (xy 76.351612 -272.184356)
			(xy 76.363671 -272.109511) (xy 76.383617 -272.03637) (xy 76.411224 -271.965765) (xy 76.44618 -271.898494)
			(xy 76.488088 -271.835319) (xy 76.536474 -271.776957) (xy 76.59079 -271.724069) (xy 76.650419 -271.677254)
			(xy 76.714687 -271.637042) (xy 76.782864 -271.60389) (xy 76.85418 -271.578172) (xy 76.927825 -271.56018)
			(xy 77.002965 -271.550118) (xy 77.078749 -271.548099) (xy 77.154319 -271.554148) (xy 77.228817 -271.568195)
			(xy 77.3014 -271.590081) (xy 77.371246 -271.619558) (xy 77.437563 -271.656293) (xy 77.499599 -271.699868)
			(xy 77.556652 -271.74979) (xy 77.608076 -271.805494) (xy 77.653287 -271.866349) (xy 77.691774 -271.931664)
			(xy 77.7231 -272.0007) (xy 77.74691 -272.072675) (xy 77.762935 -272.146773) (xy 77.770994 -272.222154)
			(xy 77.771498 -272.26006) (xy 78.887577 -272.26006) (xy 78.891612 -272.184356) (xy 78.903671 -272.109511)
			(xy 78.923617 -272.03637) (xy 78.951224 -271.965765) (xy 78.98618 -271.898494) (xy 79.028088 -271.835319)
			(xy 79.076474 -271.776957) (xy 79.13079 -271.724069) (xy 79.190419 -271.677254) (xy 79.254687 -271.637042)
			(xy 79.322864 -271.60389) (xy 79.39418 -271.578172) (xy 79.467825 -271.56018) (xy 79.542965 -271.550118)
			(xy 79.618749 -271.548099) (xy 79.694319 -271.554148) (xy 79.768817 -271.568195) (xy 79.8414 -271.590081)
			(xy 79.911246 -271.619558) (xy 79.977563 -271.656293) (xy 80.039599 -271.699868) (xy 80.096652 -271.74979)
			(xy 80.148076 -271.805494) (xy 80.193287 -271.866349) (xy 80.231774 -271.931664) (xy 80.2631 -272.0007)
			(xy 80.28691 -272.072675) (xy 80.302935 -272.146773) (xy 80.310994 -272.222154) (xy 80.311498 -272.26006)
			(xy 81.427577 -272.26006) (xy 81.431612 -272.184356) (xy 81.443671 -272.109511) (xy 81.463617 -272.03637)
			(xy 81.491224 -271.965765) (xy 81.52618 -271.898494) (xy 81.568088 -271.835319) (xy 81.616474 -271.776957)
			(xy 81.67079 -271.724069) (xy 81.730419 -271.677254) (xy 81.794687 -271.637042) (xy 81.862864 -271.60389)
			(xy 81.93418 -271.578172) (xy 82.007825 -271.56018) (xy 82.082965 -271.550118) (xy 82.158749 -271.548099)
			(xy 82.234319 -271.554148) (xy 82.308817 -271.568195) (xy 82.3814 -271.590081) (xy 82.451246 -271.619558)
			(xy 82.517563 -271.656293) (xy 82.579599 -271.699868) (xy 82.585544 -271.70507) (xy 86.197697 -271.70507)
			(xy 86.201732 -271.629366) (xy 86.213791 -271.554521) (xy 86.233737 -271.48138) (xy 86.261344 -271.410775)
			(xy 86.2963 -271.343504) (xy 86.338208 -271.280329) (xy 86.386594 -271.221967) (xy 86.44091 -271.169079)
			(xy 86.500539 -271.122264) (xy 86.564807 -271.082052) (xy 86.632984 -271.0489) (xy 86.7043 -271.023182)
			(xy 86.777945 -271.00519) (xy 86.853085 -270.995128) (xy 86.928869 -270.993109) (xy 87.004439 -270.999158)
			(xy 87.078937 -271.013205) (xy 87.15152 -271.035091) (xy 87.221366 -271.064568) (xy 87.287683 -271.101303)
			(xy 87.349719 -271.144878) (xy 87.406772 -271.1948) (xy 87.458196 -271.250504) (xy 87.503407 -271.311359)
			(xy 87.541894 -271.376674) (xy 87.57322 -271.44571) (xy 87.59703 -271.517685) (xy 87.613055 -271.591783)
			(xy 87.621114 -271.667164) (xy 87.621618 -271.70507) (xy 87.621114 -271.742976) (xy 87.613055 -271.818357)
			(xy 87.59703 -271.892455) (xy 87.57322 -271.96443) (xy 87.541894 -272.033466) (xy 87.503407 -272.098781)
			(xy 87.458196 -272.159636) (xy 87.406772 -272.21534) (xy 87.349719 -272.265262) (xy 87.287683 -272.308837)
			(xy 87.221366 -272.345572) (xy 87.15152 -272.375049) (xy 87.078937 -272.396935) (xy 87.004439 -272.410982)
			(xy 86.928869 -272.417031) (xy 86.853085 -272.415012) (xy 86.777945 -272.40495) (xy 86.7043 -272.386958)
			(xy 86.632984 -272.36124) (xy 86.564807 -272.328088) (xy 86.500539 -272.287876) (xy 86.44091 -272.241061)
			(xy 86.386594 -272.188173) (xy 86.338208 -272.129811) (xy 86.2963 -272.066636) (xy 86.261344 -271.999365)
			(xy 86.233737 -271.92876) (xy 86.213791 -271.855619) (xy 86.201732 -271.780774) (xy 86.197697 -271.70507)
			(xy 82.585544 -271.70507) (xy 82.636652 -271.74979) (xy 82.688076 -271.805494) (xy 82.733287 -271.866349)
			(xy 82.771774 -271.931664) (xy 82.8031 -272.0007) (xy 82.82691 -272.072675) (xy 82.842935 -272.146773)
			(xy 82.850994 -272.222154) (xy 82.851498 -272.26006) (xy 82.850994 -272.297966) (xy 82.842935 -272.373347)
			(xy 82.82691 -272.447445) (xy 82.8031 -272.51942) (xy 82.771774 -272.588456) (xy 82.733287 -272.653771)
			(xy 82.688076 -272.714626) (xy 82.636652 -272.77033) (xy 82.579599 -272.820252) (xy 82.517563 -272.863827)
			(xy 82.451246 -272.900562) (xy 82.3814 -272.930039) (xy 82.308817 -272.951925) (xy 82.234319 -272.965972)
			(xy 82.158749 -272.972021) (xy 82.082965 -272.970002) (xy 82.007825 -272.95994) (xy 81.93418 -272.941948)
			(xy 81.862864 -272.91623) (xy 81.794687 -272.883078) (xy 81.730419 -272.842866) (xy 81.67079 -272.796051)
			(xy 81.616474 -272.743163) (xy 81.568088 -272.684801) (xy 81.52618 -272.621626) (xy 81.491224 -272.554355)
			(xy 81.463617 -272.48375) (xy 81.443671 -272.410609) (xy 81.431612 -272.335764) (xy 81.427577 -272.26006)
			(xy 80.311498 -272.26006) (xy 80.310994 -272.297966) (xy 80.302935 -272.373347) (xy 80.28691 -272.447445)
			(xy 80.2631 -272.51942) (xy 80.231774 -272.588456) (xy 80.193287 -272.653771) (xy 80.148076 -272.714626)
			(xy 80.096652 -272.77033) (xy 80.039599 -272.820252) (xy 79.977563 -272.863827) (xy 79.911246 -272.900562)
			(xy 79.8414 -272.930039) (xy 79.768817 -272.951925) (xy 79.694319 -272.965972) (xy 79.618749 -272.972021)
			(xy 79.542965 -272.970002) (xy 79.467825 -272.95994) (xy 79.39418 -272.941948) (xy 79.322864 -272.91623)
			(xy 79.254687 -272.883078) (xy 79.190419 -272.842866) (xy 79.13079 -272.796051) (xy 79.076474 -272.743163)
			(xy 79.028088 -272.684801) (xy 78.98618 -272.621626) (xy 78.951224 -272.554355) (xy 78.923617 -272.48375)
			(xy 78.903671 -272.410609) (xy 78.891612 -272.335764) (xy 78.887577 -272.26006) (xy 77.771498 -272.26006)
			(xy 77.770994 -272.297966) (xy 77.762935 -272.373347) (xy 77.74691 -272.447445) (xy 77.7231 -272.51942)
			(xy 77.691774 -272.588456) (xy 77.653287 -272.653771) (xy 77.608076 -272.714626) (xy 77.556652 -272.77033)
			(xy 77.499599 -272.820252) (xy 77.437563 -272.863827) (xy 77.371246 -272.900562) (xy 77.3014 -272.930039)
			(xy 77.228817 -272.951925) (xy 77.154319 -272.965972) (xy 77.078749 -272.972021) (xy 77.002965 -272.970002)
			(xy 76.927825 -272.95994) (xy 76.85418 -272.941948) (xy 76.782864 -272.91623) (xy 76.714687 -272.883078)
			(xy 76.650419 -272.842866) (xy 76.59079 -272.796051) (xy 76.536474 -272.743163) (xy 76.488088 -272.684801)
			(xy 76.44618 -272.621626) (xy 76.411224 -272.554355) (xy 76.383617 -272.48375) (xy 76.363671 -272.410609)
			(xy 76.351612 -272.335764) (xy 76.347577 -272.26006) (xy 75.231498 -272.26006) (xy 75.230994 -272.297966)
			(xy 75.222935 -272.373347) (xy 75.20691 -272.447445) (xy 75.1831 -272.51942) (xy 75.151774 -272.588456)
			(xy 75.113287 -272.653771) (xy 75.068076 -272.714626) (xy 75.016652 -272.77033) (xy 74.959599 -272.820252)
			(xy 74.897563 -272.863827) (xy 74.831246 -272.900562) (xy 74.7614 -272.930039) (xy 74.688817 -272.951925)
			(xy 74.614319 -272.965972) (xy 74.538749 -272.972021) (xy 74.462965 -272.970002) (xy 74.387825 -272.95994)
			(xy 74.31418 -272.941948) (xy 74.242864 -272.91623) (xy 74.174687 -272.883078) (xy 74.110419 -272.842866)
			(xy 74.05079 -272.796051) (xy 73.996474 -272.743163) (xy 73.948088 -272.684801) (xy 73.90618 -272.621626)
			(xy 73.871224 -272.554355) (xy 73.843617 -272.48375) (xy 73.823671 -272.410609) (xy 73.811612 -272.335764)
			(xy 73.807577 -272.26006) (xy 72.691498 -272.26006) (xy 72.690994 -272.297966) (xy 72.682935 -272.373347)
			(xy 72.66691 -272.447445) (xy 72.6431 -272.51942) (xy 72.611774 -272.588456) (xy 72.573287 -272.653771)
			(xy 72.528076 -272.714626) (xy 72.476652 -272.77033) (xy 72.419599 -272.820252) (xy 72.357563 -272.863827)
			(xy 72.291246 -272.900562) (xy 72.2214 -272.930039) (xy 72.148817 -272.951925) (xy 72.074319 -272.965972)
			(xy 71.998749 -272.972021) (xy 71.922965 -272.970002) (xy 71.847825 -272.95994) (xy 71.77418 -272.941948)
			(xy 71.702864 -272.91623) (xy 71.634687 -272.883078) (xy 71.570419 -272.842866) (xy 71.51079 -272.796051)
			(xy 71.456474 -272.743163) (xy 71.408088 -272.684801) (xy 71.36618 -272.621626) (xy 71.331224 -272.554355)
			(xy 71.303617 -272.48375) (xy 71.283671 -272.410609) (xy 71.271612 -272.335764) (xy 71.267577 -272.26006)
			(xy 70.151498 -272.26006) (xy 70.150994 -272.297966) (xy 70.142935 -272.373347) (xy 70.12691 -272.447445)
			(xy 70.1031 -272.51942) (xy 70.071774 -272.588456) (xy 70.033287 -272.653771) (xy 69.988076 -272.714626)
			(xy 69.936652 -272.77033) (xy 69.879599 -272.820252) (xy 69.817563 -272.863827) (xy 69.751246 -272.900562)
			(xy 69.6814 -272.930039) (xy 69.608817 -272.951925) (xy 69.534319 -272.965972) (xy 69.458749 -272.972021)
			(xy 69.382965 -272.970002) (xy 69.307825 -272.95994) (xy 69.23418 -272.941948) (xy 69.162864 -272.91623)
			(xy 69.094687 -272.883078) (xy 69.030419 -272.842866) (xy 68.97079 -272.796051) (xy 68.916474 -272.743163)
			(xy 68.868088 -272.684801) (xy 68.82618 -272.621626) (xy 68.791224 -272.554355) (xy 68.763617 -272.48375)
			(xy 68.743671 -272.410609) (xy 68.731612 -272.335764) (xy 68.727577 -272.26006) (xy 67.611498 -272.26006)
			(xy 67.610994 -272.297966) (xy 67.602935 -272.373347) (xy 67.58691 -272.447445) (xy 67.5631 -272.51942)
			(xy 67.531774 -272.588456) (xy 67.493287 -272.653771) (xy 67.448076 -272.714626) (xy 67.396652 -272.77033)
			(xy 67.339599 -272.820252) (xy 67.277563 -272.863827) (xy 67.211246 -272.900562) (xy 67.1414 -272.930039)
			(xy 67.068817 -272.951925) (xy 66.994319 -272.965972) (xy 66.918749 -272.972021) (xy 66.842965 -272.970002)
			(xy 66.767825 -272.95994) (xy 66.69418 -272.941948) (xy 66.622864 -272.91623) (xy 66.554687 -272.883078)
			(xy 66.490419 -272.842866) (xy 66.43079 -272.796051) (xy 66.376474 -272.743163) (xy 66.328088 -272.684801)
			(xy 66.28618 -272.621626) (xy 66.251224 -272.554355) (xy 66.223617 -272.48375) (xy 66.203671 -272.410609)
			(xy 66.191612 -272.335764) (xy 66.187577 -272.26006) (xy 65.071498 -272.26006) (xy 65.070994 -272.297966)
			(xy 65.062935 -272.373347) (xy 65.04691 -272.447445) (xy 65.0231 -272.51942) (xy 64.991774 -272.588456)
			(xy 64.953287 -272.653771) (xy 64.908076 -272.714626) (xy 64.856652 -272.77033) (xy 64.799599 -272.820252)
			(xy 64.737563 -272.863827) (xy 64.671246 -272.900562) (xy 64.6014 -272.930039) (xy 64.528817 -272.951925)
			(xy 64.454319 -272.965972) (xy 64.378749 -272.972021) (xy 64.302965 -272.970002) (xy 64.227825 -272.95994)
			(xy 64.15418 -272.941948) (xy 64.082864 -272.91623) (xy 64.014687 -272.883078) (xy 63.950419 -272.842866)
			(xy 63.89079 -272.796051) (xy 63.836474 -272.743163) (xy 63.788088 -272.684801) (xy 63.74618 -272.621626)
			(xy 63.711224 -272.554355) (xy 63.683617 -272.48375) (xy 63.663671 -272.410609) (xy 63.651612 -272.335764)
			(xy 63.647577 -272.26006) (xy 42.501206 -272.26006) (xy 42.575976 -272.318035) (xy 42.663827 -272.396597)
			(xy 42.745961 -272.481118) (xy 42.821974 -272.571184) (xy 42.891492 -272.666352) (xy 42.954175 -272.766155)
			(xy 43.009714 -272.870102) (xy 43.056667 -272.97507) (xy 84.927697 -272.97507) (xy 84.931732 -272.899366)
			(xy 84.943791 -272.824521) (xy 84.963737 -272.75138) (xy 84.991344 -272.680775) (xy 85.0263 -272.613504)
			(xy 85.068208 -272.550329) (xy 85.116594 -272.491967) (xy 85.17091 -272.439079) (xy 85.230539 -272.392264)
			(xy 85.294807 -272.352052) (xy 85.362984 -272.3189) (xy 85.4343 -272.293182) (xy 85.507945 -272.27519)
			(xy 85.583085 -272.265128) (xy 85.658869 -272.263109) (xy 85.734439 -272.269158) (xy 85.808937 -272.283205)
			(xy 85.88152 -272.305091) (xy 85.951366 -272.334568) (xy 86.017683 -272.371303) (xy 86.079719 -272.414878)
			(xy 86.136772 -272.4648) (xy 86.188196 -272.520504) (xy 86.233407 -272.581359) (xy 86.271894 -272.646674)
			(xy 86.30322 -272.71571) (xy 86.32703 -272.787685) (xy 86.343055 -272.861783) (xy 86.351114 -272.937164)
			(xy 86.351618 -272.97507) (xy 86.351114 -273.012976) (xy 86.343055 -273.088357) (xy 86.32703 -273.162455)
			(xy 86.30322 -273.23443) (xy 86.271894 -273.303466) (xy 86.233407 -273.368781) (xy 86.188196 -273.429636)
			(xy 86.136772 -273.48534) (xy 86.079719 -273.535262) (xy 86.017683 -273.578837) (xy 85.951366 -273.615572)
			(xy 85.88152 -273.645049) (xy 85.808937 -273.666935) (xy 85.734439 -273.680982) (xy 85.658869 -273.687031)
			(xy 85.583085 -273.685012) (xy 85.507945 -273.67495) (xy 85.4343 -273.656958) (xy 85.362984 -273.63124)
			(xy 85.294807 -273.598088) (xy 85.230539 -273.557876) (xy 85.17091 -273.511061) (xy 85.116594 -273.458173)
			(xy 85.068208 -273.399811) (xy 85.0263 -273.336636) (xy 84.991344 -273.269365) (xy 84.963737 -273.19876)
			(xy 84.943791 -273.125619) (xy 84.931732 -273.050774) (xy 84.927697 -272.97507) (xy 43.056667 -272.97507)
			(xy 43.057837 -272.977685) (xy 43.098308 -273.088373) (xy 43.130928 -273.201623) (xy 43.155536 -273.31688)
			(xy 43.172012 -273.433578) (xy 43.180275 -273.551143) (xy 43.180762 -273.61007) (xy 43.180574 -273.643253)
			(xy 43.177908 -273.709567) (xy 43.175428 -273.742658) (xy 43.170086 -273.803308) (xy 43.151724 -273.92368)
			(xy 43.124703 -274.042409) (xy 43.089164 -274.158872) (xy 43.067732 -274.21586) (xy 43.056201 -274.24507)
			(xy 86.197697 -274.24507) (xy 86.201732 -274.169366) (xy 86.213791 -274.094521) (xy 86.233737 -274.02138)
			(xy 86.261344 -273.950775) (xy 86.2963 -273.883504) (xy 86.338208 -273.820329) (xy 86.386594 -273.761967)
			(xy 86.44091 -273.709079) (xy 86.500539 -273.662264) (xy 86.564807 -273.622052) (xy 86.632984 -273.5889)
			(xy 86.7043 -273.563182) (xy 86.777945 -273.54519) (xy 86.853085 -273.535128) (xy 86.928869 -273.533109)
			(xy 87.004439 -273.539158) (xy 87.078937 -273.553205) (xy 87.15152 -273.575091) (xy 87.221366 -273.604568)
			(xy 87.287683 -273.641303) (xy 87.349719 -273.684878) (xy 87.406772 -273.7348) (xy 87.458196 -273.790504)
			(xy 87.503407 -273.851359) (xy 87.541894 -273.916674) (xy 87.57322 -273.98571) (xy 87.59703 -274.057685)
			(xy 87.613055 -274.131783) (xy 87.621114 -274.207164) (xy 87.621618 -274.24507) (xy 87.621114 -274.282976)
			(xy 87.613055 -274.358357) (xy 87.59703 -274.432455) (xy 87.57322 -274.50443) (xy 87.541894 -274.573466)
			(xy 87.503407 -274.638781) (xy 87.458196 -274.699636) (xy 87.406772 -274.75534) (xy 87.349719 -274.805262)
			(xy 87.287683 -274.848837) (xy 87.221366 -274.885572) (xy 87.15152 -274.915049) (xy 87.078937 -274.936935)
			(xy 87.004439 -274.950982) (xy 86.928869 -274.957031) (xy 86.853085 -274.955012) (xy 86.777945 -274.94495)
			(xy 86.7043 -274.926958) (xy 86.632984 -274.90124) (xy 86.564807 -274.868088) (xy 86.500539 -274.827876)
			(xy 86.44091 -274.781061) (xy 86.386594 -274.728173) (xy 86.338208 -274.669811) (xy 86.2963 -274.606636)
			(xy 86.261344 -274.539365) (xy 86.233737 -274.46876) (xy 86.213791 -274.395619) (xy 86.201732 -274.320774)
			(xy 86.197697 -274.24507) (xy 43.056201 -274.24507) (xy 43.049898 -274.261038) (xy 43.009704 -274.349472)
			(xy 42.964476 -274.43544) (xy 42.939716 -274.477226) (xy 42.909418 -274.526592) (xy 42.842981 -274.621486)
			(xy 42.770166 -274.711581) (xy 42.691321 -274.796447) (xy 42.606819 -274.875682) (xy 42.517061 -274.94891)
			(xy 42.501262 -274.96008) (xy 63.647577 -274.96008) (xy 63.651612 -274.884376) (xy 63.663671 -274.809531)
			(xy 63.683617 -274.73639) (xy 63.711224 -274.665785) (xy 63.74618 -274.598514) (xy 63.788088 -274.535339)
			(xy 63.836474 -274.476977) (xy 63.89079 -274.424089) (xy 63.950419 -274.377274) (xy 64.014687 -274.337062)
			(xy 64.082864 -274.30391) (xy 64.15418 -274.278192) (xy 64.227825 -274.2602) (xy 64.302965 -274.250138)
			(xy 64.378749 -274.248119) (xy 64.454319 -274.254168) (xy 64.528817 -274.268215) (xy 64.6014 -274.290101)
			(xy 64.671246 -274.319578) (xy 64.737563 -274.356313) (xy 64.799599 -274.399888) (xy 64.856652 -274.44981)
			(xy 64.908076 -274.505514) (xy 64.953287 -274.566369) (xy 64.991774 -274.631684) (xy 65.0231 -274.70072)
			(xy 65.04691 -274.772695) (xy 65.062935 -274.846793) (xy 65.070994 -274.922174) (xy 65.071498 -274.96008)
			(xy 66.187577 -274.96008) (xy 66.191612 -274.884376) (xy 66.203671 -274.809531) (xy 66.223617 -274.73639)
			(xy 66.251224 -274.665785) (xy 66.28618 -274.598514) (xy 66.328088 -274.535339) (xy 66.376474 -274.476977)
			(xy 66.43079 -274.424089) (xy 66.490419 -274.377274) (xy 66.554687 -274.337062) (xy 66.622864 -274.30391)
			(xy 66.69418 -274.278192) (xy 66.767825 -274.2602) (xy 66.842965 -274.250138) (xy 66.918749 -274.248119)
			(xy 66.994319 -274.254168) (xy 67.068817 -274.268215) (xy 67.1414 -274.290101) (xy 67.211246 -274.319578)
			(xy 67.277563 -274.356313) (xy 67.339599 -274.399888) (xy 67.396652 -274.44981) (xy 67.448076 -274.505514)
			(xy 67.493287 -274.566369) (xy 67.531774 -274.631684) (xy 67.5631 -274.70072) (xy 67.58691 -274.772695)
			(xy 67.602935 -274.846793) (xy 67.610994 -274.922174) (xy 67.611498 -274.96008) (xy 68.727577 -274.96008)
			(xy 68.731612 -274.884376) (xy 68.743671 -274.809531) (xy 68.763617 -274.73639) (xy 68.791224 -274.665785)
			(xy 68.82618 -274.598514) (xy 68.868088 -274.535339) (xy 68.916474 -274.476977) (xy 68.97079 -274.424089)
			(xy 69.030419 -274.377274) (xy 69.094687 -274.337062) (xy 69.162864 -274.30391) (xy 69.23418 -274.278192)
			(xy 69.307825 -274.2602) (xy 69.382965 -274.250138) (xy 69.458749 -274.248119) (xy 69.534319 -274.254168)
			(xy 69.608817 -274.268215) (xy 69.6814 -274.290101) (xy 69.751246 -274.319578) (xy 69.817563 -274.356313)
			(xy 69.879599 -274.399888) (xy 69.936652 -274.44981) (xy 69.988076 -274.505514) (xy 70.033287 -274.566369)
			(xy 70.071774 -274.631684) (xy 70.1031 -274.70072) (xy 70.12691 -274.772695) (xy 70.142935 -274.846793)
			(xy 70.150994 -274.922174) (xy 70.151498 -274.96008) (xy 71.267577 -274.96008) (xy 71.271612 -274.884376)
			(xy 71.283671 -274.809531) (xy 71.303617 -274.73639) (xy 71.331224 -274.665785) (xy 71.36618 -274.598514)
			(xy 71.408088 -274.535339) (xy 71.456474 -274.476977) (xy 71.51079 -274.424089) (xy 71.570419 -274.377274)
			(xy 71.634687 -274.337062) (xy 71.702864 -274.30391) (xy 71.77418 -274.278192) (xy 71.847825 -274.2602)
			(xy 71.922965 -274.250138) (xy 71.998749 -274.248119) (xy 72.074319 -274.254168) (xy 72.148817 -274.268215)
			(xy 72.2214 -274.290101) (xy 72.291246 -274.319578) (xy 72.357563 -274.356313) (xy 72.419599 -274.399888)
			(xy 72.476652 -274.44981) (xy 72.528076 -274.505514) (xy 72.573287 -274.566369) (xy 72.611774 -274.631684)
			(xy 72.6431 -274.70072) (xy 72.66691 -274.772695) (xy 72.682935 -274.846793) (xy 72.690994 -274.922174)
			(xy 72.691498 -274.96008) (xy 73.807577 -274.96008) (xy 73.811612 -274.884376) (xy 73.823671 -274.809531)
			(xy 73.843617 -274.73639) (xy 73.871224 -274.665785) (xy 73.90618 -274.598514) (xy 73.948088 -274.535339)
			(xy 73.996474 -274.476977) (xy 74.05079 -274.424089) (xy 74.110419 -274.377274) (xy 74.174687 -274.337062)
			(xy 74.242864 -274.30391) (xy 74.31418 -274.278192) (xy 74.387825 -274.2602) (xy 74.462965 -274.250138)
			(xy 74.538749 -274.248119) (xy 74.614319 -274.254168) (xy 74.688817 -274.268215) (xy 74.7614 -274.290101)
			(xy 74.831246 -274.319578) (xy 74.897563 -274.356313) (xy 74.959599 -274.399888) (xy 75.016652 -274.44981)
			(xy 75.068076 -274.505514) (xy 75.113287 -274.566369) (xy 75.151774 -274.631684) (xy 75.1831 -274.70072)
			(xy 75.20691 -274.772695) (xy 75.222935 -274.846793) (xy 75.230994 -274.922174) (xy 75.231498 -274.96008)
			(xy 76.347577 -274.96008) (xy 76.351612 -274.884376) (xy 76.363671 -274.809531) (xy 76.383617 -274.73639)
			(xy 76.411224 -274.665785) (xy 76.44618 -274.598514) (xy 76.488088 -274.535339) (xy 76.536474 -274.476977)
			(xy 76.59079 -274.424089) (xy 76.650419 -274.377274) (xy 76.714687 -274.337062) (xy 76.782864 -274.30391)
			(xy 76.85418 -274.278192) (xy 76.927825 -274.2602) (xy 77.002965 -274.250138) (xy 77.078749 -274.248119)
			(xy 77.154319 -274.254168) (xy 77.228817 -274.268215) (xy 77.3014 -274.290101) (xy 77.371246 -274.319578)
			(xy 77.437563 -274.356313) (xy 77.499599 -274.399888) (xy 77.556652 -274.44981) (xy 77.608076 -274.505514)
			(xy 77.653287 -274.566369) (xy 77.691774 -274.631684) (xy 77.7231 -274.70072) (xy 77.74691 -274.772695)
			(xy 77.762935 -274.846793) (xy 77.770994 -274.922174) (xy 77.771498 -274.96008) (xy 78.887577 -274.96008)
			(xy 78.891612 -274.884376) (xy 78.903671 -274.809531) (xy 78.923617 -274.73639) (xy 78.951224 -274.665785)
			(xy 78.98618 -274.598514) (xy 79.028088 -274.535339) (xy 79.076474 -274.476977) (xy 79.13079 -274.424089)
			(xy 79.190419 -274.377274) (xy 79.254687 -274.337062) (xy 79.322864 -274.30391) (xy 79.39418 -274.278192)
			(xy 79.467825 -274.2602) (xy 79.542965 -274.250138) (xy 79.618749 -274.248119) (xy 79.694319 -274.254168)
			(xy 79.768817 -274.268215) (xy 79.8414 -274.290101) (xy 79.911246 -274.319578) (xy 79.977563 -274.356313)
			(xy 80.039599 -274.399888) (xy 80.096652 -274.44981) (xy 80.148076 -274.505514) (xy 80.193287 -274.566369)
			(xy 80.231774 -274.631684) (xy 80.2631 -274.70072) (xy 80.28691 -274.772695) (xy 80.302935 -274.846793)
			(xy 80.310994 -274.922174) (xy 80.311498 -274.96008) (xy 81.427577 -274.96008) (xy 81.431612 -274.884376)
			(xy 81.443671 -274.809531) (xy 81.463617 -274.73639) (xy 81.491224 -274.665785) (xy 81.52618 -274.598514)
			(xy 81.568088 -274.535339) (xy 81.616474 -274.476977) (xy 81.67079 -274.424089) (xy 81.730419 -274.377274)
			(xy 81.794687 -274.337062) (xy 81.862864 -274.30391) (xy 81.93418 -274.278192) (xy 82.007825 -274.2602)
			(xy 82.082965 -274.250138) (xy 82.158749 -274.248119) (xy 82.234319 -274.254168) (xy 82.308817 -274.268215)
			(xy 82.3814 -274.290101) (xy 82.451246 -274.319578) (xy 82.517563 -274.356313) (xy 82.579599 -274.399888)
			(xy 82.636652 -274.44981) (xy 82.688076 -274.505514) (xy 82.733287 -274.566369) (xy 82.771774 -274.631684)
			(xy 82.8031 -274.70072) (xy 82.82691 -274.772695) (xy 82.842935 -274.846793) (xy 82.850994 -274.922174)
			(xy 82.851498 -274.96008) (xy 82.850994 -274.997986) (xy 82.842935 -275.073367) (xy 82.82691 -275.147465)
			(xy 82.8031 -275.21944) (xy 82.771774 -275.288476) (xy 82.733287 -275.353791) (xy 82.688076 -275.414646)
			(xy 82.636652 -275.47035) (xy 82.585544 -275.51507) (xy 84.927697 -275.51507) (xy 84.931732 -275.439366)
			(xy 84.943791 -275.364521) (xy 84.963737 -275.29138) (xy 84.991344 -275.220775) (xy 85.0263 -275.153504)
			(xy 85.068208 -275.090329) (xy 85.116594 -275.031967) (xy 85.17091 -274.979079) (xy 85.230539 -274.932264)
			(xy 85.294807 -274.892052) (xy 85.362984 -274.8589) (xy 85.4343 -274.833182) (xy 85.507945 -274.81519)
			(xy 85.583085 -274.805128) (xy 85.658869 -274.803109) (xy 85.734439 -274.809158) (xy 85.808937 -274.823205)
			(xy 85.88152 -274.845091) (xy 85.951366 -274.874568) (xy 86.017683 -274.911303) (xy 86.079719 -274.954878)
			(xy 86.136772 -275.0048) (xy 86.188196 -275.060504) (xy 86.233407 -275.121359) (xy 86.271894 -275.186674)
			(xy 86.30322 -275.25571) (xy 86.32703 -275.327685) (xy 86.343055 -275.401783) (xy 86.351114 -275.477164)
			(xy 86.351618 -275.51507) (xy 86.351114 -275.552976) (xy 86.343055 -275.628357) (xy 86.32703 -275.702455)
			(xy 86.30322 -275.77443) (xy 86.271894 -275.843466) (xy 86.233407 -275.908781) (xy 86.188196 -275.969636)
			(xy 86.136772 -276.02534) (xy 86.079719 -276.075262) (xy 86.017683 -276.118837) (xy 85.951366 -276.155572)
			(xy 85.88152 -276.185049) (xy 85.808937 -276.206935) (xy 85.734439 -276.220982) (xy 85.658869 -276.227031)
			(xy 85.583085 -276.225012) (xy 85.507945 -276.21495) (xy 85.4343 -276.196958) (xy 85.362984 -276.17124)
			(xy 85.294807 -276.138088) (xy 85.230539 -276.097876) (xy 85.17091 -276.051061) (xy 85.116594 -275.998173)
			(xy 85.068208 -275.939811) (xy 85.0263 -275.876636) (xy 84.991344 -275.809365) (xy 84.963737 -275.73876)
			(xy 84.943791 -275.665619) (xy 84.931732 -275.590774) (xy 84.927697 -275.51507) (xy 82.585544 -275.51507)
			(xy 82.579599 -275.520272) (xy 82.517563 -275.563847) (xy 82.451246 -275.600582) (xy 82.3814 -275.630059)
			(xy 82.308817 -275.651945) (xy 82.234319 -275.665992) (xy 82.158749 -275.672041) (xy 82.082965 -275.670022)
			(xy 82.007825 -275.65996) (xy 81.93418 -275.641968) (xy 81.862864 -275.61625) (xy 81.794687 -275.583098)
			(xy 81.730419 -275.542886) (xy 81.67079 -275.496071) (xy 81.616474 -275.443183) (xy 81.568088 -275.384821)
			(xy 81.52618 -275.321646) (xy 81.491224 -275.254375) (xy 81.463617 -275.18377) (xy 81.443671 -275.110629)
			(xy 81.431612 -275.035784) (xy 81.427577 -274.96008) (xy 80.311498 -274.96008) (xy 80.310994 -274.997986)
			(xy 80.302935 -275.073367) (xy 80.28691 -275.147465) (xy 80.2631 -275.21944) (xy 80.231774 -275.288476)
			(xy 80.193287 -275.353791) (xy 80.148076 -275.414646) (xy 80.096652 -275.47035) (xy 80.039599 -275.520272)
			(xy 79.977563 -275.563847) (xy 79.911246 -275.600582) (xy 79.8414 -275.630059) (xy 79.768817 -275.651945)
			(xy 79.694319 -275.665992) (xy 79.618749 -275.672041) (xy 79.542965 -275.670022) (xy 79.467825 -275.65996)
			(xy 79.39418 -275.641968) (xy 79.322864 -275.61625) (xy 79.254687 -275.583098) (xy 79.190419 -275.542886)
			(xy 79.13079 -275.496071) (xy 79.076474 -275.443183) (xy 79.028088 -275.384821) (xy 78.98618 -275.321646)
			(xy 78.951224 -275.254375) (xy 78.923617 -275.18377) (xy 78.903671 -275.110629) (xy 78.891612 -275.035784)
			(xy 78.887577 -274.96008) (xy 77.771498 -274.96008) (xy 77.770994 -274.997986) (xy 77.762935 -275.073367)
			(xy 77.74691 -275.147465) (xy 77.7231 -275.21944) (xy 77.691774 -275.288476) (xy 77.653287 -275.353791)
			(xy 77.608076 -275.414646) (xy 77.556652 -275.47035) (xy 77.499599 -275.520272) (xy 77.437563 -275.563847)
			(xy 77.371246 -275.600582) (xy 77.3014 -275.630059) (xy 77.228817 -275.651945) (xy 77.154319 -275.665992)
			(xy 77.078749 -275.672041) (xy 77.002965 -275.670022) (xy 76.927825 -275.65996) (xy 76.85418 -275.641968)
			(xy 76.782864 -275.61625) (xy 76.714687 -275.583098) (xy 76.650419 -275.542886) (xy 76.59079 -275.496071)
			(xy 76.536474 -275.443183) (xy 76.488088 -275.384821) (xy 76.44618 -275.321646) (xy 76.411224 -275.254375)
			(xy 76.383617 -275.18377) (xy 76.363671 -275.110629) (xy 76.351612 -275.035784) (xy 76.347577 -274.96008)
			(xy 75.231498 -274.96008) (xy 75.230994 -274.997986) (xy 75.222935 -275.073367) (xy 75.20691 -275.147465)
			(xy 75.1831 -275.21944) (xy 75.151774 -275.288476) (xy 75.113287 -275.353791) (xy 75.068076 -275.414646)
			(xy 75.016652 -275.47035) (xy 74.959599 -275.520272) (xy 74.897563 -275.563847) (xy 74.831246 -275.600582)
			(xy 74.7614 -275.630059) (xy 74.688817 -275.651945) (xy 74.614319 -275.665992) (xy 74.538749 -275.672041)
			(xy 74.462965 -275.670022) (xy 74.387825 -275.65996) (xy 74.31418 -275.641968) (xy 74.242864 -275.61625)
			(xy 74.174687 -275.583098) (xy 74.110419 -275.542886) (xy 74.05079 -275.496071) (xy 73.996474 -275.443183)
			(xy 73.948088 -275.384821) (xy 73.90618 -275.321646) (xy 73.871224 -275.254375) (xy 73.843617 -275.18377)
			(xy 73.823671 -275.110629) (xy 73.811612 -275.035784) (xy 73.807577 -274.96008) (xy 72.691498 -274.96008)
			(xy 72.690994 -274.997986) (xy 72.682935 -275.073367) (xy 72.66691 -275.147465) (xy 72.6431 -275.21944)
			(xy 72.611774 -275.288476) (xy 72.573287 -275.353791) (xy 72.528076 -275.414646) (xy 72.476652 -275.47035)
			(xy 72.419599 -275.520272) (xy 72.357563 -275.563847) (xy 72.291246 -275.600582) (xy 72.2214 -275.630059)
			(xy 72.148817 -275.651945) (xy 72.074319 -275.665992) (xy 71.998749 -275.672041) (xy 71.922965 -275.670022)
			(xy 71.847825 -275.65996) (xy 71.77418 -275.641968) (xy 71.702864 -275.61625) (xy 71.634687 -275.583098)
			(xy 71.570419 -275.542886) (xy 71.51079 -275.496071) (xy 71.456474 -275.443183) (xy 71.408088 -275.384821)
			(xy 71.36618 -275.321646) (xy 71.331224 -275.254375) (xy 71.303617 -275.18377) (xy 71.283671 -275.110629)
			(xy 71.271612 -275.035784) (xy 71.267577 -274.96008) (xy 70.151498 -274.96008) (xy 70.150994 -274.997986)
			(xy 70.142935 -275.073367) (xy 70.12691 -275.147465) (xy 70.1031 -275.21944) (xy 70.071774 -275.288476)
			(xy 70.033287 -275.353791) (xy 69.988076 -275.414646) (xy 69.936652 -275.47035) (xy 69.879599 -275.520272)
			(xy 69.817563 -275.563847) (xy 69.751246 -275.600582) (xy 69.6814 -275.630059) (xy 69.608817 -275.651945)
			(xy 69.534319 -275.665992) (xy 69.458749 -275.672041) (xy 69.382965 -275.670022) (xy 69.307825 -275.65996)
			(xy 69.23418 -275.641968) (xy 69.162864 -275.61625) (xy 69.094687 -275.583098) (xy 69.030419 -275.542886)
			(xy 68.97079 -275.496071) (xy 68.916474 -275.443183) (xy 68.868088 -275.384821) (xy 68.82618 -275.321646)
			(xy 68.791224 -275.254375) (xy 68.763617 -275.18377) (xy 68.743671 -275.110629) (xy 68.731612 -275.035784)
			(xy 68.727577 -274.96008) (xy 67.611498 -274.96008) (xy 67.610994 -274.997986) (xy 67.602935 -275.073367)
			(xy 67.58691 -275.147465) (xy 67.5631 -275.21944) (xy 67.531774 -275.288476) (xy 67.493287 -275.353791)
			(xy 67.448076 -275.414646) (xy 67.396652 -275.47035) (xy 67.339599 -275.520272) (xy 67.277563 -275.563847)
			(xy 67.211246 -275.600582) (xy 67.1414 -275.630059) (xy 67.068817 -275.651945) (xy 66.994319 -275.665992)
			(xy 66.918749 -275.672041) (xy 66.842965 -275.670022) (xy 66.767825 -275.65996) (xy 66.69418 -275.641968)
			(xy 66.622864 -275.61625) (xy 66.554687 -275.583098) (xy 66.490419 -275.542886) (xy 66.43079 -275.496071)
			(xy 66.376474 -275.443183) (xy 66.328088 -275.384821) (xy 66.28618 -275.321646) (xy 66.251224 -275.254375)
			(xy 66.223617 -275.18377) (xy 66.203671 -275.110629) (xy 66.191612 -275.035784) (xy 66.187577 -274.96008)
			(xy 65.071498 -274.96008) (xy 65.070994 -274.997986) (xy 65.062935 -275.073367) (xy 65.04691 -275.147465)
			(xy 65.0231 -275.21944) (xy 64.991774 -275.288476) (xy 64.953287 -275.353791) (xy 64.908076 -275.414646)
			(xy 64.856652 -275.47035) (xy 64.799599 -275.520272) (xy 64.737563 -275.563847) (xy 64.671246 -275.600582)
			(xy 64.6014 -275.630059) (xy 64.528817 -275.651945) (xy 64.454319 -275.665992) (xy 64.378749 -275.672041)
			(xy 64.302965 -275.670022) (xy 64.227825 -275.65996) (xy 64.15418 -275.641968) (xy 64.082864 -275.61625)
			(xy 64.014687 -275.583098) (xy 63.950419 -275.542886) (xy 63.89079 -275.496071) (xy 63.836474 -275.443183)
			(xy 63.788088 -275.384821) (xy 63.74618 -275.321646) (xy 63.711224 -275.254375) (xy 63.683617 -275.18377)
			(xy 63.663671 -275.110629) (xy 63.651612 -275.035784) (xy 63.647577 -274.96008) (xy 42.501262 -274.96008)
			(xy 42.422473 -275.015784) (xy 42.323505 -275.075985) (xy 42.220626 -275.129228) (xy 42.114325 -275.17526)
			(xy 42.005107 -275.213863) (xy 41.893489 -275.244854) (xy 41.780003 -275.268084) (xy 41.665186 -275.283444)
			(xy 41.549583 -275.290862) (xy 41.491662 -275.291042) (xy 41.469164 -275.292704) (xy 41.42524 -275.302966)
			(xy 41.383815 -275.320818) (xy 41.346191 -275.345699) (xy 41.313548 -275.37683) (xy 41.286911 -275.413232)
			(xy 41.267115 -275.453763) (xy 41.254782 -275.497152) (xy 41.250298 -275.542036) (xy 41.253806 -275.587007)
			(xy 41.265194 -275.630653) (xy 41.284105 -275.671604) (xy 41.309946 -275.708576) (xy 41.325546 -275.724874)
			(xy 45.647356 -280.046684) (xy 45.647356 -281.15666) (xy 86.943928 -281.15666) (xy 86.943928 -281.096724)
			(xy 86.951751 -281.037302) (xy 86.967264 -280.979409) (xy 86.9902 -280.924036) (xy 87.020167 -280.87213)
			(xy 87.056654 -280.82458) (xy 87.099034 -280.7822) (xy 87.146584 -280.745713) (xy 87.19849 -280.715746)
			(xy 87.253863 -280.69281) (xy 87.311756 -280.677297) (xy 87.371178 -280.669474) (xy 87.431114 -280.669474)
			(xy 87.490536 -280.677297) (xy 87.548429 -280.69281) (xy 87.603802 -280.715746) (xy 87.655708 -280.745713)
			(xy 87.703258 -280.7822) (xy 87.745638 -280.82458) (xy 87.782125 -280.87213) (xy 87.812092 -280.924036)
			(xy 87.835028 -280.979409) (xy 87.850541 -281.037302) (xy 87.858364 -281.096724) (xy 87.858854 -281.126692)
			(xy 87.858364 -281.15666) (xy 87.850541 -281.216082) (xy 87.835028 -281.273975) (xy 87.812092 -281.329348)
			(xy 87.782125 -281.381254) (xy 87.745638 -281.428804) (xy 87.703258 -281.471184) (xy 87.655708 -281.507671)
			(xy 87.603802 -281.537638) (xy 87.548429 -281.560574) (xy 87.490536 -281.576087) (xy 87.431114 -281.58391)
			(xy 87.371178 -281.58391) (xy 87.311756 -281.576087) (xy 87.253863 -281.560574) (xy 87.19849 -281.537638)
			(xy 87.146584 -281.507671) (xy 87.099034 -281.471184) (xy 87.056654 -281.428804) (xy 87.020167 -281.381254)
			(xy 86.9902 -281.329348) (xy 86.967264 -281.273975) (xy 86.951751 -281.216082) (xy 86.943928 -281.15666)
			(xy 45.647356 -281.15666) (xy 45.647356 -281.86786) (xy 85.270068 -281.86786) (xy 85.270068 -281.807924)
			(xy 85.277891 -281.748502) (xy 85.293404 -281.690609) (xy 85.31634 -281.635236) (xy 85.346307 -281.58333)
			(xy 85.382794 -281.53578) (xy 85.425174 -281.4934) (xy 85.472724 -281.456913) (xy 85.52463 -281.426946)
			(xy 85.580003 -281.40401) (xy 85.637896 -281.388497) (xy 85.697318 -281.380674) (xy 85.757254 -281.380674)
			(xy 85.816676 -281.388497) (xy 85.874569 -281.40401) (xy 85.929942 -281.426946) (xy 85.981848 -281.456913)
			(xy 86.029398 -281.4934) (xy 86.071778 -281.53578) (xy 86.108265 -281.58333) (xy 86.138232 -281.635236)
			(xy 86.161168 -281.690609) (xy 86.176681 -281.748502) (xy 86.184504 -281.807924) (xy 86.184994 -281.837892)
			(xy 86.184504 -281.86786) (xy 86.176681 -281.927282) (xy 86.161168 -281.985175) (xy 86.138232 -282.040548)
			(xy 86.108265 -282.092454) (xy 86.071778 -282.140004) (xy 86.029398 -282.182384) (xy 85.981848 -282.218871)
			(xy 85.929942 -282.248838) (xy 85.874569 -282.271774) (xy 85.816676 -282.287287) (xy 85.757254 -282.29511)
			(xy 85.697318 -282.29511) (xy 85.637896 -282.287287) (xy 85.580003 -282.271774) (xy 85.52463 -282.248838)
			(xy 85.472724 -282.218871) (xy 85.425174 -282.182384) (xy 85.382794 -282.140004) (xy 85.346307 -282.092454)
			(xy 85.31634 -282.040548) (xy 85.293404 -281.985175) (xy 85.277891 -281.927282) (xy 85.270068 -281.86786)
			(xy 45.647356 -281.86786) (xy 45.647356 -284.379416) (xy 51.251612 -284.379416) (xy 52.903628 -284.379416)
			(xy 52.903628 -284.786828) (xy 83.105988 -284.786828) (xy 83.105988 -284.726892) (xy 83.113811 -284.66747)
			(xy 83.129324 -284.609577) (xy 83.15226 -284.554204) (xy 83.182227 -284.502298) (xy 83.218714 -284.454748)
			(xy 83.261094 -284.412368) (xy 83.308644 -284.375881) (xy 83.36055 -284.345914) (xy 83.415923 -284.322978)
			(xy 83.473816 -284.307465) (xy 83.533238 -284.299642) (xy 83.593174 -284.299642) (xy 83.652596 -284.307465)
			(xy 83.710489 -284.322978) (xy 83.765862 -284.345914) (xy 83.817768 -284.375881) (xy 83.865318 -284.412368)
			(xy 83.907698 -284.454748) (xy 83.944185 -284.502298) (xy 83.974152 -284.554204) (xy 83.997088 -284.609577)
			(xy 84.012601 -284.66747) (xy 84.020424 -284.726892) (xy 84.020914 -284.75686) (xy 84.020424 -284.786828)
			(xy 84.012601 -284.84625) (xy 83.997088 -284.904143) (xy 83.974152 -284.959516) (xy 83.944185 -285.011422)
			(xy 83.907698 -285.058972) (xy 83.865318 -285.101352) (xy 83.817768 -285.137839) (xy 83.765862 -285.167806)
			(xy 83.710489 -285.190742) (xy 83.652596 -285.206255) (xy 83.593174 -285.214078) (xy 83.533238 -285.214078)
			(xy 83.473816 -285.206255) (xy 83.415923 -285.190742) (xy 83.36055 -285.167806) (xy 83.308644 -285.137839)
			(xy 83.261094 -285.101352) (xy 83.218714 -285.058972) (xy 83.182227 -285.011422) (xy 83.15226 -284.959516)
			(xy 83.129324 -284.904143) (xy 83.113811 -284.84625) (xy 83.105988 -284.786828) (xy 52.903628 -284.786828)
			(xy 52.903628 -285.7246) (xy 58.726192 -285.7246) (xy 58.730079 -285.670247) (xy 58.741663 -285.617001)
			(xy 58.760706 -285.565945) (xy 58.786822 -285.518119) (xy 58.819479 -285.474496) (xy 58.858012 -285.435966)
			(xy 58.901636 -285.403312) (xy 58.949463 -285.377198) (xy 59.00052 -285.358157) (xy 59.053767 -285.346577)
			(xy 59.10812 -285.342692) (xy 59.162473 -285.346582) (xy 59.215719 -285.358169) (xy 59.266774 -285.377215)
			(xy 59.314598 -285.403333) (xy 59.336686 -285.419292) (xy 59.355698 -285.432888) (xy 59.397581 -285.45362)
			(xy 59.442549 -285.466346) (xy 59.489086 -285.470636) (xy 59.535623 -285.466346) (xy 59.580591 -285.45362)
			(xy 59.622474 -285.432888) (xy 59.641486 -285.419292) (xy 59.663574 -285.403331) (xy 59.711401 -285.377208)
			(xy 59.762458 -285.358158) (xy 59.815708 -285.346568) (xy 59.870064 -285.342675) (xy 59.924421 -285.346558)
			(xy 59.977672 -285.358137) (xy 60.028734 -285.377178) (xy 60.076565 -285.403292) (xy 60.120193 -285.435948)
			(xy 60.158729 -285.47448) (xy 60.191389 -285.518105) (xy 60.217507 -285.565934) (xy 60.236552 -285.616993)
			(xy 60.248137 -285.670243) (xy 60.252025 -285.7246) (xy 61.258109 -285.7246) (xy 61.261996 -285.670251)
			(xy 61.273578 -285.617008) (xy 61.29262 -285.565956) (xy 61.318733 -285.518133) (xy 61.351387 -285.474513)
			(xy 61.389916 -285.435984) (xy 61.433536 -285.403331) (xy 61.481359 -285.377218) (xy 61.532412 -285.358177)
			(xy 61.585655 -285.346595) (xy 61.640004 -285.342709) (xy 61.694353 -285.346596) (xy 61.747596 -285.358179)
			(xy 61.798648 -285.377222) (xy 61.846471 -285.403336) (xy 61.868558 -285.419292) (xy 61.88757 -285.432888)
			(xy 61.929453 -285.45362) (xy 61.974421 -285.466346) (xy 62.020958 -285.470636) (xy 62.067495 -285.466346)
			(xy 62.112463 -285.45362) (xy 62.154346 -285.432888) (xy 62.173358 -285.419292) (xy 62.195447 -285.403328)
			(xy 62.243276 -285.377201) (xy 62.294336 -285.358147) (xy 62.347588 -285.346554) (xy 62.401948 -285.342658)
			(xy 62.456309 -285.346539) (xy 62.509565 -285.358118) (xy 62.56063 -285.377158) (xy 62.608465 -285.403272)
			(xy 62.652097 -285.435929) (xy 62.690637 -285.474464) (xy 62.7233 -285.518091) (xy 62.749421 -285.565923)
			(xy 62.768468 -285.616986) (xy 62.780053 -285.670239) (xy 62.781323 -285.687986) (xy 63.482113 -285.687986)
			(xy 63.486003 -285.633636) (xy 63.497588 -285.580393) (xy 63.516632 -285.529341) (xy 63.542748 -285.481519)
			(xy 63.575404 -285.437901) (xy 63.613936 -285.399374) (xy 63.657558 -285.366723) (xy 63.705383 -285.340612)
			(xy 63.756438 -285.321574) (xy 63.809682 -285.309996) (xy 63.864032 -285.306113) (xy 63.918382 -285.310005)
			(xy 63.971624 -285.321593) (xy 64.022675 -285.340639) (xy 64.070496 -285.366758) (xy 64.092582 -285.382716)
			(xy 64.111594 -285.396312) (xy 64.153477 -285.417044) (xy 64.198445 -285.42977) (xy 64.244982 -285.43406)
			(xy 64.291519 -285.42977) (xy 64.336487 -285.417044) (xy 64.37837 -285.396312) (xy 64.397382 -285.382716)
			(xy 64.419448 -285.366722) (xy 64.467276 -285.340595) (xy 64.518336 -285.321542) (xy 64.571588 -285.309949)
			(xy 64.625947 -285.306053) (xy 64.680308 -285.309934) (xy 64.733563 -285.321512) (xy 64.784628 -285.340552)
			(xy 64.832463 -285.366665) (xy 64.876095 -285.399321) (xy 64.914635 -285.437854) (xy 64.947299 -285.48148)
			(xy 64.97342 -285.529311) (xy 64.992469 -285.580373) (xy 65.004056 -285.633626) (xy 65.00535 -285.651699)
			(xy 65.77816 -285.651699) (xy 65.782048 -285.597338) (xy 65.793634 -285.544085) (xy 65.812681 -285.493022)
			(xy 65.838802 -285.445191) (xy 65.871465 -285.401564) (xy 65.910005 -285.36303) (xy 65.953636 -285.330373)
			(xy 66.001472 -285.304259) (xy 66.052537 -285.285219) (xy 66.105792 -285.273641) (xy 66.160153 -285.26976)
			(xy 66.214513 -285.273656) (xy 66.267765 -285.285249) (xy 66.318825 -285.304303) (xy 66.366653 -285.33043)
			(xy 66.388742 -285.346394) (xy 66.407754 -285.35999) (xy 66.449637 -285.380722) (xy 66.494605 -285.393448)
			(xy 66.541142 -285.397738) (xy 66.587679 -285.393448) (xy 66.632647 -285.380722) (xy 66.67453 -285.35999)
			(xy 66.693542 -285.346394) (xy 66.715627 -285.330435) (xy 66.76345 -285.304321) (xy 66.814502 -285.285278)
			(xy 66.867745 -285.273695) (xy 66.922095 -285.269807) (xy 66.976444 -285.273693) (xy 67.029687 -285.285275)
			(xy 67.08074 -285.304316) (xy 67.128564 -285.330429) (xy 67.172184 -285.363082) (xy 67.210713 -285.401611)
			(xy 67.243367 -285.445231) (xy 67.269481 -285.493054) (xy 67.288523 -285.544106) (xy 67.300106 -285.597349)
			(xy 67.30141 -285.61558) (xy 68.15259 -285.61558) (xy 68.156481 -285.561224) (xy 68.168069 -285.507976)
			(xy 68.187117 -285.456919) (xy 68.213237 -285.409092) (xy 68.245899 -285.365471) (xy 68.284437 -285.326942)
			(xy 68.328067 -285.29429) (xy 68.375899 -285.26818) (xy 68.42696 -285.249144) (xy 68.480211 -285.237569)
			(xy 68.534568 -285.23369) (xy 68.588923 -285.237588) (xy 68.64217 -285.249182) (xy 68.693224 -285.268236)
			(xy 68.741047 -285.294363) (xy 68.763134 -285.310326) (xy 68.782146 -285.323922) (xy 68.824029 -285.344654)
			(xy 68.868997 -285.35738) (xy 68.915534 -285.36167) (xy 68.962071 -285.35738) (xy 69.007039 -285.344654)
			(xy 69.048922 -285.323922) (xy 69.067934 -285.310326) (xy 69.089989 -285.294323) (xy 69.137815 -285.268203)
			(xy 69.18887 -285.249156) (xy 69.242117 -285.237568) (xy 69.296471 -285.233677) (xy 69.350825 -285.23756)
			(xy 69.404074 -285.249139) (xy 69.455132 -285.268179) (xy 69.502962 -285.294292) (xy 69.546588 -285.326945)
			(xy 69.585122 -285.365475) (xy 69.617782 -285.409097) (xy 69.6439 -285.456923) (xy 69.662947 -285.507979)
			(xy 69.674533 -285.561226) (xy 69.678423 -285.61558) (xy 69.674539 -285.669934) (xy 69.662958 -285.723182)
			(xy 69.643917 -285.77424) (xy 69.617804 -285.822069) (xy 69.585149 -285.865694) (xy 69.546618 -285.904228)
			(xy 69.502996 -285.936886) (xy 69.45517 -285.963004) (xy 69.404113 -285.982049) (xy 69.350866 -285.993634)
			(xy 69.296512 -285.997523) (xy 69.242157 -285.993637) (xy 69.188909 -285.982056) (xy 69.137852 -285.963014)
			(xy 69.090024 -285.936899) (xy 69.067934 -285.920942) (xy 69.048922 -285.907346) (xy 69.007039 -285.886614)
			(xy 68.962071 -285.873888) (xy 68.915534 -285.869598) (xy 68.868997 -285.873888) (xy 68.824029 -285.886614)
			(xy 68.782146 -285.907346) (xy 68.763134 -285.920942) (xy 68.741013 -285.936859) (xy 68.693187 -285.962981)
			(xy 68.642131 -285.98203) (xy 68.588882 -285.993618) (xy 68.534527 -285.99751) (xy 68.480171 -285.993626)
			(xy 68.426921 -285.982045) (xy 68.375862 -285.963003) (xy 68.328032 -285.936888) (xy 68.284406 -285.904232)
			(xy 68.245873 -285.865699) (xy 68.213215 -285.822073) (xy 68.1871 -285.774244) (xy 68.168057 -285.723185)
			(xy 68.156475 -285.669935) (xy 68.15259 -285.61558) (xy 67.30141 -285.61558) (xy 67.303993 -285.651699)
			(xy 67.300106 -285.706048) (xy 67.288524 -285.759291) (xy 67.269482 -285.810344) (xy 67.243369 -285.858167)
			(xy 67.210715 -285.901787) (xy 67.172186 -285.940316) (xy 67.128566 -285.97297) (xy 67.080742 -285.999083)
			(xy 67.02969 -286.018124) (xy 66.976446 -286.029706) (xy 66.922097 -286.033593) (xy 66.867748 -286.029705)
			(xy 66.814505 -286.018123) (xy 66.763452 -285.99908) (xy 66.715629 -285.972966) (xy 66.693542 -285.95701)
			(xy 66.67453 -285.943414) (xy 66.632647 -285.922682) (xy 66.587679 -285.909956) (xy 66.541142 -285.905666)
			(xy 66.494605 -285.909956) (xy 66.449637 -285.922682) (xy 66.407754 -285.943414) (xy 66.388742 -285.95701)
			(xy 66.366651 -285.972971) (xy 66.318823 -285.999098) (xy 66.267763 -286.018152) (xy 66.214511 -286.029745)
			(xy 66.160151 -286.03364) (xy 66.10579 -286.029759) (xy 66.052535 -286.01818) (xy 66.00147 -285.99914)
			(xy 65.953634 -285.973026) (xy 65.910003 -285.940369) (xy 65.871464 -285.901835) (xy 65.838801 -285.858207)
			(xy 65.81268 -285.810375) (xy 65.793633 -285.759313) (xy 65.782048 -285.706059) (xy 65.77816 -285.651699)
			(xy 65.00535 -285.651699) (xy 65.007947 -285.687986) (xy 65.00406 -285.742346) (xy 64.992477 -285.7956)
			(xy 64.973432 -285.846663) (xy 64.947314 -285.894495) (xy 64.914654 -285.938124) (xy 64.876117 -285.97666)
			(xy 64.832488 -286.009319) (xy 64.784654 -286.035436) (xy 64.733591 -286.05448) (xy 64.680336 -286.066062)
			(xy 64.625976 -286.069947) (xy 64.571616 -286.066055) (xy 64.518364 -286.054466) (xy 64.467302 -286.035417)
			(xy 64.419472 -286.009293) (xy 64.397382 -285.993332) (xy 64.37837 -285.979736) (xy 64.336487 -285.959004)
			(xy 64.291519 -285.946278) (xy 64.244982 -285.941988) (xy 64.198445 -285.946278) (xy 64.153477 -285.959004)
			(xy 64.111594 -285.979736) (xy 64.092582 -285.993332) (xy 64.070472 -286.009258) (xy 64.022649 -286.035373)
			(xy 63.971596 -286.054416) (xy 63.918353 -286.065999) (xy 63.864003 -286.069887) (xy 63.809654 -286.066)
			(xy 63.75641 -286.054417) (xy 63.705357 -286.035376) (xy 63.657534 -286.009262) (xy 63.613914 -285.976608)
			(xy 63.575385 -285.938078) (xy 63.542732 -285.894457) (xy 63.51662 -285.846633) (xy 63.497579 -285.795579)
			(xy 63.485999 -285.742335) (xy 63.482113 -285.687986) (xy 62.781323 -285.687986) (xy 62.783942 -285.7246)
			(xy 62.780053 -285.778961) (xy 62.768468 -285.832214) (xy 62.749421 -285.883277) (xy 62.7233 -285.931109)
			(xy 62.690637 -285.974736) (xy 62.652097 -286.013271) (xy 62.608465 -286.045928) (xy 62.56063 -286.072042)
			(xy 62.509565 -286.091082) (xy 62.456309 -286.102661) (xy 62.401948 -286.106542) (xy 62.347588 -286.102646)
			(xy 62.294336 -286.091053) (xy 62.243276 -286.071999) (xy 62.195447 -286.045872) (xy 62.173358 -286.029908)
			(xy 62.154346 -286.016312) (xy 62.112463 -285.99558) (xy 62.067495 -285.982854) (xy 62.020958 -285.978564)
			(xy 61.974421 -285.982854) (xy 61.929453 -285.99558) (xy 61.88757 -286.016312) (xy 61.868558 -286.029908)
			(xy 61.846471 -286.045864) (xy 61.798648 -286.071978) (xy 61.747596 -286.091021) (xy 61.694353 -286.102604)
			(xy 61.640004 -286.106491) (xy 61.585655 -286.102605) (xy 61.532412 -286.091023) (xy 61.481359 -286.071982)
			(xy 61.433536 -286.045869) (xy 61.389916 -286.013216) (xy 61.351387 -285.974687) (xy 61.318733 -285.931067)
			(xy 61.29262 -285.883244) (xy 61.273578 -285.832192) (xy 61.261996 -285.778949) (xy 61.258109 -285.7246)
			(xy 60.252025 -285.7246) (xy 60.248137 -285.778957) (xy 60.236552 -285.832207) (xy 60.217507 -285.883266)
			(xy 60.191389 -285.931095) (xy 60.158729 -285.97472) (xy 60.120193 -286.013252) (xy 60.076565 -286.045908)
			(xy 60.028734 -286.072022) (xy 59.977672 -286.091063) (xy 59.924421 -286.102642) (xy 59.870064 -286.106525)
			(xy 59.815708 -286.102632) (xy 59.762458 -286.091042) (xy 59.711401 -286.071992) (xy 59.663574 -286.045869)
			(xy 59.641486 -286.029908) (xy 59.622474 -286.016312) (xy 59.580591 -285.99558) (xy 59.535623 -285.982854)
			(xy 59.489086 -285.978564) (xy 59.442549 -285.982854) (xy 59.397581 -285.99558) (xy 59.355698 -286.016312)
			(xy 59.336686 -286.029908) (xy 59.314598 -286.045867) (xy 59.266774 -286.071985) (xy 59.215719 -286.091031)
			(xy 59.162473 -286.102618) (xy 59.10812 -286.106508) (xy 59.053767 -286.102623) (xy 59.00052 -286.091043)
			(xy 58.949463 -286.072002) (xy 58.901636 -286.045888) (xy 58.858012 -286.013234) (xy 58.819479 -285.974704)
			(xy 58.786822 -285.931081) (xy 58.760706 -285.883255) (xy 58.741663 -285.832199) (xy 58.730079 -285.778953)
			(xy 58.726192 -285.7246) (xy 52.903628 -285.7246) (xy 52.903628 -286.031432) (xy 51.251612 -286.031432)
			(xy 51.251612 -284.379416) (xy 45.647356 -284.379416) (xy 45.647356 -285.245979) (xy 47.75199 -285.245979)
			(xy 47.75199 -285.164869) (xy 47.75994 -285.08415) (xy 47.775763 -285.004599) (xy 47.799308 -284.926983)
			(xy 47.830347 -284.852047) (xy 47.868582 -284.780515) (xy 47.913644 -284.713075) (xy 47.965099 -284.650376)
			(xy 48.022452 -284.593023) (xy 48.085151 -284.541568) (xy 48.152591 -284.496506) (xy 48.224123 -284.458271)
			(xy 48.299059 -284.427232) (xy 48.376675 -284.403687) (xy 48.456226 -284.387864) (xy 48.536945 -284.379914)
			(xy 48.618055 -284.379914) (xy 48.698774 -284.387864) (xy 48.778325 -284.403687) (xy 48.855941 -284.427232)
			(xy 48.930877 -284.458271) (xy 49.002409 -284.496506) (xy 49.069849 -284.541568) (xy 49.132548 -284.593023)
			(xy 49.189901 -284.650376) (xy 49.241356 -284.713075) (xy 49.286418 -284.780515) (xy 49.324653 -284.852047)
			(xy 49.355692 -284.926983) (xy 49.379237 -285.004599) (xy 49.39506 -285.08415) (xy 49.40301 -285.164869)
			(xy 49.403508 -285.205424) (xy 49.40301 -285.245979) (xy 49.39506 -285.326698) (xy 49.379237 -285.406249)
			(xy 49.355692 -285.483865) (xy 49.324653 -285.558801) (xy 49.286418 -285.630333) (xy 49.241356 -285.697773)
			(xy 49.189901 -285.760472) (xy 49.132548 -285.817825) (xy 49.069849 -285.86928) (xy 49.002409 -285.914342)
			(xy 48.930877 -285.952577) (xy 48.855941 -285.983616) (xy 48.778325 -286.007161) (xy 48.698774 -286.022984)
			(xy 48.618055 -286.030934) (xy 48.536945 -286.030934) (xy 48.456226 -286.022984) (xy 48.376675 -286.007161)
			(xy 48.299059 -285.983616) (xy 48.224123 -285.952577) (xy 48.152591 -285.914342) (xy 48.085151 -285.86928)
			(xy 48.022452 -285.817825) (xy 47.965099 -285.760472) (xy 47.913644 -285.697773) (xy 47.868582 -285.630333)
			(xy 47.830347 -285.558801) (xy 47.799308 -285.483865) (xy 47.775763 -285.406249) (xy 47.75994 -285.326698)
			(xy 47.75199 -285.245979) (xy 45.647356 -285.245979) (xy 45.647356 -286.12744) (xy 82.488514 -286.12744)
			(xy 82.488514 -286.067504) (xy 82.496337 -286.008082) (xy 82.51185 -285.950189) (xy 82.534786 -285.894816)
			(xy 82.564753 -285.84291) (xy 82.60124 -285.79536) (xy 82.64362 -285.75298) (xy 82.69117 -285.716493)
			(xy 82.743076 -285.686526) (xy 82.798449 -285.66359) (xy 82.856342 -285.648077) (xy 82.915764 -285.640254)
			(xy 82.9757 -285.640254) (xy 83.035122 -285.648077) (xy 83.093015 -285.66359) (xy 83.148388 -285.686526)
			(xy 83.200294 -285.716493) (xy 83.247844 -285.75298) (xy 83.290224 -285.79536) (xy 83.326711 -285.84291)
			(xy 83.356678 -285.894816) (xy 83.379614 -285.950189) (xy 83.395127 -286.008082) (xy 83.40295 -286.067504)
			(xy 83.40344 -286.097472) (xy 83.40295 -286.12744) (xy 83.395127 -286.186862) (xy 83.379614 -286.244755)
			(xy 83.356678 -286.300128) (xy 83.326711 -286.352034) (xy 83.290224 -286.399584) (xy 83.247844 -286.441964)
			(xy 83.200294 -286.478451) (xy 83.148388 -286.508418) (xy 83.093015 -286.531354) (xy 83.035122 -286.546867)
			(xy 82.9757 -286.55469) (xy 82.915764 -286.55469) (xy 82.856342 -286.546867) (xy 82.798449 -286.531354)
			(xy 82.743076 -286.508418) (xy 82.69117 -286.478451) (xy 82.64362 -286.441964) (xy 82.60124 -286.399584)
			(xy 82.564753 -286.352034) (xy 82.534786 -286.300128) (xy 82.51185 -286.244755) (xy 82.496337 -286.186862)
			(xy 82.488514 -286.12744) (xy 45.647356 -286.12744) (xy 45.647356 -286.71012) (xy 86.39887 -286.71012)
			(xy 86.402874 -286.510022) (xy 86.414881 -286.310244) (xy 86.434872 -286.111107) (xy 86.462814 -285.912929)
			(xy 86.498662 -285.716027) (xy 86.54236 -285.520718) (xy 86.593837 -285.327313) (xy 86.653011 -285.136123)
			(xy 86.719787 -284.947453) (xy 86.794059 -284.761606) (xy 86.875706 -284.578879) (xy 86.964599 -284.399566)
			(xy 87.060595 -284.223952) (xy 87.16354 -284.05232) (xy 87.27327 -283.884944) (xy 87.389608 -283.722093)
			(xy 87.512369 -283.564026) (xy 87.641356 -283.410998) (xy 87.776363 -283.263253) (xy 87.917172 -283.121027)
			(xy 88.063559 -282.98455) (xy 88.215289 -282.854038) (xy 88.37212 -282.729702) (xy 88.533799 -282.61174)
			(xy 88.700069 -282.500341) (xy 88.870662 -282.395684) (xy 89.045306 -282.297936) (xy 89.223722 -282.207253)
			(xy 89.405622 -282.123782) (xy 89.590717 -282.047655) (xy 89.778709 -281.978995) (xy 89.969298 -281.917911)
			(xy 90.162178 -281.864501) (xy 90.35704 -281.818852) (xy 90.553573 -281.781035) (xy 90.751462 -281.751111)
			(xy 90.950389 -281.729129) (xy 91.150037 -281.715124) (xy 91.350085 -281.709118) (xy 91.550213 -281.71112)
			(xy 91.750101 -281.721128) (xy 91.949428 -281.739125) (xy 92.147876 -281.765083) (xy 92.345126 -281.79896)
			(xy 92.540863 -281.840702) (xy 92.734773 -281.890241) (xy 92.926546 -281.947499) (xy 93.115875 -282.012384)
			(xy 93.302455 -282.084792) (xy 93.48599 -282.164608) (xy 93.666184 -282.251702) (xy 93.842749 -282.345936)
			(xy 94.015402 -282.447159) (xy 94.183867 -282.555209) (xy 94.347875 -282.669912) (xy 94.507162 -282.791086)
			(xy 94.661473 -282.918535) (xy 94.810561 -283.052056) (xy 94.954188 -283.191436) (xy 95.092124 -283.33645)
			(xy 95.224147 -283.486867) (xy 95.350046 -283.642445) (xy 95.46962 -283.802937) (xy 95.582676 -283.968083)
			(xy 95.689035 -284.137621) (xy 95.788526 -284.311279) (xy 95.880989 -284.488778) (xy 95.966276 -284.669834)
			(xy 96.044251 -284.854158) (xy 96.114788 -285.041454) (xy 96.177776 -285.231422) (xy 96.233113 -285.423758)
			(xy 96.28071 -285.618154) (xy 96.320491 -285.814299) (xy 96.352393 -286.011878) (xy 96.376364 -286.210575)
			(xy 96.392366 -286.410073) (xy 96.400373 -286.610051) (xy 96.400874 -286.71012) (xy 96.400373 -286.810189)
			(xy 96.392366 -287.010167) (xy 96.376364 -287.209665) (xy 96.352393 -287.408362) (xy 96.320491 -287.605941)
			(xy 96.28071 -287.802086) (xy 96.233113 -287.996482) (xy 96.177776 -288.188818) (xy 96.114788 -288.378786)
			(xy 96.044251 -288.566082) (xy 95.966276 -288.750406) (xy 95.880989 -288.931462) (xy 95.788526 -289.108961)
			(xy 95.689035 -289.282619) (xy 95.582676 -289.452157) (xy 95.46962 -289.617303) (xy 95.350046 -289.777795)
			(xy 95.224147 -289.933373) (xy 95.092124 -290.08379) (xy 94.954188 -290.228804) (xy 94.810561 -290.368184)
			(xy 94.661473 -290.501705) (xy 94.507162 -290.629154) (xy 94.347875 -290.750328) (xy 94.183867 -290.865031)
			(xy 94.015402 -290.973081) (xy 93.842749 -291.074304) (xy 93.666184 -291.168538) (xy 93.48599 -291.255632)
			(xy 93.302455 -291.335448) (xy 93.115875 -291.407856) (xy 92.926546 -291.472741) (xy 92.734773 -291.529999)
			(xy 92.540863 -291.579538) (xy 92.345126 -291.62128) (xy 92.147876 -291.655157) (xy 91.949428 -291.681115)
			(xy 91.750101 -291.699112) (xy 91.550213 -291.70912) (xy 91.350085 -291.711122) (xy 91.150037 -291.705116)
			(xy 90.950389 -291.691111) (xy 90.751462 -291.669129) (xy 90.553573 -291.639205) (xy 90.35704 -291.601388)
			(xy 90.162178 -291.555739) (xy 89.969298 -291.502329) (xy 89.778709 -291.441245) (xy 89.590717 -291.372585)
			(xy 89.405622 -291.296458) (xy 89.223722 -291.212987) (xy 89.045306 -291.122304) (xy 88.870662 -291.024556)
			(xy 88.700069 -290.919899) (xy 88.533799 -290.8085) (xy 88.37212 -290.690538) (xy 88.215289 -290.566202)
			(xy 88.063559 -290.43569) (xy 87.917172 -290.299213) (xy 87.776363 -290.156987) (xy 87.641356 -290.009242)
			(xy 87.512369 -289.856214) (xy 87.389608 -289.698147) (xy 87.27327 -289.535296) (xy 87.16354 -289.36792)
			(xy 87.060595 -289.196288) (xy 86.964599 -289.020674) (xy 86.875706 -288.841361) (xy 86.794059 -288.658634)
			(xy 86.719787 -288.472787) (xy 86.653011 -288.284117) (xy 86.593837 -288.092927) (xy 86.54236 -287.899522)
			(xy 86.498662 -287.704213) (xy 86.462814 -287.507311) (xy 86.434872 -287.309133) (xy 86.414881 -287.109996)
			(xy 86.402874 -286.910218) (xy 86.39887 -286.71012) (xy 45.647356 -286.71012) (xy 45.647356 -288.395394)
			(xy 58.7262 -288.395394) (xy 58.730088 -288.341042) (xy 58.741672 -288.287797) (xy 58.760716 -288.236743)
			(xy 58.786832 -288.188918) (xy 58.819489 -288.145297) (xy 58.858021 -288.106768) (xy 58.901645 -288.074115)
			(xy 58.949472 -288.048003) (xy 59.000528 -288.028963) (xy 59.053774 -288.017384) (xy 59.108126 -288.0135)
			(xy 59.162478 -288.017391) (xy 59.215722 -288.028978) (xy 59.266776 -288.048025) (xy 59.314599 -288.074143)
			(xy 59.336686 -288.090102) (xy 59.355698 -288.103698) (xy 59.397581 -288.12443) (xy 59.442549 -288.137156)
			(xy 59.489086 -288.141446) (xy 59.535623 -288.137156) (xy 59.580591 -288.12443) (xy 59.622474 -288.103698)
			(xy 59.641486 -288.090102) (xy 59.663565 -288.074127) (xy 59.711392 -288.048003) (xy 59.76245 -288.028952)
			(xy 59.8157 -288.017361) (xy 59.870058 -288.013467) (xy 59.924416 -288.017349) (xy 59.977669 -288.028928)
			(xy 60.028731 -288.047968) (xy 60.076564 -288.074082) (xy 60.120193 -288.106738) (xy 60.158731 -288.14527)
			(xy 60.191392 -288.188895) (xy 60.217512 -288.236725) (xy 60.236558 -288.287785) (xy 60.248144 -288.341036)
			(xy 60.252033 -288.395394) (xy 61.258117 -288.395394) (xy 61.262005 -288.341046) (xy 61.273588 -288.287805)
			(xy 61.29263 -288.236753) (xy 61.318743 -288.188932) (xy 61.351397 -288.145314) (xy 61.389926 -288.106786)
			(xy 61.433546 -288.074135) (xy 61.481368 -288.048023) (xy 61.53242 -288.028983) (xy 61.585662 -288.017402)
			(xy 61.64001 -288.013517) (xy 61.694358 -288.017405) (xy 61.747599 -288.028989) (xy 61.79865 -288.048031)
			(xy 61.846472 -288.074146) (xy 61.868558 -288.090102) (xy 61.88757 -288.103698) (xy 61.929453 -288.12443)
			(xy 61.974421 -288.137156) (xy 62.020958 -288.141446) (xy 62.067495 -288.137156) (xy 62.112463 -288.12443)
			(xy 62.154346 -288.103698) (xy 62.173358 -288.090102) (xy 62.195438 -288.074125) (xy 62.243267 -288.047996)
			(xy 62.294328 -288.028941) (xy 62.347581 -288.017347) (xy 62.401942 -288.01345) (xy 62.456304 -288.01733)
			(xy 62.509561 -288.028908) (xy 62.560628 -288.047948) (xy 62.608465 -288.074062) (xy 62.652098 -288.106719)
			(xy 62.690639 -288.145254) (xy 62.723303 -288.188881) (xy 62.749425 -288.236714) (xy 62.768474 -288.287778)
			(xy 62.78006 -288.341032) (xy 62.78133 -288.35878) (xy 63.482121 -288.35878) (xy 63.486012 -288.304431)
			(xy 63.497597 -288.25119) (xy 63.516642 -288.200139) (xy 63.542758 -288.152318) (xy 63.575414 -288.108701)
			(xy 63.613946 -288.070176) (xy 63.657568 -288.037526) (xy 63.705392 -288.011417) (xy 63.756446 -287.99238)
			(xy 63.809689 -287.980803) (xy 63.864038 -287.976921) (xy 63.918386 -287.980814) (xy 63.971627 -287.992402)
			(xy 64.022677 -288.011449) (xy 64.070497 -288.037568) (xy 64.092582 -288.053526) (xy 64.111594 -288.067122)
			(xy 64.153477 -288.087854) (xy 64.198445 -288.10058) (xy 64.244982 -288.10487) (xy 64.291519 -288.10058)
			(xy 64.336487 -288.087854) (xy 64.37837 -288.067122) (xy 64.397382 -288.053526) (xy 64.419439 -288.037519)
			(xy 64.467267 -288.011391) (xy 64.518328 -287.992336) (xy 64.571581 -287.980742) (xy 64.625941 -287.976845)
			(xy 64.680303 -287.980725) (xy 64.733559 -287.992303) (xy 64.784626 -288.011342) (xy 64.832463 -288.037455)
			(xy 64.876096 -288.070111) (xy 64.914637 -288.108644) (xy 64.947302 -288.152271) (xy 64.973425 -288.200102)
			(xy 64.992475 -288.251165) (xy 65.004063 -288.304419) (xy 65.005357 -288.322493) (xy 65.778168 -288.322493)
			(xy 65.782057 -288.268134) (xy 65.793644 -288.214881) (xy 65.812691 -288.16382) (xy 65.838812 -288.11599)
			(xy 65.871475 -288.072364) (xy 65.910015 -288.033832) (xy 65.953646 -288.001177) (xy 66.001481 -287.975064)
			(xy 66.052545 -287.956025) (xy 66.105799 -287.944448) (xy 66.160159 -287.940568) (xy 66.214518 -287.944465)
			(xy 66.267769 -287.956058) (xy 66.318827 -287.975113) (xy 66.366654 -288.00124) (xy 66.388742 -288.017204)
			(xy 66.407754 -288.0308) (xy 66.449637 -288.051532) (xy 66.494605 -288.064258) (xy 66.541142 -288.068548)
			(xy 66.587679 -288.064258) (xy 66.632647 -288.051532) (xy 66.67453 -288.0308) (xy 66.693542 -288.017204)
			(xy 66.715618 -288.001231) (xy 66.763441 -287.975116) (xy 66.814494 -287.956072) (xy 66.867738 -287.944488)
			(xy 66.922089 -287.940599) (xy 66.976439 -287.944485) (xy 67.029684 -287.956066) (xy 67.080738 -287.975106)
			(xy 67.128563 -288.001219) (xy 67.172185 -288.033872) (xy 67.210716 -288.072401) (xy 67.243371 -288.116021)
			(xy 67.269486 -288.163845) (xy 67.288529 -288.214898) (xy 67.300113 -288.268142) (xy 67.301417 -288.286374)
			(xy 68.152598 -288.286374) (xy 68.15649 -288.232019) (xy 68.168078 -288.178772) (xy 68.187126 -288.127717)
			(xy 68.213247 -288.079892) (xy 68.245909 -288.036271) (xy 68.284447 -287.997744) (xy 68.328076 -287.965093)
			(xy 68.375908 -287.938985) (xy 68.426968 -287.91995) (xy 68.480218 -287.908376) (xy 68.534574 -287.904498)
			(xy 68.588928 -287.908397) (xy 68.642173 -287.919991) (xy 68.693227 -287.939046) (xy 68.741048 -287.965173)
			(xy 68.763134 -287.981136) (xy 68.782146 -287.994732) (xy 68.824029 -288.015464) (xy 68.868997 -288.02819)
			(xy 68.915534 -288.03248) (xy 68.962071 -288.02819) (xy 69.007039 -288.015464) (xy 69.048922 -287.994732)
			(xy 69.067934 -287.981136) (xy 69.08998 -287.96512) (xy 69.137806 -287.938999) (xy 69.188862 -287.91995)
			(xy 69.24211 -287.908361) (xy 69.296465 -287.904469) (xy 69.350821 -287.908351) (xy 69.40407 -287.91993)
			(xy 69.45513 -287.938969) (xy 69.502961 -287.965082) (xy 69.546588 -287.997735) (xy 69.585125 -288.036265)
			(xy 69.617785 -288.079887) (xy 69.643905 -288.127714) (xy 69.662953 -288.178771) (xy 69.67454 -288.232019)
			(xy 69.678431 -288.286374) (xy 69.674548 -288.340729) (xy 69.662967 -288.393979) (xy 69.643927 -288.445038)
			(xy 69.617814 -288.492868) (xy 69.585159 -288.536495) (xy 69.546628 -288.57503) (xy 69.503005 -288.60769)
			(xy 69.455178 -288.633809) (xy 69.404121 -288.652855) (xy 69.350873 -288.664441) (xy 69.296518 -288.668331)
			(xy 69.242162 -288.664446) (xy 69.188913 -288.652865) (xy 69.137854 -288.633823) (xy 69.090025 -288.607709)
			(xy 69.067934 -288.591752) (xy 69.048922 -288.578156) (xy 69.007039 -288.557424) (xy 68.962071 -288.544698)
			(xy 68.915534 -288.540408) (xy 68.868997 -288.544698) (xy 68.824029 -288.557424) (xy 68.782146 -288.578156)
			(xy 68.763134 -288.591752) (xy 68.741004 -288.607655) (xy 68.693179 -288.633776) (xy 68.642123 -288.652824)
			(xy 68.588875 -288.664411) (xy 68.534521 -288.668302) (xy 68.480166 -288.664417) (xy 68.426918 -288.652835)
			(xy 68.37586 -288.633793) (xy 68.328032 -288.607678) (xy 68.284407 -288.575022) (xy 68.245875 -288.536489)
			(xy 68.213219 -288.492864) (xy 68.187104 -288.445035) (xy 68.168063 -288.393977) (xy 68.156482 -288.340728)
			(xy 68.152598 -288.286374) (xy 67.301417 -288.286374) (xy 67.304001 -288.322493) (xy 67.300115 -288.376843)
			(xy 67.288533 -288.430088) (xy 67.269492 -288.481142) (xy 67.243379 -288.528966) (xy 67.210725 -288.572588)
			(xy 67.172196 -288.611118) (xy 67.128575 -288.643773) (xy 67.080751 -288.669888) (xy 67.029698 -288.68893)
			(xy 66.976454 -288.700513) (xy 66.922103 -288.704401) (xy 66.867752 -288.700514) (xy 66.814508 -288.688932)
			(xy 66.763454 -288.66989) (xy 66.71563 -288.643776) (xy 66.693542 -288.62782) (xy 66.67453 -288.614224)
			(xy 66.632647 -288.593492) (xy 66.587679 -288.580766) (xy 66.541142 -288.576476) (xy 66.494605 -288.580766)
			(xy 66.449637 -288.593492) (xy 66.407754 -288.614224) (xy 66.388742 -288.62782) (xy 66.366642 -288.643767)
			(xy 66.318814 -288.669893) (xy 66.267755 -288.688946) (xy 66.214504 -288.700538) (xy 66.160145 -288.704432)
			(xy 66.105785 -288.70055) (xy 66.052531 -288.688971) (xy 66.001467 -288.66993) (xy 65.953634 -288.643816)
			(xy 65.910004 -288.611159) (xy 65.871466 -288.572625) (xy 65.838805 -288.528998) (xy 65.812685 -288.481167)
			(xy 65.793639 -288.430105) (xy 65.782055 -288.376852) (xy 65.778168 -288.322493) (xy 65.005357 -288.322493)
			(xy 65.007955 -288.35878) (xy 65.004069 -288.413141) (xy 64.992486 -288.466396) (xy 64.973442 -288.517461)
			(xy 64.947324 -288.565295) (xy 64.914664 -288.608925) (xy 64.876127 -288.647462) (xy 64.832497 -288.680123)
			(xy 64.784663 -288.706241) (xy 64.733599 -288.725286) (xy 64.680344 -288.736869) (xy 64.625982 -288.740755)
			(xy 64.571621 -288.736864) (xy 64.518367 -288.725276) (xy 64.467305 -288.706226) (xy 64.419473 -288.680103)
			(xy 64.397382 -288.664142) (xy 64.37837 -288.650546) (xy 64.336487 -288.629814) (xy 64.291519 -288.617088)
			(xy 64.244982 -288.612798) (xy 64.198445 -288.617088) (xy 64.153477 -288.629814) (xy 64.111594 -288.650546)
			(xy 64.092582 -288.664142) (xy 64.070462 -288.680055) (xy 64.02264 -288.706168) (xy 63.971588 -288.72521)
			(xy 63.918346 -288.736792) (xy 63.863997 -288.740679) (xy 63.809649 -288.736791) (xy 63.756407 -288.725208)
			(xy 63.705355 -288.706166) (xy 63.657533 -288.680052) (xy 63.613915 -288.647398) (xy 63.575387 -288.608868)
			(xy 63.542736 -288.565247) (xy 63.516625 -288.517424) (xy 63.497585 -288.466371) (xy 63.486006 -288.413128)
			(xy 63.482121 -288.35878) (xy 62.78133 -288.35878) (xy 62.78395 -288.395394) (xy 62.780062 -288.449756)
			(xy 62.768477 -288.503011) (xy 62.74943 -288.554075) (xy 62.72331 -288.601908) (xy 62.690647 -288.645537)
			(xy 62.652107 -288.684073) (xy 62.608475 -288.716731) (xy 62.560639 -288.742847) (xy 62.509573 -288.761888)
			(xy 62.456316 -288.773468) (xy 62.401954 -288.77735) (xy 62.347593 -288.773455) (xy 62.294339 -288.761862)
			(xy 62.243278 -288.742809) (xy 62.195448 -288.716681) (xy 62.173358 -288.700718) (xy 62.154346 -288.687122)
			(xy 62.112463 -288.66639) (xy 62.067495 -288.653664) (xy 62.020958 -288.649374) (xy 61.974421 -288.653664)
			(xy 61.929453 -288.66639) (xy 61.88757 -288.687122) (xy 61.868558 -288.700718) (xy 61.846461 -288.716661)
			(xy 61.798639 -288.742774) (xy 61.747588 -288.761815) (xy 61.694346 -288.773397) (xy 61.639998 -288.777283)
			(xy 61.58565 -288.773396) (xy 61.532409 -288.761814) (xy 61.481357 -288.742772) (xy 61.433535 -288.716659)
			(xy 61.389917 -288.684006) (xy 61.351389 -288.645477) (xy 61.318737 -288.601858) (xy 61.292625 -288.554036)
			(xy 61.273584 -288.502984) (xy 61.262003 -288.449742) (xy 61.258117 -288.395394) (xy 60.252033 -288.395394)
			(xy 60.248146 -288.449752) (xy 60.236562 -288.503003) (xy 60.217517 -288.554064) (xy 60.191399 -288.601894)
			(xy 60.158739 -288.645521) (xy 60.120203 -288.684055) (xy 60.076574 -288.716712) (xy 60.028742 -288.742827)
			(xy 59.97768 -288.761869) (xy 59.924428 -288.773449) (xy 59.87007 -288.777333) (xy 59.815712 -288.773441)
			(xy 59.762462 -288.761852) (xy 59.711403 -288.742802) (xy 59.663575 -288.716679) (xy 59.641486 -288.700718)
			(xy 59.622474 -288.687122) (xy 59.580591 -288.66639) (xy 59.535623 -288.653664) (xy 59.489086 -288.649374)
			(xy 59.442549 -288.653664) (xy 59.397581 -288.66639) (xy 59.355698 -288.687122) (xy 59.336686 -288.700718)
			(xy 59.314589 -288.716663) (xy 59.266765 -288.74278) (xy 59.215711 -288.761825) (xy 59.162466 -288.773411)
			(xy 59.108114 -288.7773) (xy 59.053762 -288.773415) (xy 59.000516 -288.761833) (xy 58.949461 -288.742792)
			(xy 58.901635 -288.716678) (xy 58.858012 -288.684024) (xy 58.819481 -288.645494) (xy 58.786826 -288.601872)
			(xy 58.760711 -288.554047) (xy 58.741669 -288.502991) (xy 58.730086 -288.449746) (xy 58.7262 -288.395394)
			(xy 45.647356 -288.395394) (xy 45.647356 -288.796984) (xy 43.380628 -291.063712) (xy 58.726176 -291.063712)
			(xy 58.730062 -291.009357) (xy 58.741644 -290.956108) (xy 58.760687 -290.905049) (xy 58.786802 -290.85722)
			(xy 58.819459 -290.813595) (xy 58.857992 -290.775062) (xy 58.901617 -290.742405) (xy 58.949445 -290.716289)
			(xy 59.000504 -290.697245) (xy 59.053753 -290.685662) (xy 59.108108 -290.681776) (xy 59.162463 -290.685665)
			(xy 59.215712 -290.69725) (xy 59.266769 -290.716295) (xy 59.314597 -290.742413) (xy 59.336686 -290.758372)
			(xy 59.355698 -290.771968) (xy 59.397581 -290.7927) (xy 59.442549 -290.805426) (xy 59.489086 -290.809716)
			(xy 59.535623 -290.805426) (xy 59.580591 -290.7927) (xy 59.622474 -290.771968) (xy 59.641486 -290.758372)
			(xy 59.663593 -290.742438) (xy 59.711419 -290.716317) (xy 59.762475 -290.69727) (xy 59.815722 -290.685682)
			(xy 59.870076 -290.681791) (xy 59.924431 -290.685675) (xy 59.977679 -290.697256) (xy 60.028738 -290.716298)
			(xy 60.076566 -290.742412) (xy 60.120191 -290.775068) (xy 60.158725 -290.8136) (xy 60.191382 -290.857224)
			(xy 60.217497 -290.905051) (xy 60.23654 -290.956109) (xy 60.248123 -291.009357) (xy 60.252009 -291.063712)
			(xy 61.258093 -291.063712) (xy 61.261978 -291.00936) (xy 61.273559 -290.956115) (xy 61.2926 -290.90506)
			(xy 61.318713 -290.857234) (xy 61.351367 -290.813612) (xy 61.389897 -290.77508) (xy 61.433517 -290.742424)
			(xy 61.481342 -290.716309) (xy 61.532396 -290.697265) (xy 61.585641 -290.685681) (xy 61.639992 -290.681793)
			(xy 61.694344 -290.685679) (xy 61.747589 -290.697261) (xy 61.798644 -290.716302) (xy 61.846469 -290.742416)
			(xy 61.868558 -290.758372) (xy 61.88757 -290.771968) (xy 61.929453 -290.7927) (xy 61.974421 -290.805426)
			(xy 62.020958 -290.809716) (xy 62.067495 -290.805426) (xy 62.112463 -290.7927) (xy 62.154346 -290.771968)
			(xy 62.173358 -290.758372) (xy 62.195466 -290.742435) (xy 62.243293 -290.716311) (xy 62.294352 -290.697259)
			(xy 62.347602 -290.685668) (xy 62.40196 -290.681774) (xy 62.456319 -290.685657) (xy 62.509572 -290.697236)
			(xy 62.560634 -290.716277) (xy 62.608467 -290.742392) (xy 62.652096 -290.775049) (xy 62.690633 -290.813583)
			(xy 62.723293 -290.85721) (xy 62.749411 -290.90504) (xy 62.768456 -290.956102) (xy 62.780039 -291.009354)
			(xy 62.781308 -291.027098) (xy 63.482097 -291.027098) (xy 63.485985 -290.972746) (xy 63.497569 -290.9195)
			(xy 63.516612 -290.868445) (xy 63.542728 -290.82062) (xy 63.575384 -290.776999) (xy 63.613916 -290.738469)
			(xy 63.657539 -290.705816) (xy 63.705366 -290.679703) (xy 63.756422 -290.660662) (xy 63.809668 -290.649082)
			(xy 63.86402 -290.645197) (xy 63.918372 -290.649088) (xy 63.971617 -290.660674) (xy 64.022671 -290.67972)
			(xy 64.070495 -290.705838) (xy 64.092582 -290.721796) (xy 64.111594 -290.735392) (xy 64.153477 -290.756124)
			(xy 64.198445 -290.76885) (xy 64.244982 -290.77314) (xy 64.291519 -290.76885) (xy 64.336487 -290.756124)
			(xy 64.37837 -290.735392) (xy 64.397382 -290.721796) (xy 64.419467 -290.705829) (xy 64.467294 -290.679705)
			(xy 64.518352 -290.660654) (xy 64.571602 -290.649063) (xy 64.625959 -290.645169) (xy 64.680318 -290.649052)
			(xy 64.73357 -290.660631) (xy 64.784632 -290.679671) (xy 64.832465 -290.705785) (xy 64.876094 -290.738441)
			(xy 64.914631 -290.776974) (xy 64.947292 -290.820599) (xy 64.973411 -290.868429) (xy 64.992457 -290.919489)
			(xy 65.004042 -290.97274) (xy 65.005335 -290.990811) (xy 65.778144 -290.990811) (xy 65.782031 -290.936448)
			(xy 65.793615 -290.883192) (xy 65.812662 -290.832127) (xy 65.838782 -290.784292) (xy 65.871445 -290.740662)
			(xy 65.909985 -290.702125) (xy 65.953618 -290.669466) (xy 66.001454 -290.643349) (xy 66.052521 -290.624307)
			(xy 66.105778 -290.612726) (xy 66.160141 -290.608844) (xy 66.214503 -290.612738) (xy 66.267758 -290.62433)
			(xy 66.318821 -290.643383) (xy 66.366652 -290.669511) (xy 66.388742 -290.685474) (xy 66.407754 -290.69907)
			(xy 66.449637 -290.719802) (xy 66.494605 -290.732528) (xy 66.541142 -290.736818) (xy 66.587679 -290.732528)
			(xy 66.632647 -290.719802) (xy 66.67453 -290.69907) (xy 66.693542 -290.685474) (xy 66.715646 -290.669542)
			(xy 66.763468 -290.64343) (xy 66.814518 -290.62439) (xy 66.867759 -290.612809) (xy 66.922107 -290.608923)
			(xy 66.976454 -290.612811) (xy 67.029694 -290.624394) (xy 67.080744 -290.643436) (xy 67.128565 -290.669549)
			(xy 67.172183 -290.702202) (xy 67.210709 -290.740731) (xy 67.24336 -290.78435) (xy 67.269472 -290.832171)
			(xy 67.288511 -290.883222) (xy 67.300091 -290.936464) (xy 67.301394 -290.954692) (xy 68.152574 -290.954692)
			(xy 68.156464 -290.900334) (xy 68.16805 -290.847083) (xy 68.187097 -290.796023) (xy 68.213218 -290.748194)
			(xy 68.245879 -290.704569) (xy 68.284418 -290.666037) (xy 68.328048 -290.633383) (xy 68.375881 -290.60727)
			(xy 68.426944 -290.588232) (xy 68.480197 -290.576654) (xy 68.534556 -290.572774) (xy 68.588913 -290.57667)
			(xy 68.642163 -290.588263) (xy 68.69322 -290.607317) (xy 68.741046 -290.633443) (xy 68.763134 -290.649406)
			(xy 68.782146 -290.663002) (xy 68.824029 -290.683734) (xy 68.868997 -290.69646) (xy 68.915534 -290.70075)
			(xy 68.962071 -290.69646) (xy 69.007039 -290.683734) (xy 69.048922 -290.663002) (xy 69.067934 -290.649406)
			(xy 69.090008 -290.63343) (xy 69.137832 -290.607313) (xy 69.188886 -290.588268) (xy 69.242131 -290.576682)
			(xy 69.296483 -290.572793) (xy 69.350835 -290.576678) (xy 69.404081 -290.588258) (xy 69.455137 -290.607299)
			(xy 69.502963 -290.633412) (xy 69.546586 -290.666065) (xy 69.585118 -290.704595) (xy 69.617775 -290.748216)
			(xy 69.643891 -290.79604) (xy 69.662935 -290.847095) (xy 69.674519 -290.90034) (xy 69.678407 -290.954692)
			(xy 69.674521 -291.009044) (xy 69.662939 -291.062289) (xy 69.643898 -291.113345) (xy 69.617784 -291.16117)
			(xy 69.585129 -291.204793) (xy 69.546599 -291.243324) (xy 69.502977 -291.275979) (xy 69.455152 -291.302094)
			(xy 69.404097 -291.321137) (xy 69.350852 -291.33272) (xy 69.2965 -291.336607) (xy 69.242148 -291.33272)
			(xy 69.188902 -291.321137) (xy 69.137848 -291.302094) (xy 69.090022 -291.275979) (xy 69.067934 -291.260022)
			(xy 69.048922 -291.246426) (xy 69.007039 -291.225694) (xy 68.962071 -291.212968) (xy 68.915534 -291.208678)
			(xy 68.868997 -291.212968) (xy 68.824029 -291.225694) (xy 68.782146 -291.246426) (xy 68.763134 -291.260022)
			(xy 68.741032 -291.275966) (xy 68.693205 -291.30209) (xy 68.642147 -291.321142) (xy 68.588897 -291.332732)
			(xy 68.534539 -291.336626) (xy 68.480181 -291.332743) (xy 68.426928 -291.321164) (xy 68.375866 -291.302123)
			(xy 68.328034 -291.276008) (xy 68.284405 -291.243352) (xy 68.245868 -291.204818) (xy 68.213208 -291.161192)
			(xy 68.18709 -291.113362) (xy 68.168045 -291.062301) (xy 68.156461 -291.00905) (xy 68.152574 -290.954692)
			(xy 67.301394 -290.954692) (xy 67.303977 -290.990811) (xy 67.300088 -291.045158) (xy 67.288505 -291.098398)
			(xy 67.269463 -291.149448) (xy 67.243349 -291.197269) (xy 67.210695 -291.240886) (xy 67.172166 -291.279412)
			(xy 67.128547 -291.312063) (xy 67.080725 -291.338173) (xy 67.029674 -291.357212) (xy 66.976432 -291.368792)
			(xy 66.922085 -291.372677) (xy 66.867738 -291.368788) (xy 66.814498 -291.357204) (xy 66.763448 -291.338161)
			(xy 66.715628 -291.312046) (xy 66.693542 -291.29609) (xy 66.67453 -291.282494) (xy 66.632647 -291.261762)
			(xy 66.587679 -291.249036) (xy 66.541142 -291.244746) (xy 66.494605 -291.249036) (xy 66.449637 -291.261762)
			(xy 66.407754 -291.282494) (xy 66.388742 -291.29609) (xy 66.36667 -291.312078) (xy 66.31884 -291.338208)
			(xy 66.267779 -291.357264) (xy 66.214525 -291.368859) (xy 66.160163 -291.372756) (xy 66.105799 -291.368877)
			(xy 66.052542 -291.357299) (xy 66.001474 -291.33826) (xy 65.953636 -291.312146) (xy 65.910002 -291.279489)
			(xy 65.871459 -291.240954) (xy 65.838794 -291.197326) (xy 65.812671 -291.149493) (xy 65.793622 -291.098429)
			(xy 65.782034 -291.045173) (xy 65.778144 -290.990811) (xy 65.005335 -290.990811) (xy 65.007931 -291.027098)
			(xy 65.004043 -291.081455) (xy 64.992458 -291.134707) (xy 64.973413 -291.185767) (xy 64.947294 -291.233597)
			(xy 64.914634 -291.277223) (xy 64.876097 -291.315756) (xy 64.832469 -291.348412) (xy 64.784637 -291.374527)
			(xy 64.733575 -291.393568) (xy 64.680322 -291.405148) (xy 64.625964 -291.409031) (xy 64.571607 -291.405137)
			(xy 64.518357 -291.393548) (xy 64.467298 -291.374497) (xy 64.419471 -291.348373) (xy 64.397382 -291.332412)
			(xy 64.37837 -291.318816) (xy 64.336487 -291.298084) (xy 64.291519 -291.285358) (xy 64.244982 -291.281068)
			(xy 64.198445 -291.285358) (xy 64.153477 -291.298084) (xy 64.111594 -291.318816) (xy 64.092582 -291.332412)
			(xy 64.07049 -291.348365) (xy 64.022666 -291.374482) (xy 63.971612 -291.393528) (xy 63.918367 -291.405113)
			(xy 63.864015 -291.409003) (xy 63.809663 -291.405117) (xy 63.756417 -291.393536) (xy 63.705362 -291.374495)
			(xy 63.657535 -291.348382) (xy 63.613913 -291.315727) (xy 63.575381 -291.277197) (xy 63.542725 -291.233576)
			(xy 63.51661 -291.18575) (xy 63.497567 -291.134695) (xy 63.485985 -291.08145) (xy 63.482097 -291.027098)
			(xy 62.781308 -291.027098) (xy 62.783926 -291.063712) (xy 62.780036 -291.11807) (xy 62.768449 -291.171321)
			(xy 62.749401 -291.222381) (xy 62.72328 -291.270211) (xy 62.690617 -291.313835) (xy 62.652078 -291.352367)
			(xy 62.608447 -291.385021) (xy 62.560612 -291.411132) (xy 62.509549 -291.43017) (xy 62.456295 -291.441747)
			(xy 62.401936 -291.445626) (xy 62.347578 -291.441728) (xy 62.294329 -291.430134) (xy 62.243271 -291.411079)
			(xy 62.195446 -291.384952) (xy 62.173358 -291.368988) (xy 62.154346 -291.355392) (xy 62.112463 -291.33466)
			(xy 62.067495 -291.321934) (xy 62.020958 -291.317644) (xy 61.974421 -291.321934) (xy 61.929453 -291.33466)
			(xy 61.88757 -291.355392) (xy 61.868558 -291.368988) (xy 61.84649 -291.384971) (xy 61.798666 -291.411088)
			(xy 61.747612 -291.430133) (xy 61.694367 -291.441718) (xy 61.640016 -291.445607) (xy 61.585665 -291.441722)
			(xy 61.532419 -291.430142) (xy 61.481364 -291.411101) (xy 61.433538 -291.384989) (xy 61.389915 -291.352336)
			(xy 61.351383 -291.313807) (xy 61.318726 -291.270186) (xy 61.29261 -291.222362) (xy 61.273566 -291.171308)
			(xy 61.261982 -291.118063) (xy 61.258093 -291.063712) (xy 60.252009 -291.063712) (xy 60.248119 -291.118066)
			(xy 60.236534 -291.171314) (xy 60.217487 -291.222371) (xy 60.191369 -291.270197) (xy 60.158709 -291.313819)
			(xy 60.120173 -291.352348) (xy 60.076546 -291.385001) (xy 60.028716 -291.411112) (xy 59.977656 -291.430151)
			(xy 59.924407 -291.441728) (xy 59.870052 -291.445609) (xy 59.815698 -291.441714) (xy 59.762451 -291.430124)
			(xy 59.711397 -291.411073) (xy 59.663573 -291.384949) (xy 59.641486 -291.368988) (xy 59.622474 -291.355392)
			(xy 59.580591 -291.33466) (xy 59.535623 -291.321934) (xy 59.489086 -291.317644) (xy 59.442549 -291.321934)
			(xy 59.397581 -291.33466) (xy 59.355698 -291.355392) (xy 59.336686 -291.368988) (xy 59.314617 -291.384974)
			(xy 59.266791 -291.411095) (xy 59.215735 -291.430143) (xy 59.162487 -291.441732) (xy 59.108132 -291.445624)
			(xy 59.053776 -291.441741) (xy 59.000527 -291.430162) (xy 58.949467 -291.411121) (xy 58.901637 -291.385008)
			(xy 58.85801 -291.352354) (xy 58.819475 -291.313823) (xy 58.786815 -291.2702) (xy 58.760697 -291.222373)
			(xy 58.741651 -291.171315) (xy 58.730065 -291.118067) (xy 58.726176 -291.063712) (xy 43.380628 -291.063712)
			(xy 39.461948 -294.982392) (xy 29.979874 -294.982392) (xy 29.74721 -295.215056) (xy 29.735821 -295.227188)
			(xy 29.725198 -295.245532) (xy 78.92464 -295.245532) (xy 78.92464 -295.185596) (xy 78.932463 -295.126174)
			(xy 78.947976 -295.068281) (xy 78.970912 -295.012908) (xy 79.000879 -294.961002) (xy 79.037366 -294.913452)
			(xy 79.079746 -294.871072) (xy 79.127296 -294.834585) (xy 79.179202 -294.804618) (xy 79.234575 -294.781682)
			(xy 79.292468 -294.766169) (xy 79.35189 -294.758346) (xy 79.411826 -294.758346) (xy 79.471248 -294.766169)
			(xy 79.529141 -294.781682) (xy 79.584514 -294.804618) (xy 79.63642 -294.834585) (xy 79.68397 -294.871072)
			(xy 79.72635 -294.913452) (xy 79.762837 -294.961002) (xy 79.792804 -295.012908) (xy 79.81574 -295.068281)
			(xy 79.831253 -295.126174) (xy 79.839076 -295.185596) (xy 79.839566 -295.215564) (xy 79.839076 -295.245532)
			(xy 79.831253 -295.304954) (xy 79.81574 -295.362847) (xy 79.792804 -295.41822) (xy 79.762837 -295.470126)
			(xy 79.72635 -295.517676) (xy 79.68397 -295.560056) (xy 79.63642 -295.596543) (xy 79.584514 -295.62651)
			(xy 79.529141 -295.649446) (xy 79.471248 -295.664959) (xy 79.411826 -295.672782) (xy 79.35189 -295.672782)
			(xy 79.292468 -295.664959) (xy 79.234575 -295.649446) (xy 79.179202 -295.62651) (xy 79.127296 -295.596543)
			(xy 79.079746 -295.560056) (xy 79.037366 -295.517676) (xy 79.000879 -295.470126) (xy 78.970912 -295.41822)
			(xy 78.947976 -295.362847) (xy 78.932463 -295.304954) (xy 78.92464 -295.245532) (xy 29.725198 -295.245532)
			(xy 29.719152 -295.255973) (xy 29.710486 -295.288088) (xy 29.709872 -295.304718) (xy 29.709872 -297.922184)
			(xy 78.968074 -297.922184) (xy 78.968074 -297.862248) (xy 78.975897 -297.802826) (xy 78.99141 -297.744933)
			(xy 79.014346 -297.68956) (xy 79.044313 -297.637654) (xy 79.0808 -297.590104) (xy 79.12318 -297.547724)
			(xy 79.17073 -297.511237) (xy 79.222636 -297.48127) (xy 79.278009 -297.458334) (xy 79.335902 -297.442821)
			(xy 79.395324 -297.434998) (xy 79.45526 -297.434998) (xy 79.514682 -297.442821) (xy 79.572575 -297.458334)
			(xy 79.627948 -297.48127) (xy 79.679854 -297.511237) (xy 79.727404 -297.547724) (xy 79.769784 -297.590104)
			(xy 79.806271 -297.637654) (xy 79.836238 -297.68956) (xy 79.859174 -297.744933) (xy 79.874687 -297.802826)
			(xy 79.88251 -297.862248) (xy 79.883 -297.892216) (xy 81.762344 -297.892216) (xy 81.766415 -297.836594)
			(xy 81.778541 -297.782157) (xy 81.798464 -297.730066) (xy 81.82576 -297.681431) (xy 81.859846 -297.637288)
			(xy 81.899995 -297.598579) (xy 81.945353 -297.566128) (xy 81.994953 -297.540627) (xy 82.047737 -297.52262)
			(xy 82.10258 -297.51249) (xy 82.158314 -297.510453) (xy 82.213751 -297.516553) (xy 82.267708 -297.530659)
			(xy 82.319037 -297.552471) (xy 82.366643 -297.581525) (xy 82.409511 -297.6172) (xy 82.446728 -297.658737)
			(xy 82.477501 -297.70525) (xy 82.501173 -297.755747) (xy 82.517241 -297.809154) (xy 82.525361 -297.86433)
			(xy 82.52587 -297.892216) (xy 82.525361 -297.920102) (xy 82.517241 -297.975278) (xy 82.501173 -298.028685)
			(xy 82.477501 -298.079182) (xy 82.446728 -298.125695) (xy 82.409511 -298.167232) (xy 82.366643 -298.202907)
			(xy 82.319037 -298.231961) (xy 82.267708 -298.253773) (xy 82.213751 -298.267879) (xy 82.158314 -298.273979)
			(xy 82.10258 -298.271942) (xy 82.047737 -298.261812) (xy 81.994953 -298.243805) (xy 81.945353 -298.218304)
			(xy 81.899995 -298.185853) (xy 81.859846 -298.147144) (xy 81.82576 -298.103001) (xy 81.798464 -298.054366)
			(xy 81.778541 -298.002275) (xy 81.766415 -297.947838) (xy 81.762344 -297.892216) (xy 79.883 -297.892216)
			(xy 79.88251 -297.922184) (xy 79.874687 -297.981606) (xy 79.859174 -298.039499) (xy 79.836238 -298.094872)
			(xy 79.806271 -298.146778) (xy 79.769784 -298.194328) (xy 79.727404 -298.236708) (xy 79.679854 -298.273195)
			(xy 79.627948 -298.303162) (xy 79.572575 -298.326098) (xy 79.514682 -298.341611) (xy 79.45526 -298.349434)
			(xy 79.395324 -298.349434) (xy 79.335902 -298.341611) (xy 79.278009 -298.326098) (xy 79.222636 -298.303162)
			(xy 79.17073 -298.273195) (xy 79.12318 -298.236708) (xy 79.0808 -298.194328) (xy 79.044313 -298.146778)
			(xy 79.014346 -298.094872) (xy 78.99141 -298.039499) (xy 78.975897 -297.981606) (xy 78.968074 -297.922184)
			(xy 29.709872 -297.922184) (xy 29.709872 -300.851618) (xy 71.800243 -300.851618) (xy 71.804128 -300.797256)
			(xy 71.815712 -300.744) (xy 71.834757 -300.692935) (xy 71.860876 -300.6451) (xy 71.893537 -300.60147)
			(xy 71.932076 -300.562932) (xy 71.975707 -300.530272) (xy 72.023542 -300.504154) (xy 72.074607 -300.48511)
			(xy 72.127864 -300.473527) (xy 72.182226 -300.469643) (xy 72.236588 -300.473535) (xy 72.289842 -300.485124)
			(xy 72.340905 -300.504175) (xy 72.388737 -300.5303) (xy 72.410828 -300.546262) (xy 72.42984 -300.559858)
			(xy 72.471723 -300.58059) (xy 72.516691 -300.593316) (xy 72.563228 -300.597606) (xy 72.609765 -300.593316)
			(xy 72.654733 -300.58059) (xy 72.696616 -300.559858) (xy 72.715628 -300.546262) (xy 72.737744 -300.530345)
			(xy 72.785565 -300.504233) (xy 72.836617 -300.485192) (xy 72.889858 -300.473611) (xy 72.944206 -300.469724)
			(xy 72.998554 -300.473612) (xy 73.051795 -300.485195) (xy 73.102845 -300.504237) (xy 73.150666 -300.530351)
			(xy 73.194284 -300.563005) (xy 73.232811 -300.601534) (xy 73.265462 -300.645154) (xy 73.291572 -300.692976)
			(xy 73.310612 -300.744028) (xy 73.322191 -300.79727) (xy 73.323471 -300.815171) (xy 73.969202 -300.815171)
			(xy 73.973093 -300.760817) (xy 73.984682 -300.707571) (xy 74.00373 -300.656516) (xy 74.029851 -300.608691)
			(xy 74.062513 -300.565072) (xy 74.101051 -300.526545) (xy 74.14468 -300.493895) (xy 74.192511 -300.467787)
			(xy 74.243572 -300.448752) (xy 74.296821 -300.437178) (xy 74.351176 -300.433302) (xy 74.405529 -300.4372)
			(xy 74.458775 -300.448795) (xy 74.509827 -300.46785) (xy 74.557648 -300.493977) (xy 74.579734 -300.50994)
			(xy 74.598746 -300.523536) (xy 74.640629 -300.544268) (xy 74.685597 -300.556994) (xy 74.732134 -300.561284)
			(xy 74.778671 -300.556994) (xy 74.823639 -300.544268) (xy 74.865522 -300.523536) (xy 74.884534 -300.50994)
			(xy 74.906576 -300.493918) (xy 74.954402 -300.467797) (xy 75.005459 -300.448747) (xy 75.058707 -300.437158)
			(xy 75.113062 -300.433265) (xy 75.167419 -300.437148) (xy 75.220669 -300.448726) (xy 75.271729 -300.467765)
			(xy 75.319561 -300.493878) (xy 75.363189 -300.526531) (xy 75.401725 -300.565061) (xy 75.434387 -300.608684)
			(xy 75.460507 -300.65651) (xy 75.479555 -300.707567) (xy 75.491143 -300.760816) (xy 75.495035 -300.815171)
			(xy 75.491151 -300.869527) (xy 75.491136 -300.869598) (xy 75.993578 -300.869598) (xy 75.997467 -300.815241)
			(xy 76.009051 -300.761992) (xy 76.028097 -300.710933) (xy 76.054215 -300.663104) (xy 76.086875 -300.61948)
			(xy 76.125411 -300.580948) (xy 76.169039 -300.548293) (xy 76.21687 -300.52218) (xy 76.267931 -300.50314)
			(xy 76.321182 -300.491561) (xy 76.375538 -300.487678) (xy 76.429894 -300.491572) (xy 76.483143 -300.503161)
			(xy 76.5342 -300.522212) (xy 76.582026 -300.548335) (xy 76.604114 -300.564296) (xy 76.623126 -300.577892)
			(xy 76.665009 -300.598624) (xy 76.709977 -300.61135) (xy 76.756514 -300.61564) (xy 76.803051 -300.61135)
			(xy 76.848019 -300.598624) (xy 76.889902 -300.577892) (xy 76.908914 -300.564296) (xy 76.930998 -300.548332)
			(xy 76.978823 -300.522213) (xy 77.029878 -300.503166) (xy 77.083124 -300.491579) (xy 77.137478 -300.487689)
			(xy 77.191831 -300.491573) (xy 77.245079 -300.503153) (xy 77.296136 -300.522194) (xy 77.343964 -300.548308)
			(xy 77.387589 -300.580962) (xy 77.426122 -300.619493) (xy 77.458779 -300.663115) (xy 77.484895 -300.710941)
			(xy 77.50394 -300.761997) (xy 77.515523 -300.815244) (xy 77.519411 -300.869598) (xy 78.144495 -300.869598)
			(xy 78.148383 -300.815245) (xy 78.159967 -300.761999) (xy 78.17901 -300.710944) (xy 78.205126 -300.663118)
			(xy 78.237783 -300.619497) (xy 78.276316 -300.580967) (xy 78.319939 -300.548313) (xy 78.367766 -300.5222)
			(xy 78.418823 -300.50316) (xy 78.47207 -300.491579) (xy 78.526422 -300.487695) (xy 78.580775 -300.491586)
			(xy 78.63402 -300.503172) (xy 78.685074 -300.522219) (xy 78.732898 -300.548337) (xy 78.754986 -300.564296)
			(xy 78.773998 -300.577892) (xy 78.815881 -300.598624) (xy 78.860849 -300.61135) (xy 78.907386 -300.61564)
			(xy 78.953923 -300.61135) (xy 78.998891 -300.598624) (xy 79.040774 -300.577892) (xy 79.059786 -300.564296)
			(xy 79.081871 -300.548329) (xy 79.129697 -300.522206) (xy 79.180755 -300.503155) (xy 79.234005 -300.491565)
			(xy 79.288362 -300.487672) (xy 79.342719 -300.491554) (xy 79.395971 -300.503134) (xy 79.447033 -300.522174)
			(xy 79.494865 -300.548288) (xy 79.538493 -300.580944) (xy 79.57703 -300.619476) (xy 79.60969 -300.663101)
			(xy 79.635809 -300.71093) (xy 79.654855 -300.76199) (xy 79.66644 -300.81524) (xy 79.670305 -300.86927)
			(xy 80.373797 -300.86927) (xy 80.377689 -300.814915) (xy 80.389278 -300.761667) (xy 80.408327 -300.710611)
			(xy 80.43445 -300.662786) (xy 80.467113 -300.619166) (xy 80.505651 -300.580638) (xy 80.549281 -300.547988)
			(xy 80.597114 -300.52188) (xy 80.648176 -300.502846) (xy 80.701427 -300.491273) (xy 80.755783 -300.487397)
			(xy 80.810137 -300.491297) (xy 80.863383 -300.502893) (xy 80.914437 -300.521949) (xy 80.962258 -300.548078)
			(xy 80.984344 -300.564042) (xy 81.003356 -300.577638) (xy 81.045239 -300.59837) (xy 81.090207 -300.611096)
			(xy 81.136744 -300.615386) (xy 81.183281 -300.611096) (xy 81.228249 -300.59837) (xy 81.270132 -300.577638)
			(xy 81.289144 -300.564042) (xy 81.311184 -300.548018) (xy 81.35901 -300.521898) (xy 81.410066 -300.50285)
			(xy 81.463313 -300.491262) (xy 81.517667 -300.48737) (xy 81.572022 -300.491253) (xy 81.625271 -300.502832)
			(xy 81.67633 -300.521871) (xy 81.72416 -300.547983) (xy 81.767787 -300.580636) (xy 81.806323 -300.619165)
			(xy 81.838983 -300.662787) (xy 81.865103 -300.710612) (xy 81.884151 -300.761669) (xy 81.895738 -300.814916)
			(xy 81.89963 -300.86927) (xy 81.895747 -300.923625) (xy 81.884168 -300.976874) (xy 81.865128 -301.027933)
			(xy 81.839016 -301.075763) (xy 81.806362 -301.119389) (xy 81.767833 -301.157925) (xy 81.724211 -301.190585)
			(xy 81.676385 -301.216704) (xy 81.625329 -301.235752) (xy 81.572081 -301.247339) (xy 81.517727 -301.25123)
			(xy 81.463372 -301.247346) (xy 81.410123 -301.235767) (xy 81.359064 -301.216727) (xy 81.311235 -301.190614)
			(xy 81.289144 -301.174658) (xy 81.270132 -301.161062) (xy 81.228249 -301.14033) (xy 81.183281 -301.127604)
			(xy 81.136744 -301.123314) (xy 81.090207 -301.127604) (xy 81.045239 -301.14033) (xy 81.003356 -301.161062)
			(xy 80.984344 -301.174658) (xy 80.962208 -301.190554) (xy 80.914382 -301.216675) (xy 80.863326 -301.235724)
			(xy 80.810078 -301.247312) (xy 80.755723 -301.251203) (xy 80.701368 -301.247318) (xy 80.648118 -301.235737)
			(xy 80.59706 -301.216695) (xy 80.549231 -301.190579) (xy 80.505606 -301.157922) (xy 80.467073 -301.119389)
			(xy 80.434417 -301.075763) (xy 80.408302 -301.027934) (xy 80.389261 -300.976875) (xy 80.377681 -300.923626)
			(xy 80.373797 -300.86927) (xy 79.670305 -300.86927) (xy 79.670328 -300.869598) (xy 79.666441 -300.923955)
			(xy 79.654856 -300.977206) (xy 79.635811 -301.028265) (xy 79.609693 -301.076095) (xy 79.577033 -301.11972)
			(xy 79.538497 -301.158253) (xy 79.494869 -301.190909) (xy 79.447037 -301.217024) (xy 79.395976 -301.236065)
			(xy 79.342724 -301.247645) (xy 79.288366 -301.251528) (xy 79.234009 -301.247635) (xy 79.18076 -301.236046)
			(xy 79.129702 -301.216996) (xy 79.081875 -301.190873) (xy 79.059786 -301.174912) (xy 79.040774 -301.161316)
			(xy 78.998891 -301.140584) (xy 78.953923 -301.127858) (xy 78.907386 -301.123568) (xy 78.860849 -301.127858)
			(xy 78.815881 -301.140584) (xy 78.773998 -301.161316) (xy 78.754986 -301.174912) (xy 78.732894 -301.190865)
			(xy 78.68507 -301.216983) (xy 78.634016 -301.236029) (xy 78.58077 -301.247615) (xy 78.526418 -301.251505)
			(xy 78.472065 -301.24762) (xy 78.418818 -301.236039) (xy 78.367762 -301.216998) (xy 78.319935 -301.190884)
			(xy 78.276312 -301.15823) (xy 78.23778 -301.1197) (xy 78.205124 -301.076078) (xy 78.179008 -301.028252)
			(xy 78.159965 -300.977196) (xy 78.148382 -300.92395) (xy 78.144495 -300.869598) (xy 77.519411 -300.869598)
			(xy 77.515524 -300.923951) (xy 77.503941 -300.977198) (xy 77.484897 -301.028254) (xy 77.458782 -301.076081)
			(xy 77.426125 -301.119704) (xy 77.387592 -301.158235) (xy 77.343968 -301.19089) (xy 77.296141 -301.217004)
			(xy 77.245083 -301.236045) (xy 77.191836 -301.247626) (xy 77.137482 -301.251511) (xy 77.083129 -301.247621)
			(xy 77.029883 -301.236035) (xy 76.978827 -301.216989) (xy 76.931002 -301.190871) (xy 76.908914 -301.174912)
			(xy 76.889902 -301.161316) (xy 76.848019 -301.140584) (xy 76.803051 -301.127858) (xy 76.756514 -301.123568)
			(xy 76.709977 -301.127858) (xy 76.665009 -301.140584) (xy 76.623126 -301.161316) (xy 76.604114 -301.174912)
			(xy 76.582022 -301.190868) (xy 76.534196 -301.21699) (xy 76.483138 -301.23604) (xy 76.42989 -301.247629)
			(xy 76.375534 -301.251522) (xy 76.321177 -301.247639) (xy 76.267926 -301.236059) (xy 76.216866 -301.217018)
			(xy 76.169035 -301.190904) (xy 76.125407 -301.158248) (xy 76.086872 -301.119716) (xy 76.054213 -301.076091)
			(xy 76.028095 -301.028263) (xy 76.00905 -300.977204) (xy 75.997466 -300.923954) (xy 75.993578 -300.869598)
			(xy 75.491136 -300.869598) (xy 75.479571 -300.922777) (xy 75.460531 -300.973837) (xy 75.434418 -301.021668)
			(xy 75.401763 -301.065295) (xy 75.363232 -301.103831) (xy 75.319609 -301.136491) (xy 75.271782 -301.162611)
			(xy 75.220724 -301.181657) (xy 75.167476 -301.193244) (xy 75.11312 -301.197135) (xy 75.058764 -301.19325)
			(xy 75.005514 -301.181669) (xy 74.954455 -301.162627) (xy 74.906625 -301.136513) (xy 74.884534 -301.120556)
			(xy 74.865522 -301.10696) (xy 74.823639 -301.086228) (xy 74.778671 -301.073502) (xy 74.732134 -301.069212)
			(xy 74.685597 -301.073502) (xy 74.640629 -301.086228) (xy 74.598746 -301.10696) (xy 74.579734 -301.120556)
			(xy 74.5576 -301.136454) (xy 74.509775 -301.162574) (xy 74.458719 -301.181621) (xy 74.405472 -301.193208)
			(xy 74.351119 -301.197098) (xy 74.296764 -301.193213) (xy 74.243516 -301.181632) (xy 74.192459 -301.162589)
			(xy 74.144631 -301.136474) (xy 74.101007 -301.103818) (xy 74.062476 -301.065285) (xy 74.02982 -301.02166)
			(xy 74.003706 -300.973832) (xy 73.984665 -300.922774) (xy 73.973085 -300.869526) (xy 73.969202 -300.815171)
			(xy 73.323471 -300.815171) (xy 73.326076 -300.851618) (xy 73.322186 -300.905965) (xy 73.310601 -300.959206)
			(xy 73.291558 -301.010256) (xy 73.265442 -301.058076) (xy 73.232787 -301.101693) (xy 73.194257 -301.140219)
			(xy 73.150636 -301.172868) (xy 73.102813 -301.198978) (xy 73.05176 -301.218015) (xy 72.998518 -301.229593)
			(xy 72.94417 -301.233476) (xy 72.889823 -301.229584) (xy 72.836582 -301.217998) (xy 72.785533 -301.198952)
			(xy 72.737713 -301.172836) (xy 72.715628 -301.156878) (xy 72.696616 -301.143282) (xy 72.654733 -301.12255)
			(xy 72.609765 -301.109824) (xy 72.563228 -301.105534) (xy 72.516691 -301.109824) (xy 72.471723 -301.12255)
			(xy 72.42984 -301.143282) (xy 72.410828 -301.156878) (xy 72.388767 -301.172881) (xy 72.340938 -301.19901)
			(xy 72.289877 -301.218066) (xy 72.236624 -301.22966) (xy 72.182262 -301.233557) (xy 72.127899 -301.229678)
			(xy 72.074642 -301.218101) (xy 72.023575 -301.199061) (xy 71.975737 -301.172948) (xy 71.932103 -301.140292)
			(xy 71.893561 -301.101758) (xy 71.860895 -301.05813) (xy 71.834772 -301.010298) (xy 71.815722 -300.959235)
			(xy 71.804134 -300.90598) (xy 71.800243 -300.851618) (xy 29.709872 -300.851618) (xy 29.709872 -302.814511)
			(xy 71.800252 -302.814511) (xy 71.804139 -302.76015) (xy 71.815723 -302.706896) (xy 71.834769 -302.655832)
			(xy 71.860888 -302.607999) (xy 71.893549 -302.564371) (xy 71.932087 -302.525835) (xy 71.975718 -302.493176)
			(xy 72.023552 -302.467059) (xy 72.074617 -302.448017) (xy 72.127872 -302.436436) (xy 72.182233 -302.432552)
			(xy 72.236594 -302.436445) (xy 72.289847 -302.448035) (xy 72.340908 -302.467087) (xy 72.388738 -302.493212)
			(xy 72.410828 -302.509174) (xy 72.42984 -302.52277) (xy 72.471723 -302.543502) (xy 72.516691 -302.556228)
			(xy 72.563228 -302.560518) (xy 72.609765 -302.556228) (xy 72.654733 -302.543502) (xy 72.696616 -302.52277)
			(xy 72.715628 -302.509174) (xy 72.737732 -302.493241) (xy 72.785555 -302.467127) (xy 72.836607 -302.448085)
			(xy 72.88985 -302.436502) (xy 72.944199 -302.432615) (xy 72.998548 -302.436502) (xy 73.05179 -302.448084)
			(xy 73.102843 -302.467126) (xy 73.150665 -302.493239) (xy 73.194285 -302.525893) (xy 73.232813 -302.564422)
			(xy 73.265466 -302.608043) (xy 73.291578 -302.655866) (xy 73.310619 -302.706919) (xy 73.3222 -302.760162)
			(xy 73.323491 -302.778224) (xy 73.969131 -302.778224) (xy 73.973016 -302.72386) (xy 73.984599 -302.670602)
			(xy 74.003644 -302.619534) (xy 74.029764 -302.571698) (xy 74.062426 -302.528065) (xy 74.100965 -302.489526)
			(xy 74.144597 -302.456864) (xy 74.192434 -302.430745) (xy 74.243501 -302.411699) (xy 74.296759 -302.400116)
			(xy 74.351123 -302.396231) (xy 74.405487 -302.400123) (xy 74.458744 -302.411713) (xy 74.509809 -302.430764)
			(xy 74.557642 -302.456889) (xy 74.579734 -302.472852) (xy 74.598746 -302.486448) (xy 74.640629 -302.50718)
			(xy 74.685597 -302.519906) (xy 74.732134 -302.524196) (xy 74.778671 -302.519906) (xy 74.823639 -302.50718)
			(xy 74.865522 -302.486448) (xy 74.884534 -302.472852) (xy 74.906659 -302.456949) (xy 74.95448 -302.430839)
			(xy 75.00553 -302.4118) (xy 75.058769 -302.400221) (xy 75.113115 -302.396336) (xy 75.167461 -302.400225)
			(xy 75.2207 -302.411809) (xy 75.271748 -302.430852) (xy 75.319567 -302.456965) (xy 75.363182 -302.489619)
			(xy 75.401707 -302.528147) (xy 75.434356 -302.571766) (xy 75.460465 -302.619588) (xy 75.479502 -302.670638)
			(xy 75.491081 -302.723878) (xy 75.494964 -302.778224) (xy 75.49108 -302.83249) (xy 75.993588 -302.83249)
			(xy 75.997477 -302.778135) (xy 76.009063 -302.724887) (xy 76.028109 -302.67383) (xy 76.054227 -302.626004)
			(xy 76.086887 -302.582381) (xy 76.125423 -302.543851) (xy 76.16905 -302.511198) (xy 76.216881 -302.485086)
			(xy 76.26794 -302.466047) (xy 76.32119 -302.454469) (xy 76.375546 -302.450588) (xy 76.4299 -302.454482)
			(xy 76.483147 -302.466073) (xy 76.534202 -302.485124) (xy 76.582027 -302.511247) (xy 76.604114 -302.527208)
			(xy 76.623126 -302.540804) (xy 76.665009 -302.561536) (xy 76.709977 -302.574262) (xy 76.756514 -302.578552)
			(xy 76.803051 -302.574262) (xy 76.848019 -302.561536) (xy 76.889902 -302.540804) (xy 76.908914 -302.527208)
			(xy 76.930987 -302.511228) (xy 76.978812 -302.485107) (xy 77.029868 -302.466059) (xy 77.083116 -302.454471)
			(xy 77.13747 -302.450579) (xy 77.191825 -302.454463) (xy 77.245075 -302.466042) (xy 77.296134 -302.485082)
			(xy 77.343963 -302.511196) (xy 77.387589 -302.54385) (xy 77.426124 -302.582381) (xy 77.458783 -302.626004)
			(xy 77.484901 -302.673831) (xy 77.503947 -302.724888) (xy 77.515532 -302.778136) (xy 77.519421 -302.83249)
			(xy 78.144505 -302.83249) (xy 78.148393 -302.778139) (xy 78.159978 -302.724895) (xy 78.179022 -302.673841)
			(xy 78.205138 -302.626018) (xy 78.237795 -302.582398) (xy 78.276327 -302.543869) (xy 78.319951 -302.511217)
			(xy 78.367777 -302.485106) (xy 78.418833 -302.466067) (xy 78.472078 -302.454488) (xy 78.52643 -302.450605)
			(xy 78.580781 -302.454496) (xy 78.634024 -302.466084) (xy 78.685077 -302.48513) (xy 78.732899 -302.511249)
			(xy 78.754986 -302.527208) (xy 78.773998 -302.540804) (xy 78.815881 -302.561536) (xy 78.860849 -302.574262)
			(xy 78.907386 -302.578552) (xy 78.953923 -302.574262) (xy 78.998891 -302.561536) (xy 79.040774 -302.540804)
			(xy 79.059786 -302.527208) (xy 79.081859 -302.511225) (xy 79.129687 -302.4851) (xy 79.180746 -302.466048)
			(xy 79.233996 -302.454457) (xy 79.288354 -302.450562) (xy 79.342713 -302.454444) (xy 79.395967 -302.466022)
			(xy 79.44703 -302.485062) (xy 79.494864 -302.511176) (xy 79.538494 -302.543832) (xy 79.577032 -302.582364)
			(xy 79.609694 -302.62599) (xy 79.635815 -302.67382) (xy 79.654862 -302.72488) (xy 79.666448 -302.778132)
			(xy 79.670326 -302.832323) (xy 80.373727 -302.832323) (xy 80.377612 -302.777957) (xy 80.389196 -302.724698)
			(xy 80.408241 -302.67363) (xy 80.434362 -302.625793) (xy 80.467025 -302.58216) (xy 80.505565 -302.54362)
			(xy 80.549199 -302.510958) (xy 80.597037 -302.484838) (xy 80.648105 -302.465793) (xy 80.701365 -302.454211)
			(xy 80.75573 -302.450327) (xy 80.810095 -302.45422) (xy 80.863353 -302.465811) (xy 80.914418 -302.484863)
			(xy 80.962252 -302.51099) (xy 80.984344 -302.526954) (xy 81.003356 -302.54055) (xy 81.045239 -302.561282)
			(xy 81.090207 -302.574008) (xy 81.136744 -302.578298) (xy 81.183281 -302.574008) (xy 81.228249 -302.561282)
			(xy 81.270132 -302.54055) (xy 81.289144 -302.526954) (xy 81.311267 -302.511049) (xy 81.359087 -302.48494)
			(xy 81.410136 -302.465903) (xy 81.463375 -302.454324) (xy 81.51772 -302.45044) (xy 81.572064 -302.45433)
			(xy 81.625302 -302.465914) (xy 81.676349 -302.484957) (xy 81.724167 -302.51107) (xy 81.767781 -302.543724)
			(xy 81.806304 -302.582251) (xy 81.838953 -302.625869) (xy 81.865061 -302.67369) (xy 81.884098 -302.724739)
			(xy 81.895676 -302.777978) (xy 81.89956 -302.832323) (xy 81.89567 -302.886667) (xy 81.884085 -302.939905)
			(xy 81.865042 -302.990952) (xy 81.838928 -303.038769) (xy 81.806275 -303.082383) (xy 81.767746 -303.120906)
			(xy 81.724128 -303.153554) (xy 81.676308 -303.179662) (xy 81.625258 -303.198699) (xy 81.572019 -303.210277)
			(xy 81.517674 -303.21416) (xy 81.46333 -303.210269) (xy 81.410092 -303.198684) (xy 81.359046 -303.179641)
			(xy 81.311228 -303.153526) (xy 81.289144 -303.13757) (xy 81.270132 -303.123974) (xy 81.228249 -303.103242)
			(xy 81.183281 -303.090516) (xy 81.136744 -303.086226) (xy 81.090207 -303.090516) (xy 81.045239 -303.103242)
			(xy 81.003356 -303.123974) (xy 80.984344 -303.13757) (xy 80.96229 -303.153585) (xy 80.91446 -303.179718)
			(xy 80.863396 -303.198777) (xy 80.81014 -303.210374) (xy 80.755776 -303.214273) (xy 80.70141 -303.210395)
			(xy 80.648149 -303.198819) (xy 80.597078 -303.179781) (xy 80.549237 -303.153667) (xy 80.5056 -303.12101)
			(xy 80.467055 -303.082475) (xy 80.434386 -303.038846) (xy 80.40826 -302.991011) (xy 80.389208 -302.939945)
			(xy 80.377619 -302.886688) (xy 80.373727 -302.832323) (xy 79.670326 -302.832323) (xy 79.670338 -302.83249)
			(xy 79.666451 -302.886849) (xy 79.654867 -302.940101) (xy 79.635823 -302.991163) (xy 79.609705 -303.038994)
			(xy 79.577045 -303.082621) (xy 79.538508 -303.121156) (xy 79.49488 -303.153814) (xy 79.447048 -303.17993)
			(xy 79.395985 -303.198972) (xy 79.342733 -303.210553) (xy 79.288374 -303.214438) (xy 79.234015 -303.210546)
			(xy 79.180764 -303.198957) (xy 79.129704 -303.179908) (xy 79.081876 -303.153785) (xy 79.059786 -303.137824)
			(xy 79.040774 -303.124228) (xy 78.998891 -303.103496) (xy 78.953923 -303.09077) (xy 78.907386 -303.08648)
			(xy 78.860849 -303.09077) (xy 78.815881 -303.103496) (xy 78.773998 -303.124228) (xy 78.754986 -303.137824)
			(xy 78.732883 -303.153761) (xy 78.68506 -303.179878) (xy 78.634006 -303.198922) (xy 78.580762 -303.210506)
			(xy 78.52641 -303.214395) (xy 78.472059 -303.210509) (xy 78.418814 -303.198928) (xy 78.367759 -303.179886)
			(xy 78.319934 -303.153773) (xy 78.276313 -303.121118) (xy 78.237782 -303.082588) (xy 78.205128 -303.038966)
			(xy 78.179014 -302.991141) (xy 78.159972 -302.940087) (xy 78.148391 -302.886842) (xy 78.144505 -302.83249)
			(xy 77.519421 -302.83249) (xy 77.515535 -302.886845) (xy 77.503952 -302.940094) (xy 77.484909 -302.991152)
			(xy 77.458794 -303.03898) (xy 77.426137 -303.082605) (xy 77.387604 -303.121137) (xy 77.343979 -303.153794)
			(xy 77.296151 -303.17991) (xy 77.245093 -303.198952) (xy 77.191844 -303.210535) (xy 77.13749 -303.214421)
			(xy 77.083135 -303.210532) (xy 77.029887 -303.198946) (xy 76.97883 -303.179901) (xy 76.931003 -303.153783)
			(xy 76.908914 -303.137824) (xy 76.889902 -303.124228) (xy 76.848019 -303.103496) (xy 76.803051 -303.09077)
			(xy 76.756514 -303.08648) (xy 76.709977 -303.09077) (xy 76.665009 -303.103496) (xy 76.623126 -303.124228)
			(xy 76.604114 -303.137824) (xy 76.58201 -303.153764) (xy 76.534185 -303.179884) (xy 76.483129 -303.198933)
			(xy 76.429881 -303.210521) (xy 76.375526 -303.214412) (xy 76.321171 -303.210528) (xy 76.267922 -303.198948)
			(xy 76.216863 -303.179906) (xy 76.169034 -303.153792) (xy 76.125408 -303.121136) (xy 76.086875 -303.082604)
			(xy 76.054217 -303.03898) (xy 76.028101 -302.991152) (xy 76.009057 -302.940094) (xy 75.997474 -302.886845)
			(xy 75.993588 -302.83249) (xy 75.49108 -302.83249) (xy 75.491074 -302.832569) (xy 75.479489 -302.885808)
			(xy 75.460445 -302.936856) (xy 75.43433 -302.984674) (xy 75.401675 -303.028289) (xy 75.363146 -303.066812)
			(xy 75.319526 -303.099461) (xy 75.271705 -303.125568) (xy 75.220654 -303.144605) (xy 75.167413 -303.156182)
			(xy 75.113067 -303.160064) (xy 75.058722 -303.156173) (xy 75.005484 -303.144586) (xy 74.954436 -303.125541)
			(xy 74.906618 -303.099425) (xy 74.884534 -303.083468) (xy 74.865522 -303.069872) (xy 74.823639 -303.04914)
			(xy 74.778671 -303.036414) (xy 74.732134 -303.032124) (xy 74.685597 -303.036414) (xy 74.640629 -303.04914)
			(xy 74.598746 -303.069872) (xy 74.579734 -303.083468) (xy 74.557683 -303.099485) (xy 74.509852 -303.125616)
			(xy 74.45879 -303.144674) (xy 74.405535 -303.15627) (xy 74.351171 -303.160169) (xy 74.296807 -303.156291)
			(xy 74.243547 -303.144714) (xy 74.192478 -303.125675) (xy 74.144638 -303.099562) (xy 74.101001 -303.066905)
			(xy 74.062457 -303.028371) (xy 74.02979 -302.984743) (xy 74.003664 -302.936909) (xy 73.984613 -302.885844)
			(xy 73.973023 -302.832588) (xy 73.969131 -302.778224) (xy 73.323491 -302.778224) (xy 73.326085 -302.814511)
			(xy 73.322197 -302.86886) (xy 73.310613 -302.922102) (xy 73.291569 -302.973154) (xy 73.265454 -303.020976)
			(xy 73.232799 -303.064594) (xy 73.194269 -303.103121) (xy 73.150647 -303.135772) (xy 73.102823 -303.161883)
			(xy 73.05177 -303.180922) (xy 72.998526 -303.192501) (xy 72.944177 -303.196385) (xy 72.889828 -303.192495)
			(xy 72.836586 -303.180909) (xy 72.785535 -303.161864) (xy 72.737714 -303.135748) (xy 72.715628 -303.11979)
			(xy 72.696616 -303.106194) (xy 72.654733 -303.085462) (xy 72.609765 -303.072736) (xy 72.563228 -303.068446)
			(xy 72.516691 -303.072736) (xy 72.471723 -303.085462) (xy 72.42984 -303.106194) (xy 72.410828 -303.11979)
			(xy 72.388756 -303.135777) (xy 72.340928 -303.161904) (xy 72.289867 -303.180958) (xy 72.236615 -303.192552)
			(xy 72.182255 -303.196448) (xy 72.127893 -303.192567) (xy 72.074638 -303.180989) (xy 72.023572 -303.16195)
			(xy 71.975736 -303.135836) (xy 71.932104 -303.10318) (xy 71.893563 -303.064646) (xy 71.8609 -303.021019)
			(xy 71.834778 -302.973188) (xy 71.815729 -302.922125) (xy 71.804142 -302.868871) (xy 71.800252 -302.814511)
			(xy 29.709872 -302.814511) (xy 29.709872 -304.958007) (xy 71.800257 -304.958007) (xy 71.804144 -304.903647)
			(xy 71.815729 -304.850393) (xy 71.834774 -304.799331) (xy 71.860894 -304.751499) (xy 71.893555 -304.707871)
			(xy 71.932093 -304.669336) (xy 71.975724 -304.636678) (xy 72.023558 -304.610562) (xy 72.074622 -304.59152)
			(xy 72.127876 -304.57994) (xy 72.182237 -304.576057) (xy 72.236596 -304.579951) (xy 72.289849 -304.591541)
			(xy 72.340909 -304.610593) (xy 72.388738 -304.636718) (xy 72.410828 -304.65268) (xy 72.42984 -304.666276)
			(xy 72.471723 -304.687008) (xy 72.516691 -304.699734) (xy 72.563228 -304.704024) (xy 72.609765 -304.699734)
			(xy 72.654733 -304.687008) (xy 72.696616 -304.666276) (xy 72.715628 -304.65268) (xy 72.737727 -304.636739)
			(xy 72.78555 -304.610624) (xy 72.836602 -304.591581) (xy 72.889845 -304.579998) (xy 72.944195 -304.57611)
			(xy 72.998545 -304.579996) (xy 73.051788 -304.591578) (xy 73.102841 -304.61062) (xy 73.150665 -304.636733)
			(xy 73.194285 -304.669387) (xy 73.232814 -304.707916) (xy 73.265468 -304.751537) (xy 73.291581 -304.799361)
			(xy 73.310622 -304.850414) (xy 73.322204 -304.903657) (xy 73.323495 -304.92172) (xy 73.969136 -304.92172)
			(xy 73.973021 -304.867357) (xy 73.984605 -304.8141) (xy 74.00365 -304.763033) (xy 74.02977 -304.715197)
			(xy 74.062432 -304.671566) (xy 74.100971 -304.633027) (xy 74.144603 -304.600366) (xy 74.192439 -304.574247)
			(xy 74.243506 -304.555203) (xy 74.296763 -304.543621) (xy 74.351127 -304.539736) (xy 74.40549 -304.543628)
			(xy 74.458746 -304.555218) (xy 74.50981 -304.57427) (xy 74.557643 -304.600395) (xy 74.579734 -304.616358)
			(xy 74.598746 -304.629954) (xy 74.640629 -304.650686) (xy 74.685597 -304.663412) (xy 74.732134 -304.667702)
			(xy 74.778671 -304.663412) (xy 74.823639 -304.650686) (xy 74.865522 -304.629954) (xy 74.884534 -304.616358)
			(xy 74.906653 -304.600447) (xy 74.954474 -304.574336) (xy 75.005525 -304.555297) (xy 75.058765 -304.543716)
			(xy 75.113112 -304.539831) (xy 75.167458 -304.54372) (xy 75.220698 -304.555303) (xy 75.271747 -304.574346)
			(xy 75.319566 -304.600459) (xy 75.363183 -304.633113) (xy 75.401708 -304.671641) (xy 75.434358 -304.715261)
			(xy 75.460468 -304.763082) (xy 75.479506 -304.814133) (xy 75.491085 -304.867374) (xy 75.494969 -304.92172)
			(xy 75.491085 -304.975987) (xy 75.993593 -304.975987) (xy 75.997482 -304.921633) (xy 76.009068 -304.868385)
			(xy 76.028114 -304.817329) (xy 76.054233 -304.769503) (xy 76.086893 -304.725882) (xy 76.125429 -304.687352)
			(xy 76.169056 -304.6547) (xy 76.216886 -304.628589) (xy 76.267945 -304.609551) (xy 76.321194 -304.597973)
			(xy 76.375549 -304.594093) (xy 76.429903 -304.597987) (xy 76.483149 -304.609578) (xy 76.534204 -304.628629)
			(xy 76.582027 -304.654753) (xy 76.604114 -304.670714) (xy 76.623126 -304.68431) (xy 76.665009 -304.705042)
			(xy 76.709977 -304.717768) (xy 76.756514 -304.722058) (xy 76.803051 -304.717768) (xy 76.848019 -304.705042)
			(xy 76.889902 -304.68431) (xy 76.908914 -304.670714) (xy 76.930981 -304.654726) (xy 76.978807 -304.628604)
			(xy 77.029864 -304.609555) (xy 77.083112 -304.597967) (xy 77.137467 -304.594074) (xy 77.191823 -304.597957)
			(xy 77.245072 -304.609537) (xy 77.296132 -304.628577) (xy 77.343963 -304.65469) (xy 77.38759 -304.687344)
			(xy 77.426126 -304.725875) (xy 77.458785 -304.769498) (xy 77.484904 -304.817325) (xy 77.50395 -304.868383)
			(xy 77.515536 -304.921631) (xy 77.519426 -304.975987) (xy 78.144509 -304.975987) (xy 78.148399 -304.921636)
			(xy 78.159983 -304.868393) (xy 78.179028 -304.81734) (xy 78.205144 -304.769517) (xy 78.237801 -304.725898)
			(xy 78.276333 -304.687371) (xy 78.319956 -304.654719) (xy 78.367782 -304.628609) (xy 78.418837 -304.60957)
			(xy 78.472082 -304.597992) (xy 78.526433 -304.594109) (xy 78.580783 -304.598002) (xy 78.634026 -304.609589)
			(xy 78.685078 -304.628636) (xy 78.7329 -304.654755) (xy 78.754986 -304.670714) (xy 78.773998 -304.68431)
			(xy 78.815881 -304.705042) (xy 78.860849 -304.717768) (xy 78.907386 -304.722058) (xy 78.953923 -304.717768)
			(xy 78.998891 -304.705042) (xy 79.040774 -304.68431) (xy 79.059786 -304.670714) (xy 79.081854 -304.654723)
			(xy 79.129682 -304.628597) (xy 79.180741 -304.609545) (xy 79.233992 -304.597953) (xy 79.288351 -304.594057)
			(xy 79.342711 -304.597939) (xy 79.395965 -304.609517) (xy 79.447029 -304.628556) (xy 79.494863 -304.65467)
			(xy 79.538494 -304.687326) (xy 79.577034 -304.725858) (xy 79.609696 -304.769484) (xy 79.635818 -304.817314)
			(xy 79.654866 -304.868375) (xy 79.666453 -304.921628) (xy 79.670331 -304.975819) (xy 80.373731 -304.975819)
			(xy 80.377617 -304.921454) (xy 80.389201 -304.868196) (xy 80.408247 -304.817129) (xy 80.434368 -304.769292)
			(xy 80.467031 -304.72566) (xy 80.505571 -304.687121) (xy 80.549204 -304.65446) (xy 80.597042 -304.628341)
			(xy 80.64811 -304.609297) (xy 80.701369 -304.597715) (xy 80.755734 -304.593831) (xy 80.810098 -304.597725)
			(xy 80.863355 -304.609316) (xy 80.914419 -304.628369) (xy 80.962252 -304.654496) (xy 80.984344 -304.67046)
			(xy 81.003356 -304.684056) (xy 81.045239 -304.704788) (xy 81.090207 -304.717514) (xy 81.136744 -304.721804)
			(xy 81.183281 -304.717514) (xy 81.228249 -304.704788) (xy 81.270132 -304.684056) (xy 81.289144 -304.67046)
			(xy 81.311261 -304.654547) (xy 81.359082 -304.628437) (xy 81.410131 -304.609399) (xy 81.463371 -304.59782)
			(xy 81.517716 -304.593935) (xy 81.572061 -304.597825) (xy 81.6253 -304.609408) (xy 81.676348 -304.628451)
			(xy 81.724166 -304.654564) (xy 81.767781 -304.687218) (xy 81.806306 -304.725745) (xy 81.838955 -304.769364)
			(xy 81.865064 -304.817184) (xy 81.884102 -304.868234) (xy 81.89568 -304.921474) (xy 81.899565 -304.975819)
			(xy 81.895675 -305.030164) (xy 81.884091 -305.083403) (xy 81.865048 -305.13445) (xy 81.838934 -305.182269)
			(xy 81.80628 -305.225884) (xy 81.767752 -305.264408) (xy 81.724134 -305.297056) (xy 81.676313 -305.323165)
			(xy 81.625263 -305.342202) (xy 81.572023 -305.353781) (xy 81.517678 -305.357665) (xy 81.463333 -305.353775)
			(xy 81.410094 -305.34219) (xy 81.359047 -305.323147) (xy 81.311229 -305.297032) (xy 81.289144 -305.281076)
			(xy 81.270132 -305.26748) (xy 81.228249 -305.246748) (xy 81.183281 -305.234022) (xy 81.136744 -305.229732)
			(xy 81.090207 -305.234022) (xy 81.045239 -305.246748) (xy 81.003356 -305.26748) (xy 80.984344 -305.281076)
			(xy 80.962285 -305.297083) (xy 80.914454 -305.323215) (xy 80.863392 -305.342273) (xy 80.810136 -305.35387)
			(xy 80.755772 -305.357769) (xy 80.701407 -305.35389) (xy 80.648147 -305.342314) (xy 80.597077 -305.323275)
			(xy 80.549237 -305.297161) (xy 80.5056 -305.264504) (xy 80.467056 -305.225969) (xy 80.434388 -305.18234)
			(xy 80.408263 -305.134506) (xy 80.389212 -305.083441) (xy 80.377623 -305.030184) (xy 80.373731 -304.975819)
			(xy 79.670331 -304.975819) (xy 79.670343 -304.975987) (xy 79.666456 -305.030346) (xy 79.654873 -305.083599)
			(xy 79.635829 -305.134662) (xy 79.609711 -305.182494) (xy 79.577051 -305.226122) (xy 79.538514 -305.264657)
			(xy 79.494886 -305.297316) (xy 79.447053 -305.323433) (xy 79.39599 -305.342476) (xy 79.342737 -305.354058)
			(xy 79.288377 -305.357943) (xy 79.234018 -305.354051) (xy 79.180766 -305.342463) (xy 79.129706 -305.323414)
			(xy 79.081876 -305.297291) (xy 79.059786 -305.28133) (xy 79.040774 -305.267734) (xy 78.998891 -305.247002)
			(xy 78.953923 -305.234276) (xy 78.907386 -305.229986) (xy 78.860849 -305.234276) (xy 78.815881 -305.247002)
			(xy 78.773998 -305.267734) (xy 78.754986 -305.28133) (xy 78.732878 -305.297259) (xy 78.685054 -305.323375)
			(xy 78.634001 -305.342418) (xy 78.580757 -305.354002) (xy 78.526407 -305.357891) (xy 78.472056 -305.354004)
			(xy 78.418812 -305.342422) (xy 78.367758 -305.32338) (xy 78.319934 -305.297267) (xy 78.276313 -305.264612)
			(xy 78.237784 -305.226082) (xy 78.20513 -305.182461) (xy 78.179017 -305.134636) (xy 78.159976 -305.083582)
			(xy 78.148395 -305.030337) (xy 78.144509 -304.975987) (xy 77.519426 -304.975987) (xy 77.51554 -305.030342)
			(xy 77.503958 -305.083592) (xy 77.484915 -305.134651) (xy 77.4588 -305.18248) (xy 77.426143 -305.226105)
			(xy 77.38761 -305.264639) (xy 77.343985 -305.297296) (xy 77.296156 -305.323412) (xy 77.245098 -305.342456)
			(xy 77.191849 -305.354039) (xy 77.137493 -305.357926) (xy 77.083138 -305.354037) (xy 77.029889 -305.342452)
			(xy 76.978831 -305.323407) (xy 76.931003 -305.297289) (xy 76.908914 -305.28133) (xy 76.889902 -305.267734)
			(xy 76.848019 -305.247002) (xy 76.803051 -305.234276) (xy 76.756514 -305.229986) (xy 76.709977 -305.234276)
			(xy 76.665009 -305.247002) (xy 76.623126 -305.267734) (xy 76.604114 -305.28133) (xy 76.582005 -305.297261)
			(xy 76.53418 -305.323382) (xy 76.483124 -305.342429) (xy 76.429877 -305.354016) (xy 76.375523 -305.357907)
			(xy 76.321168 -305.354023) (xy 76.26792 -305.342442) (xy 76.216862 -305.3234) (xy 76.169033 -305.297286)
			(xy 76.125409 -305.26463) (xy 76.086876 -305.226098) (xy 76.054219 -305.182475) (xy 76.028103 -305.134647)
			(xy 76.009061 -305.083589) (xy 75.997479 -305.030341) (xy 75.993593 -304.975987) (xy 75.491085 -304.975987)
			(xy 75.491079 -304.976067) (xy 75.479494 -305.029306) (xy 75.460451 -305.080355) (xy 75.434336 -305.128174)
			(xy 75.401681 -305.171789) (xy 75.363152 -305.210314) (xy 75.319532 -305.242963) (xy 75.27171 -305.269071)
			(xy 75.220659 -305.288108) (xy 75.167418 -305.299686) (xy 75.113071 -305.303569) (xy 75.058725 -305.299678)
			(xy 75.005486 -305.288092) (xy 74.954437 -305.269047) (xy 74.906619 -305.242931) (xy 74.884534 -305.226974)
			(xy 74.865522 -305.213378) (xy 74.823639 -305.192646) (xy 74.778671 -305.17992) (xy 74.732134 -305.17563)
			(xy 74.685597 -305.17992) (xy 74.640629 -305.192646) (xy 74.598746 -305.213378) (xy 74.579734 -305.226974)
			(xy 74.557677 -305.242983) (xy 74.509847 -305.269113) (xy 74.458785 -305.28817) (xy 74.405531 -305.299766)
			(xy 74.351168 -305.303664) (xy 74.296804 -305.299785) (xy 74.243545 -305.288209) (xy 74.192476 -305.26917)
			(xy 74.144637 -305.243056) (xy 74.101002 -305.2104) (xy 74.062458 -305.171865) (xy 74.029792 -305.128237)
			(xy 74.003667 -305.080404) (xy 73.984616 -305.02934) (xy 73.973027 -304.976084) (xy 73.969136 -304.92172)
			(xy 73.323495 -304.92172) (xy 73.32609 -304.958007) (xy 73.322202 -305.012357) (xy 73.310618 -305.0656)
			(xy 73.291575 -305.116652) (xy 73.26546 -305.164475) (xy 73.232805 -305.208094) (xy 73.194274 -305.246622)
			(xy 73.150653 -305.279274) (xy 73.102828 -305.305386) (xy 73.051774 -305.324426) (xy 72.998531 -305.336006)
			(xy 72.944181 -305.33989) (xy 72.889831 -305.336) (xy 72.836588 -305.324415) (xy 72.785537 -305.30537)
			(xy 72.737715 -305.279254) (xy 72.715628 -305.263296) (xy 72.696616 -305.2497) (xy 72.654733 -305.228968)
			(xy 72.609765 -305.216242) (xy 72.563228 -305.211952) (xy 72.516691 -305.216242) (xy 72.471723 -305.228968)
			(xy 72.42984 -305.2497) (xy 72.410828 -305.263296) (xy 72.38875 -305.279275) (xy 72.340922 -305.305401)
			(xy 72.289863 -305.324455) (xy 72.236611 -305.336047) (xy 72.182251 -305.339943) (xy 72.127891 -305.336062)
			(xy 72.074636 -305.324484) (xy 72.023571 -305.305444) (xy 71.975736 -305.27933) (xy 71.932104 -305.246674)
			(xy 71.893565 -305.20814) (xy 71.860902 -305.164513) (xy 71.83478 -305.116682) (xy 71.815733 -305.06562)
			(xy 71.804146 -305.012367) (xy 71.800257 -304.958007) (xy 29.709872 -304.958007) (xy 29.709872 -305.557428)
			(xy 51.27498 -305.557428) (xy 52.926996 -305.557428) (xy 52.926996 -307.208936) (xy 51.27498 -307.208936)
			(xy 51.27498 -305.557428) (xy 29.709872 -305.557428) (xy 29.709872 -306.423737) (xy 47.775358 -306.423737)
			(xy 47.775358 -306.342627) (xy 47.783308 -306.261908) (xy 47.799131 -306.182357) (xy 47.822676 -306.104741)
			(xy 47.853715 -306.029805) (xy 47.89195 -305.958273) (xy 47.937012 -305.890833) (xy 47.988467 -305.828134)
			(xy 48.04582 -305.770781) (xy 48.108519 -305.719326) (xy 48.175959 -305.674264) (xy 48.247491 -305.636029)
			(xy 48.322427 -305.60499) (xy 48.400043 -305.581445) (xy 48.479594 -305.565622) (xy 48.560313 -305.557672)
			(xy 48.641423 -305.557672) (xy 48.722142 -305.565622) (xy 48.801693 -305.581445) (xy 48.879309 -305.60499)
			(xy 48.954245 -305.636029) (xy 49.025777 -305.674264) (xy 49.093217 -305.719326) (xy 49.155916 -305.770781)
			(xy 49.213269 -305.828134) (xy 49.264724 -305.890833) (xy 49.309786 -305.958273) (xy 49.348021 -306.029805)
			(xy 49.37906 -306.104741) (xy 49.402605 -306.182357) (xy 49.418428 -306.261908) (xy 49.426378 -306.342627)
			(xy 49.426876 -306.383182) (xy 49.426378 -306.423737) (xy 49.418428 -306.504456) (xy 49.402605 -306.584007)
			(xy 49.37906 -306.661623) (xy 49.348021 -306.736559) (xy 49.309786 -306.808091) (xy 49.264724 -306.875531)
			(xy 49.213269 -306.93823) (xy 49.155916 -306.995583) (xy 49.093217 -307.047038) (xy 49.025777 -307.0921)
			(xy 48.954245 -307.130335) (xy 48.879309 -307.161374) (xy 48.801693 -307.184919) (xy 48.722142 -307.200742)
			(xy 48.641423 -307.208692) (xy 48.560313 -307.208692) (xy 48.479594 -307.200742) (xy 48.400043 -307.184919)
			(xy 48.322427 -307.161374) (xy 48.247491 -307.130335) (xy 48.175959 -307.0921) (xy 48.108519 -307.047038)
			(xy 48.04582 -306.995583) (xy 47.988467 -306.93823) (xy 47.937012 -306.875531) (xy 47.89195 -306.808091)
			(xy 47.853715 -306.736559) (xy 47.822676 -306.661623) (xy 47.799131 -306.584007) (xy 47.783308 -306.504456)
			(xy 47.775358 -306.423737) (xy 29.709872 -306.423737) (xy 29.709872 -318.06007) (xy 39.818564 -318.06007)
			(xy 39.819058 -318.002661) (xy 39.826902 -317.888113) (xy 39.842544 -317.774366) (xy 39.865911 -317.661952)
			(xy 39.896896 -317.551394) (xy 39.935352 -317.443209) (xy 39.981101 -317.3379) (xy 40.03393 -317.235958)
			(xy 40.093592 -317.137859) (xy 40.159809 -317.04406) (xy 40.232272 -316.954998) (xy 40.310645 -316.871089)
			(xy 40.39456 -316.792723) (xy 40.483627 -316.720266) (xy 40.577431 -316.654056) (xy 40.675535 -316.594402)
			(xy 40.777481 -316.541581) (xy 40.882793 -316.495839) (xy 40.990981 -316.457391) (xy 41.101541 -316.426415)
			(xy 41.213957 -316.403056) (xy 41.327705 -316.387423) (xy 41.442254 -316.379588) (xy 41.557072 -316.379588)
			(xy 41.671621 -316.387423) (xy 41.785369 -316.403056) (xy 41.897785 -316.426415) (xy 42.008345 -316.457391)
			(xy 42.116533 -316.495839) (xy 42.221845 -316.541581) (xy 42.323791 -316.594402) (xy 42.421895 -316.654056)
			(xy 42.501239 -316.71006) (xy 63.647577 -316.71006) (xy 63.651612 -316.634356) (xy 63.663671 -316.559511)
			(xy 63.683617 -316.48637) (xy 63.711224 -316.415765) (xy 63.74618 -316.348494) (xy 63.788088 -316.285319)
			(xy 63.836474 -316.226957) (xy 63.89079 -316.174069) (xy 63.950419 -316.127254) (xy 64.014687 -316.087042)
			(xy 64.082864 -316.05389) (xy 64.15418 -316.028172) (xy 64.227825 -316.01018) (xy 64.302965 -316.000118)
			(xy 64.378749 -315.998099) (xy 64.454319 -316.004148) (xy 64.528817 -316.018195) (xy 64.6014 -316.040081)
			(xy 64.671246 -316.069558) (xy 64.737563 -316.106293) (xy 64.799599 -316.149868) (xy 64.856652 -316.19979)
			(xy 64.908076 -316.255494) (xy 64.953287 -316.316349) (xy 64.991774 -316.381664) (xy 65.0231 -316.4507)
			(xy 65.04691 -316.522675) (xy 65.062935 -316.596773) (xy 65.070994 -316.672154) (xy 65.071498 -316.71006)
			(xy 66.187577 -316.71006) (xy 66.191612 -316.634356) (xy 66.203671 -316.559511) (xy 66.223617 -316.48637)
			(xy 66.251224 -316.415765) (xy 66.28618 -316.348494) (xy 66.328088 -316.285319) (xy 66.376474 -316.226957)
			(xy 66.43079 -316.174069) (xy 66.490419 -316.127254) (xy 66.554687 -316.087042) (xy 66.622864 -316.05389)
			(xy 66.69418 -316.028172) (xy 66.767825 -316.01018) (xy 66.842965 -316.000118) (xy 66.918749 -315.998099)
			(xy 66.994319 -316.004148) (xy 67.068817 -316.018195) (xy 67.1414 -316.040081) (xy 67.211246 -316.069558)
			(xy 67.277563 -316.106293) (xy 67.339599 -316.149868) (xy 67.396652 -316.19979) (xy 67.448076 -316.255494)
			(xy 67.493287 -316.316349) (xy 67.531774 -316.381664) (xy 67.5631 -316.4507) (xy 67.58691 -316.522675)
			(xy 67.602935 -316.596773) (xy 67.610994 -316.672154) (xy 67.611498 -316.71006) (xy 68.727577 -316.71006)
			(xy 68.731612 -316.634356) (xy 68.743671 -316.559511) (xy 68.763617 -316.48637) (xy 68.791224 -316.415765)
			(xy 68.82618 -316.348494) (xy 68.868088 -316.285319) (xy 68.916474 -316.226957) (xy 68.97079 -316.174069)
			(xy 69.030419 -316.127254) (xy 69.094687 -316.087042) (xy 69.162864 -316.05389) (xy 69.23418 -316.028172)
			(xy 69.307825 -316.01018) (xy 69.382965 -316.000118) (xy 69.458749 -315.998099) (xy 69.534319 -316.004148)
			(xy 69.608817 -316.018195) (xy 69.6814 -316.040081) (xy 69.751246 -316.069558) (xy 69.817563 -316.106293)
			(xy 69.879599 -316.149868) (xy 69.936652 -316.19979) (xy 69.988076 -316.255494) (xy 70.033287 -316.316349)
			(xy 70.071774 -316.381664) (xy 70.1031 -316.4507) (xy 70.12691 -316.522675) (xy 70.142935 -316.596773)
			(xy 70.150994 -316.672154) (xy 70.151498 -316.71006) (xy 71.267577 -316.71006) (xy 71.271612 -316.634356)
			(xy 71.283671 -316.559511) (xy 71.303617 -316.48637) (xy 71.331224 -316.415765) (xy 71.36618 -316.348494)
			(xy 71.408088 -316.285319) (xy 71.456474 -316.226957) (xy 71.51079 -316.174069) (xy 71.570419 -316.127254)
			(xy 71.634687 -316.087042) (xy 71.702864 -316.05389) (xy 71.77418 -316.028172) (xy 71.847825 -316.01018)
			(xy 71.922965 -316.000118) (xy 71.998749 -315.998099) (xy 72.074319 -316.004148) (xy 72.148817 -316.018195)
			(xy 72.2214 -316.040081) (xy 72.291246 -316.069558) (xy 72.357563 -316.106293) (xy 72.419599 -316.149868)
			(xy 72.476652 -316.19979) (xy 72.528076 -316.255494) (xy 72.573287 -316.316349) (xy 72.611774 -316.381664)
			(xy 72.6431 -316.4507) (xy 72.66691 -316.522675) (xy 72.682935 -316.596773) (xy 72.690994 -316.672154)
			(xy 72.691498 -316.71006) (xy 73.807577 -316.71006) (xy 73.811612 -316.634356) (xy 73.823671 -316.559511)
			(xy 73.843617 -316.48637) (xy 73.871224 -316.415765) (xy 73.90618 -316.348494) (xy 73.948088 -316.285319)
			(xy 73.996474 -316.226957) (xy 74.05079 -316.174069) (xy 74.110419 -316.127254) (xy 74.174687 -316.087042)
			(xy 74.242864 -316.05389) (xy 74.31418 -316.028172) (xy 74.387825 -316.01018) (xy 74.462965 -316.000118)
			(xy 74.538749 -315.998099) (xy 74.614319 -316.004148) (xy 74.688817 -316.018195) (xy 74.7614 -316.040081)
			(xy 74.831246 -316.069558) (xy 74.897563 -316.106293) (xy 74.959599 -316.149868) (xy 75.016652 -316.19979)
			(xy 75.068076 -316.255494) (xy 75.113287 -316.316349) (xy 75.151774 -316.381664) (xy 75.1831 -316.4507)
			(xy 75.20691 -316.522675) (xy 75.222935 -316.596773) (xy 75.230994 -316.672154) (xy 75.231498 -316.71006)
			(xy 76.347577 -316.71006) (xy 76.351612 -316.634356) (xy 76.363671 -316.559511) (xy 76.383617 -316.48637)
			(xy 76.411224 -316.415765) (xy 76.44618 -316.348494) (xy 76.488088 -316.285319) (xy 76.536474 -316.226957)
			(xy 76.59079 -316.174069) (xy 76.650419 -316.127254) (xy 76.714687 -316.087042) (xy 76.782864 -316.05389)
			(xy 76.85418 -316.028172) (xy 76.927825 -316.01018) (xy 77.002965 -316.000118) (xy 77.078749 -315.998099)
			(xy 77.154319 -316.004148) (xy 77.228817 -316.018195) (xy 77.3014 -316.040081) (xy 77.371246 -316.069558)
			(xy 77.437563 -316.106293) (xy 77.499599 -316.149868) (xy 77.556652 -316.19979) (xy 77.608076 -316.255494)
			(xy 77.653287 -316.316349) (xy 77.691774 -316.381664) (xy 77.7231 -316.4507) (xy 77.74691 -316.522675)
			(xy 77.762935 -316.596773) (xy 77.770994 -316.672154) (xy 77.771498 -316.71006) (xy 78.887577 -316.71006)
			(xy 78.891612 -316.634356) (xy 78.903671 -316.559511) (xy 78.923617 -316.48637) (xy 78.951224 -316.415765)
			(xy 78.98618 -316.348494) (xy 79.028088 -316.285319) (xy 79.076474 -316.226957) (xy 79.13079 -316.174069)
			(xy 79.190419 -316.127254) (xy 79.254687 -316.087042) (xy 79.322864 -316.05389) (xy 79.39418 -316.028172)
			(xy 79.467825 -316.01018) (xy 79.542965 -316.000118) (xy 79.618749 -315.998099) (xy 79.694319 -316.004148)
			(xy 79.768817 -316.018195) (xy 79.8414 -316.040081) (xy 79.911246 -316.069558) (xy 79.977563 -316.106293)
			(xy 80.039599 -316.149868) (xy 80.096652 -316.19979) (xy 80.148076 -316.255494) (xy 80.193287 -316.316349)
			(xy 80.231774 -316.381664) (xy 80.2631 -316.4507) (xy 80.28691 -316.522675) (xy 80.302935 -316.596773)
			(xy 80.310994 -316.672154) (xy 80.311498 -316.71006) (xy 81.427577 -316.71006) (xy 81.431612 -316.634356)
			(xy 81.443671 -316.559511) (xy 81.463617 -316.48637) (xy 81.491224 -316.415765) (xy 81.52618 -316.348494)
			(xy 81.568088 -316.285319) (xy 81.616474 -316.226957) (xy 81.67079 -316.174069) (xy 81.730419 -316.127254)
			(xy 81.794687 -316.087042) (xy 81.862864 -316.05389) (xy 81.93418 -316.028172) (xy 82.007825 -316.01018)
			(xy 82.082965 -316.000118) (xy 82.158749 -315.998099) (xy 82.234319 -316.004148) (xy 82.308817 -316.018195)
			(xy 82.3814 -316.040081) (xy 82.451246 -316.069558) (xy 82.517563 -316.106293) (xy 82.579599 -316.149868)
			(xy 82.585544 -316.15507) (xy 86.197697 -316.15507) (xy 86.201732 -316.079366) (xy 86.213791 -316.004521)
			(xy 86.233737 -315.93138) (xy 86.261344 -315.860775) (xy 86.2963 -315.793504) (xy 86.338208 -315.730329)
			(xy 86.386594 -315.671967) (xy 86.44091 -315.619079) (xy 86.500539 -315.572264) (xy 86.564807 -315.532052)
			(xy 86.632984 -315.4989) (xy 86.7043 -315.473182) (xy 86.777945 -315.45519) (xy 86.853085 -315.445128)
			(xy 86.928869 -315.443109) (xy 87.004439 -315.449158) (xy 87.078937 -315.463205) (xy 87.15152 -315.485091)
			(xy 87.221366 -315.514568) (xy 87.287683 -315.551303) (xy 87.349719 -315.594878) (xy 87.406772 -315.6448)
			(xy 87.458196 -315.700504) (xy 87.503407 -315.761359) (xy 87.541894 -315.826674) (xy 87.57322 -315.89571)
			(xy 87.59703 -315.967685) (xy 87.613055 -316.041783) (xy 87.621114 -316.117164) (xy 87.621618 -316.15507)
			(xy 87.621114 -316.192976) (xy 87.613055 -316.268357) (xy 87.59703 -316.342455) (xy 87.57322 -316.41443)
			(xy 87.541894 -316.483466) (xy 87.503407 -316.548781) (xy 87.458196 -316.609636) (xy 87.406772 -316.66534)
			(xy 87.349719 -316.715262) (xy 87.287683 -316.758837) (xy 87.221366 -316.795572) (xy 87.15152 -316.825049)
			(xy 87.078937 -316.846935) (xy 87.004439 -316.860982) (xy 86.928869 -316.867031) (xy 86.853085 -316.865012)
			(xy 86.777945 -316.85495) (xy 86.7043 -316.836958) (xy 86.632984 -316.81124) (xy 86.564807 -316.778088)
			(xy 86.500539 -316.737876) (xy 86.44091 -316.691061) (xy 86.386594 -316.638173) (xy 86.338208 -316.579811)
			(xy 86.2963 -316.516636) (xy 86.261344 -316.449365) (xy 86.233737 -316.37876) (xy 86.213791 -316.305619)
			(xy 86.201732 -316.230774) (xy 86.197697 -316.15507) (xy 82.585544 -316.15507) (xy 82.636652 -316.19979)
			(xy 82.688076 -316.255494) (xy 82.733287 -316.316349) (xy 82.771774 -316.381664) (xy 82.8031 -316.4507)
			(xy 82.82691 -316.522675) (xy 82.842935 -316.596773) (xy 82.850994 -316.672154) (xy 82.851498 -316.71006)
			(xy 82.850994 -316.747966) (xy 82.842935 -316.823347) (xy 82.82691 -316.897445) (xy 82.8031 -316.96942)
			(xy 82.771774 -317.038456) (xy 82.733287 -317.103771) (xy 82.688076 -317.164626) (xy 82.636652 -317.22033)
			(xy 82.579599 -317.270252) (xy 82.517563 -317.313827) (xy 82.451246 -317.350562) (xy 82.3814 -317.380039)
			(xy 82.308817 -317.401925) (xy 82.234319 -317.415972) (xy 82.158749 -317.422021) (xy 82.082965 -317.420002)
			(xy 82.007825 -317.40994) (xy 81.93418 -317.391948) (xy 81.862864 -317.36623) (xy 81.794687 -317.333078)
			(xy 81.730419 -317.292866) (xy 81.67079 -317.246051) (xy 81.616474 -317.193163) (xy 81.568088 -317.134801)
			(xy 81.52618 -317.071626) (xy 81.491224 -317.004355) (xy 81.463617 -316.93375) (xy 81.443671 -316.860609)
			(xy 81.431612 -316.785764) (xy 81.427577 -316.71006) (xy 80.311498 -316.71006) (xy 80.310994 -316.747966)
			(xy 80.302935 -316.823347) (xy 80.28691 -316.897445) (xy 80.2631 -316.96942) (xy 80.231774 -317.038456)
			(xy 80.193287 -317.103771) (xy 80.148076 -317.164626) (xy 80.096652 -317.22033) (xy 80.039599 -317.270252)
			(xy 79.977563 -317.313827) (xy 79.911246 -317.350562) (xy 79.8414 -317.380039) (xy 79.768817 -317.401925)
			(xy 79.694319 -317.415972) (xy 79.618749 -317.422021) (xy 79.542965 -317.420002) (xy 79.467825 -317.40994)
			(xy 79.39418 -317.391948) (xy 79.322864 -317.36623) (xy 79.254687 -317.333078) (xy 79.190419 -317.292866)
			(xy 79.13079 -317.246051) (xy 79.076474 -317.193163) (xy 79.028088 -317.134801) (xy 78.98618 -317.071626)
			(xy 78.951224 -317.004355) (xy 78.923617 -316.93375) (xy 78.903671 -316.860609) (xy 78.891612 -316.785764)
			(xy 78.887577 -316.71006) (xy 77.771498 -316.71006) (xy 77.770994 -316.747966) (xy 77.762935 -316.823347)
			(xy 77.74691 -316.897445) (xy 77.7231 -316.96942) (xy 77.691774 -317.038456) (xy 77.653287 -317.103771)
			(xy 77.608076 -317.164626) (xy 77.556652 -317.22033) (xy 77.499599 -317.270252) (xy 77.437563 -317.313827)
			(xy 77.371246 -317.350562) (xy 77.3014 -317.380039) (xy 77.228817 -317.401925) (xy 77.154319 -317.415972)
			(xy 77.078749 -317.422021) (xy 77.002965 -317.420002) (xy 76.927825 -317.40994) (xy 76.85418 -317.391948)
			(xy 76.782864 -317.36623) (xy 76.714687 -317.333078) (xy 76.650419 -317.292866) (xy 76.59079 -317.246051)
			(xy 76.536474 -317.193163) (xy 76.488088 -317.134801) (xy 76.44618 -317.071626) (xy 76.411224 -317.004355)
			(xy 76.383617 -316.93375) (xy 76.363671 -316.860609) (xy 76.351612 -316.785764) (xy 76.347577 -316.71006)
			(xy 75.231498 -316.71006) (xy 75.230994 -316.747966) (xy 75.222935 -316.823347) (xy 75.20691 -316.897445)
			(xy 75.1831 -316.96942) (xy 75.151774 -317.038456) (xy 75.113287 -317.103771) (xy 75.068076 -317.164626)
			(xy 75.016652 -317.22033) (xy 74.959599 -317.270252) (xy 74.897563 -317.313827) (xy 74.831246 -317.350562)
			(xy 74.7614 -317.380039) (xy 74.688817 -317.401925) (xy 74.614319 -317.415972) (xy 74.538749 -317.422021)
			(xy 74.462965 -317.420002) (xy 74.387825 -317.40994) (xy 74.31418 -317.391948) (xy 74.242864 -317.36623)
			(xy 74.174687 -317.333078) (xy 74.110419 -317.292866) (xy 74.05079 -317.246051) (xy 73.996474 -317.193163)
			(xy 73.948088 -317.134801) (xy 73.90618 -317.071626) (xy 73.871224 -317.004355) (xy 73.843617 -316.93375)
			(xy 73.823671 -316.860609) (xy 73.811612 -316.785764) (xy 73.807577 -316.71006) (xy 72.691498 -316.71006)
			(xy 72.690994 -316.747966) (xy 72.682935 -316.823347) (xy 72.66691 -316.897445) (xy 72.6431 -316.96942)
			(xy 72.611774 -317.038456) (xy 72.573287 -317.103771) (xy 72.528076 -317.164626) (xy 72.476652 -317.22033)
			(xy 72.419599 -317.270252) (xy 72.357563 -317.313827) (xy 72.291246 -317.350562) (xy 72.2214 -317.380039)
			(xy 72.148817 -317.401925) (xy 72.074319 -317.415972) (xy 71.998749 -317.422021) (xy 71.922965 -317.420002)
			(xy 71.847825 -317.40994) (xy 71.77418 -317.391948) (xy 71.702864 -317.36623) (xy 71.634687 -317.333078)
			(xy 71.570419 -317.292866) (xy 71.51079 -317.246051) (xy 71.456474 -317.193163) (xy 71.408088 -317.134801)
			(xy 71.36618 -317.071626) (xy 71.331224 -317.004355) (xy 71.303617 -316.93375) (xy 71.283671 -316.860609)
			(xy 71.271612 -316.785764) (xy 71.267577 -316.71006) (xy 70.151498 -316.71006) (xy 70.150994 -316.747966)
			(xy 70.142935 -316.823347) (xy 70.12691 -316.897445) (xy 70.1031 -316.96942) (xy 70.071774 -317.038456)
			(xy 70.033287 -317.103771) (xy 69.988076 -317.164626) (xy 69.936652 -317.22033) (xy 69.879599 -317.270252)
			(xy 69.817563 -317.313827) (xy 69.751246 -317.350562) (xy 69.6814 -317.380039) (xy 69.608817 -317.401925)
			(xy 69.534319 -317.415972) (xy 69.458749 -317.422021) (xy 69.382965 -317.420002) (xy 69.307825 -317.40994)
			(xy 69.23418 -317.391948) (xy 69.162864 -317.36623) (xy 69.094687 -317.333078) (xy 69.030419 -317.292866)
			(xy 68.97079 -317.246051) (xy 68.916474 -317.193163) (xy 68.868088 -317.134801) (xy 68.82618 -317.071626)
			(xy 68.791224 -317.004355) (xy 68.763617 -316.93375) (xy 68.743671 -316.860609) (xy 68.731612 -316.785764)
			(xy 68.727577 -316.71006) (xy 67.611498 -316.71006) (xy 67.610994 -316.747966) (xy 67.602935 -316.823347)
			(xy 67.58691 -316.897445) (xy 67.5631 -316.96942) (xy 67.531774 -317.038456) (xy 67.493287 -317.103771)
			(xy 67.448076 -317.164626) (xy 67.396652 -317.22033) (xy 67.339599 -317.270252) (xy 67.277563 -317.313827)
			(xy 67.211246 -317.350562) (xy 67.1414 -317.380039) (xy 67.068817 -317.401925) (xy 66.994319 -317.415972)
			(xy 66.918749 -317.422021) (xy 66.842965 -317.420002) (xy 66.767825 -317.40994) (xy 66.69418 -317.391948)
			(xy 66.622864 -317.36623) (xy 66.554687 -317.333078) (xy 66.490419 -317.292866) (xy 66.43079 -317.246051)
			(xy 66.376474 -317.193163) (xy 66.328088 -317.134801) (xy 66.28618 -317.071626) (xy 66.251224 -317.004355)
			(xy 66.223617 -316.93375) (xy 66.203671 -316.860609) (xy 66.191612 -316.785764) (xy 66.187577 -316.71006)
			(xy 65.071498 -316.71006) (xy 65.070994 -316.747966) (xy 65.062935 -316.823347) (xy 65.04691 -316.897445)
			(xy 65.0231 -316.96942) (xy 64.991774 -317.038456) (xy 64.953287 -317.103771) (xy 64.908076 -317.164626)
			(xy 64.856652 -317.22033) (xy 64.799599 -317.270252) (xy 64.737563 -317.313827) (xy 64.671246 -317.350562)
			(xy 64.6014 -317.380039) (xy 64.528817 -317.401925) (xy 64.454319 -317.415972) (xy 64.378749 -317.422021)
			(xy 64.302965 -317.420002) (xy 64.227825 -317.40994) (xy 64.15418 -317.391948) (xy 64.082864 -317.36623)
			(xy 64.014687 -317.333078) (xy 63.950419 -317.292866) (xy 63.89079 -317.246051) (xy 63.836474 -317.193163)
			(xy 63.788088 -317.134801) (xy 63.74618 -317.071626) (xy 63.711224 -317.004355) (xy 63.683617 -316.93375)
			(xy 63.663671 -316.860609) (xy 63.651612 -316.785764) (xy 63.647577 -316.71006) (xy 42.501239 -316.71006)
			(xy 42.515699 -316.720266) (xy 42.604766 -316.792723) (xy 42.688681 -316.871089) (xy 42.767054 -316.954998)
			(xy 42.839517 -317.04406) (xy 42.905734 -317.137859) (xy 42.965396 -317.235958) (xy 43.018225 -317.3379)
			(xy 43.056094 -317.42507) (xy 84.927697 -317.42507) (xy 84.931732 -317.349366) (xy 84.943791 -317.274521)
			(xy 84.963737 -317.20138) (xy 84.991344 -317.130775) (xy 85.0263 -317.063504) (xy 85.068208 -317.000329)
			(xy 85.116594 -316.941967) (xy 85.17091 -316.889079) (xy 85.230539 -316.842264) (xy 85.294807 -316.802052)
			(xy 85.362984 -316.7689) (xy 85.4343 -316.743182) (xy 85.507945 -316.72519) (xy 85.583085 -316.715128)
			(xy 85.658869 -316.713109) (xy 85.734439 -316.719158) (xy 85.808937 -316.733205) (xy 85.88152 -316.755091)
			(xy 85.951366 -316.784568) (xy 86.017683 -316.821303) (xy 86.079719 -316.864878) (xy 86.136772 -316.9148)
			(xy 86.188196 -316.970504) (xy 86.233407 -317.031359) (xy 86.271894 -317.096674) (xy 86.30322 -317.16571)
			(xy 86.32703 -317.237685) (xy 86.343055 -317.311783) (xy 86.351114 -317.387164) (xy 86.351618 -317.42507)
			(xy 86.351114 -317.462976) (xy 86.343055 -317.538357) (xy 86.32703 -317.612455) (xy 86.30322 -317.68443)
			(xy 86.271894 -317.753466) (xy 86.233407 -317.818781) (xy 86.188196 -317.879636) (xy 86.136772 -317.93534)
			(xy 86.079719 -317.985262) (xy 86.017683 -318.028837) (xy 85.951366 -318.065572) (xy 85.88152 -318.095049)
			(xy 85.808937 -318.116935) (xy 85.734439 -318.130982) (xy 85.658869 -318.137031) (xy 85.583085 -318.135012)
			(xy 85.507945 -318.12495) (xy 85.4343 -318.106958) (xy 85.362984 -318.08124) (xy 85.294807 -318.048088)
			(xy 85.230539 -318.007876) (xy 85.17091 -317.961061) (xy 85.116594 -317.908173) (xy 85.068208 -317.849811)
			(xy 85.0263 -317.786636) (xy 84.991344 -317.719365) (xy 84.963737 -317.64876) (xy 84.943791 -317.575619)
			(xy 84.931732 -317.500774) (xy 84.927697 -317.42507) (xy 43.056094 -317.42507) (xy 43.063974 -317.443209)
			(xy 43.10243 -317.551394) (xy 43.133415 -317.661952) (xy 43.156782 -317.774366) (xy 43.172424 -317.888113)
			(xy 43.180268 -318.002661) (xy 43.180762 -318.06007) (xy 43.180576 -318.093253) (xy 43.177909 -318.159567)
			(xy 43.175428 -318.192658) (xy 43.170272 -318.250942) (xy 43.152948 -318.366671) (xy 43.127616 -318.480914)
			(xy 43.094401 -318.593119) (xy 43.056327 -318.69507) (xy 86.197697 -318.69507) (xy 86.201732 -318.619366)
			(xy 86.213791 -318.544521) (xy 86.233737 -318.47138) (xy 86.261344 -318.400775) (xy 86.2963 -318.333504)
			(xy 86.338208 -318.270329) (xy 86.386594 -318.211967) (xy 86.44091 -318.159079) (xy 86.500539 -318.112264)
			(xy 86.564807 -318.072052) (xy 86.632984 -318.0389) (xy 86.7043 -318.013182) (xy 86.777945 -317.99519)
			(xy 86.853085 -317.985128) (xy 86.928869 -317.983109) (xy 87.004439 -317.989158) (xy 87.078937 -318.003205)
			(xy 87.15152 -318.025091) (xy 87.221366 -318.054568) (xy 87.287683 -318.091303) (xy 87.349719 -318.134878)
			(xy 87.406772 -318.1848) (xy 87.458196 -318.240504) (xy 87.503407 -318.301359) (xy 87.541894 -318.366674)
			(xy 87.57322 -318.43571) (xy 87.59703 -318.507685) (xy 87.613055 -318.581783) (xy 87.621114 -318.657164)
			(xy 87.621618 -318.69507) (xy 87.621114 -318.732976) (xy 87.613055 -318.808357) (xy 87.59703 -318.882455)
			(xy 87.57322 -318.95443) (xy 87.541894 -319.023466) (xy 87.503407 -319.088781) (xy 87.458196 -319.149636)
			(xy 87.406772 -319.20534) (xy 87.349719 -319.255262) (xy 87.287683 -319.298837) (xy 87.221366 -319.335572)
			(xy 87.15152 -319.365049) (xy 87.078937 -319.386935) (xy 87.004439 -319.400982) (xy 86.928869 -319.407031)
			(xy 86.853085 -319.405012) (xy 86.777945 -319.39495) (xy 86.7043 -319.376958) (xy 86.632984 -319.35124)
			(xy 86.564807 -319.318088) (xy 86.500539 -319.277876) (xy 86.44091 -319.231061) (xy 86.386594 -319.178173)
			(xy 86.338208 -319.119811) (xy 86.2963 -319.056636) (xy 86.261344 -318.989365) (xy 86.233737 -318.91876)
			(xy 86.213791 -318.845619) (xy 86.201732 -318.770774) (xy 86.197697 -318.69507) (xy 43.056327 -318.69507)
			(xy 43.053462 -318.702742) (xy 43.004999 -318.809253) (xy 42.949245 -318.912135) (xy 42.886471 -319.010891)
			(xy 42.816981 -319.105042) (xy 42.741111 -319.194132) (xy 42.659229 -319.277729) (xy 42.571732 -319.35543)
			(xy 42.500813 -319.41008) (xy 63.647577 -319.41008) (xy 63.651612 -319.334376) (xy 63.663671 -319.259531)
			(xy 63.683617 -319.18639) (xy 63.711224 -319.115785) (xy 63.74618 -319.048514) (xy 63.788088 -318.985339)
			(xy 63.836474 -318.926977) (xy 63.89079 -318.874089) (xy 63.950419 -318.827274) (xy 64.014687 -318.787062)
			(xy 64.082864 -318.75391) (xy 64.15418 -318.728192) (xy 64.227825 -318.7102) (xy 64.302965 -318.700138)
			(xy 64.378749 -318.698119) (xy 64.454319 -318.704168) (xy 64.528817 -318.718215) (xy 64.6014 -318.740101)
			(xy 64.671246 -318.769578) (xy 64.737563 -318.806313) (xy 64.799599 -318.849888) (xy 64.856652 -318.89981)
			(xy 64.908076 -318.955514) (xy 64.953287 -319.016369) (xy 64.991774 -319.081684) (xy 65.0231 -319.15072)
			(xy 65.04691 -319.222695) (xy 65.062935 -319.296793) (xy 65.070994 -319.372174) (xy 65.071498 -319.41008)
			(xy 66.187577 -319.41008) (xy 66.191612 -319.334376) (xy 66.203671 -319.259531) (xy 66.223617 -319.18639)
			(xy 66.251224 -319.115785) (xy 66.28618 -319.048514) (xy 66.328088 -318.985339) (xy 66.376474 -318.926977)
			(xy 66.43079 -318.874089) (xy 66.490419 -318.827274) (xy 66.554687 -318.787062) (xy 66.622864 -318.75391)
			(xy 66.69418 -318.728192) (xy 66.767825 -318.7102) (xy 66.842965 -318.700138) (xy 66.918749 -318.698119)
			(xy 66.994319 -318.704168) (xy 67.068817 -318.718215) (xy 67.1414 -318.740101) (xy 67.211246 -318.769578)
			(xy 67.277563 -318.806313) (xy 67.339599 -318.849888) (xy 67.396652 -318.89981) (xy 67.448076 -318.955514)
			(xy 67.493287 -319.016369) (xy 67.531774 -319.081684) (xy 67.5631 -319.15072) (xy 67.58691 -319.222695)
			(xy 67.602935 -319.296793) (xy 67.610994 -319.372174) (xy 67.611498 -319.41008) (xy 68.727577 -319.41008)
			(xy 68.731612 -319.334376) (xy 68.743671 -319.259531) (xy 68.763617 -319.18639) (xy 68.791224 -319.115785)
			(xy 68.82618 -319.048514) (xy 68.868088 -318.985339) (xy 68.916474 -318.926977) (xy 68.97079 -318.874089)
			(xy 69.030419 -318.827274) (xy 69.094687 -318.787062) (xy 69.162864 -318.75391) (xy 69.23418 -318.728192)
			(xy 69.307825 -318.7102) (xy 69.382965 -318.700138) (xy 69.458749 -318.698119) (xy 69.534319 -318.704168)
			(xy 69.608817 -318.718215) (xy 69.6814 -318.740101) (xy 69.751246 -318.769578) (xy 69.817563 -318.806313)
			(xy 69.879599 -318.849888) (xy 69.936652 -318.89981) (xy 69.988076 -318.955514) (xy 70.033287 -319.016369)
			(xy 70.071774 -319.081684) (xy 70.1031 -319.15072) (xy 70.12691 -319.222695) (xy 70.142935 -319.296793)
			(xy 70.150994 -319.372174) (xy 70.151498 -319.41008) (xy 71.267577 -319.41008) (xy 71.271612 -319.334376)
			(xy 71.283671 -319.259531) (xy 71.303617 -319.18639) (xy 71.331224 -319.115785) (xy 71.36618 -319.048514)
			(xy 71.408088 -318.985339) (xy 71.456474 -318.926977) (xy 71.51079 -318.874089) (xy 71.570419 -318.827274)
			(xy 71.634687 -318.787062) (xy 71.702864 -318.75391) (xy 71.77418 -318.728192) (xy 71.847825 -318.7102)
			(xy 71.922965 -318.700138) (xy 71.998749 -318.698119) (xy 72.074319 -318.704168) (xy 72.148817 -318.718215)
			(xy 72.2214 -318.740101) (xy 72.291246 -318.769578) (xy 72.357563 -318.806313) (xy 72.419599 -318.849888)
			(xy 72.476652 -318.89981) (xy 72.528076 -318.955514) (xy 72.573287 -319.016369) (xy 72.611774 -319.081684)
			(xy 72.6431 -319.15072) (xy 72.66691 -319.222695) (xy 72.682935 -319.296793) (xy 72.690994 -319.372174)
			(xy 72.691498 -319.41008) (xy 73.807577 -319.41008) (xy 73.811612 -319.334376) (xy 73.823671 -319.259531)
			(xy 73.843617 -319.18639) (xy 73.871224 -319.115785) (xy 73.90618 -319.048514) (xy 73.948088 -318.985339)
			(xy 73.996474 -318.926977) (xy 74.05079 -318.874089) (xy 74.110419 -318.827274) (xy 74.174687 -318.787062)
			(xy 74.242864 -318.75391) (xy 74.31418 -318.728192) (xy 74.387825 -318.7102) (xy 74.462965 -318.700138)
			(xy 74.538749 -318.698119) (xy 74.614319 -318.704168) (xy 74.688817 -318.718215) (xy 74.7614 -318.740101)
			(xy 74.831246 -318.769578) (xy 74.897563 -318.806313) (xy 74.959599 -318.849888) (xy 75.016652 -318.89981)
			(xy 75.068076 -318.955514) (xy 75.113287 -319.016369) (xy 75.151774 -319.081684) (xy 75.1831 -319.15072)
			(xy 75.20691 -319.222695) (xy 75.222935 -319.296793) (xy 75.230994 -319.372174) (xy 75.231498 -319.41008)
			(xy 76.347577 -319.41008) (xy 76.351612 -319.334376) (xy 76.363671 -319.259531) (xy 76.383617 -319.18639)
			(xy 76.411224 -319.115785) (xy 76.44618 -319.048514) (xy 76.488088 -318.985339) (xy 76.536474 -318.926977)
			(xy 76.59079 -318.874089) (xy 76.650419 -318.827274) (xy 76.714687 -318.787062) (xy 76.782864 -318.75391)
			(xy 76.85418 -318.728192) (xy 76.927825 -318.7102) (xy 77.002965 -318.700138) (xy 77.078749 -318.698119)
			(xy 77.154319 -318.704168) (xy 77.228817 -318.718215) (xy 77.3014 -318.740101) (xy 77.371246 -318.769578)
			(xy 77.437563 -318.806313) (xy 77.499599 -318.849888) (xy 77.556652 -318.89981) (xy 77.608076 -318.955514)
			(xy 77.653287 -319.016369) (xy 77.691774 -319.081684) (xy 77.7231 -319.15072) (xy 77.74691 -319.222695)
			(xy 77.762935 -319.296793) (xy 77.770994 -319.372174) (xy 77.771498 -319.41008) (xy 78.887577 -319.41008)
			(xy 78.891612 -319.334376) (xy 78.903671 -319.259531) (xy 78.923617 -319.18639) (xy 78.951224 -319.115785)
			(xy 78.98618 -319.048514) (xy 79.028088 -318.985339) (xy 79.076474 -318.926977) (xy 79.13079 -318.874089)
			(xy 79.190419 -318.827274) (xy 79.254687 -318.787062) (xy 79.322864 -318.75391) (xy 79.39418 -318.728192)
			(xy 79.467825 -318.7102) (xy 79.542965 -318.700138) (xy 79.618749 -318.698119) (xy 79.694319 -318.704168)
			(xy 79.768817 -318.718215) (xy 79.8414 -318.740101) (xy 79.911246 -318.769578) (xy 79.977563 -318.806313)
			(xy 80.039599 -318.849888) (xy 80.096652 -318.89981) (xy 80.148076 -318.955514) (xy 80.193287 -319.016369)
			(xy 80.231774 -319.081684) (xy 80.2631 -319.15072) (xy 80.28691 -319.222695) (xy 80.302935 -319.296793)
			(xy 80.310994 -319.372174) (xy 80.311498 -319.41008) (xy 81.427577 -319.41008) (xy 81.431612 -319.334376)
			(xy 81.443671 -319.259531) (xy 81.463617 -319.18639) (xy 81.491224 -319.115785) (xy 81.52618 -319.048514)
			(xy 81.568088 -318.985339) (xy 81.616474 -318.926977) (xy 81.67079 -318.874089) (xy 81.730419 -318.827274)
			(xy 81.794687 -318.787062) (xy 81.862864 -318.75391) (xy 81.93418 -318.728192) (xy 82.007825 -318.7102)
			(xy 82.082965 -318.700138) (xy 82.158749 -318.698119) (xy 82.234319 -318.704168) (xy 82.308817 -318.718215)
			(xy 82.3814 -318.740101) (xy 82.451246 -318.769578) (xy 82.517563 -318.806313) (xy 82.579599 -318.849888)
			(xy 82.636652 -318.89981) (xy 82.688076 -318.955514) (xy 82.733287 -319.016369) (xy 82.771774 -319.081684)
			(xy 82.8031 -319.15072) (xy 82.82691 -319.222695) (xy 82.842935 -319.296793) (xy 82.850994 -319.372174)
			(xy 82.851498 -319.41008) (xy 82.850994 -319.447986) (xy 82.842935 -319.523367) (xy 82.82691 -319.597465)
			(xy 82.8031 -319.66944) (xy 82.771774 -319.738476) (xy 82.733287 -319.803791) (xy 82.688076 -319.864646)
			(xy 82.636652 -319.92035) (xy 82.585544 -319.96507) (xy 84.927697 -319.96507) (xy 84.931732 -319.889366)
			(xy 84.943791 -319.814521) (xy 84.963737 -319.74138) (xy 84.991344 -319.670775) (xy 85.0263 -319.603504)
			(xy 85.068208 -319.540329) (xy 85.116594 -319.481967) (xy 85.17091 -319.429079) (xy 85.230539 -319.382264)
			(xy 85.294807 -319.342052) (xy 85.362984 -319.3089) (xy 85.4343 -319.283182) (xy 85.507945 -319.26519)
			(xy 85.583085 -319.255128) (xy 85.658869 -319.253109) (xy 85.734439 -319.259158) (xy 85.808937 -319.273205)
			(xy 85.88152 -319.295091) (xy 85.951366 -319.324568) (xy 86.017683 -319.361303) (xy 86.079719 -319.404878)
			(xy 86.136772 -319.4548) (xy 86.188196 -319.510504) (xy 86.233407 -319.571359) (xy 86.271894 -319.636674)
			(xy 86.30322 -319.70571) (xy 86.32703 -319.777685) (xy 86.343055 -319.851783) (xy 86.351114 -319.927164)
			(xy 86.351618 -319.96507) (xy 86.351114 -320.002976) (xy 86.343055 -320.078357) (xy 86.32703 -320.152455)
			(xy 86.30322 -320.22443) (xy 86.271894 -320.293466) (xy 86.233407 -320.358781) (xy 86.188196 -320.419636)
			(xy 86.136772 -320.47534) (xy 86.079719 -320.525262) (xy 86.017683 -320.568837) (xy 85.951366 -320.605572)
			(xy 85.88152 -320.635049) (xy 85.808937 -320.656935) (xy 85.734439 -320.670982) (xy 85.658869 -320.677031)
			(xy 85.583085 -320.675012) (xy 85.507945 -320.66495) (xy 85.4343 -320.646958) (xy 85.362984 -320.62124)
			(xy 85.294807 -320.588088) (xy 85.230539 -320.547876) (xy 85.17091 -320.501061) (xy 85.116594 -320.448173)
			(xy 85.068208 -320.389811) (xy 85.0263 -320.326636) (xy 84.991344 -320.259365) (xy 84.963737 -320.18876)
			(xy 84.943791 -320.115619) (xy 84.931732 -320.040774) (xy 84.927697 -319.96507) (xy 82.585544 -319.96507)
			(xy 82.579599 -319.970272) (xy 82.517563 -320.013847) (xy 82.451246 -320.050582) (xy 82.3814 -320.080059)
			(xy 82.308817 -320.101945) (xy 82.234319 -320.115992) (xy 82.158749 -320.122041) (xy 82.082965 -320.120022)
			(xy 82.007825 -320.10996) (xy 81.93418 -320.091968) (xy 81.862864 -320.06625) (xy 81.794687 -320.033098)
			(xy 81.730419 -319.992886) (xy 81.67079 -319.946071) (xy 81.616474 -319.893183) (xy 81.568088 -319.834821)
			(xy 81.52618 -319.771646) (xy 81.491224 -319.704375) (xy 81.463617 -319.63377) (xy 81.443671 -319.560629)
			(xy 81.431612 -319.485784) (xy 81.427577 -319.41008) (xy 80.311498 -319.41008) (xy 80.310994 -319.447986)
			(xy 80.302935 -319.523367) (xy 80.28691 -319.597465) (xy 80.2631 -319.66944) (xy 80.231774 -319.738476)
			(xy 80.193287 -319.803791) (xy 80.148076 -319.864646) (xy 80.096652 -319.92035) (xy 80.039599 -319.970272)
			(xy 79.977563 -320.013847) (xy 79.911246 -320.050582) (xy 79.8414 -320.080059) (xy 79.768817 -320.101945)
			(xy 79.694319 -320.115992) (xy 79.618749 -320.122041) (xy 79.542965 -320.120022) (xy 79.467825 -320.10996)
			(xy 79.39418 -320.091968) (xy 79.322864 -320.06625) (xy 79.254687 -320.033098) (xy 79.190419 -319.992886)
			(xy 79.13079 -319.946071) (xy 79.076474 -319.893183) (xy 79.028088 -319.834821) (xy 78.98618 -319.771646)
			(xy 78.951224 -319.704375) (xy 78.923617 -319.63377) (xy 78.903671 -319.560629) (xy 78.891612 -319.485784)
			(xy 78.887577 -319.41008) (xy 77.771498 -319.41008) (xy 77.770994 -319.447986) (xy 77.762935 -319.523367)
			(xy 77.74691 -319.597465) (xy 77.7231 -319.66944) (xy 77.691774 -319.738476) (xy 77.653287 -319.803791)
			(xy 77.608076 -319.864646) (xy 77.556652 -319.92035) (xy 77.499599 -319.970272) (xy 77.437563 -320.013847)
			(xy 77.371246 -320.050582) (xy 77.3014 -320.080059) (xy 77.228817 -320.101945) (xy 77.154319 -320.115992)
			(xy 77.078749 -320.122041) (xy 77.002965 -320.120022) (xy 76.927825 -320.10996) (xy 76.85418 -320.091968)
			(xy 76.782864 -320.06625) (xy 76.714687 -320.033098) (xy 76.650419 -319.992886) (xy 76.59079 -319.946071)
			(xy 76.536474 -319.893183) (xy 76.488088 -319.834821) (xy 76.44618 -319.771646) (xy 76.411224 -319.704375)
			(xy 76.383617 -319.63377) (xy 76.363671 -319.560629) (xy 76.351612 -319.485784) (xy 76.347577 -319.41008)
			(xy 75.231498 -319.41008) (xy 75.230994 -319.447986) (xy 75.222935 -319.523367) (xy 75.20691 -319.597465)
			(xy 75.1831 -319.66944) (xy 75.151774 -319.738476) (xy 75.113287 -319.803791) (xy 75.068076 -319.864646)
			(xy 75.016652 -319.92035) (xy 74.959599 -319.970272) (xy 74.897563 -320.013847) (xy 74.831246 -320.050582)
			(xy 74.7614 -320.080059) (xy 74.688817 -320.101945) (xy 74.614319 -320.115992) (xy 74.538749 -320.122041)
			(xy 74.462965 -320.120022) (xy 74.387825 -320.10996) (xy 74.31418 -320.091968) (xy 74.242864 -320.06625)
			(xy 74.174687 -320.033098) (xy 74.110419 -319.992886) (xy 74.05079 -319.946071) (xy 73.996474 -319.893183)
			(xy 73.948088 -319.834821) (xy 73.90618 -319.771646) (xy 73.871224 -319.704375) (xy 73.843617 -319.63377)
			(xy 73.823671 -319.560629) (xy 73.811612 -319.485784) (xy 73.807577 -319.41008) (xy 72.691498 -319.41008)
			(xy 72.690994 -319.447986) (xy 72.682935 -319.523367) (xy 72.66691 -319.597465) (xy 72.6431 -319.66944)
			(xy 72.611774 -319.738476) (xy 72.573287 -319.803791) (xy 72.528076 -319.864646) (xy 72.476652 -319.92035)
			(xy 72.419599 -319.970272) (xy 72.357563 -320.013847) (xy 72.291246 -320.050582) (xy 72.2214 -320.080059)
			(xy 72.148817 -320.101945) (xy 72.074319 -320.115992) (xy 71.998749 -320.122041) (xy 71.922965 -320.120022)
			(xy 71.847825 -320.10996) (xy 71.77418 -320.091968) (xy 71.702864 -320.06625) (xy 71.634687 -320.033098)
			(xy 71.570419 -319.992886) (xy 71.51079 -319.946071) (xy 71.456474 -319.893183) (xy 71.408088 -319.834821)
			(xy 71.36618 -319.771646) (xy 71.331224 -319.704375) (xy 71.303617 -319.63377) (xy 71.283671 -319.560629)
			(xy 71.271612 -319.485784) (xy 71.267577 -319.41008) (xy 70.151498 -319.41008) (xy 70.150994 -319.447986)
			(xy 70.142935 -319.523367) (xy 70.12691 -319.597465) (xy 70.1031 -319.66944) (xy 70.071774 -319.738476)
			(xy 70.033287 -319.803791) (xy 69.988076 -319.864646) (xy 69.936652 -319.92035) (xy 69.879599 -319.970272)
			(xy 69.817563 -320.013847) (xy 69.751246 -320.050582) (xy 69.6814 -320.080059) (xy 69.608817 -320.101945)
			(xy 69.534319 -320.115992) (xy 69.458749 -320.122041) (xy 69.382965 -320.120022) (xy 69.307825 -320.10996)
			(xy 69.23418 -320.091968) (xy 69.162864 -320.06625) (xy 69.094687 -320.033098) (xy 69.030419 -319.992886)
			(xy 68.97079 -319.946071) (xy 68.916474 -319.893183) (xy 68.868088 -319.834821) (xy 68.82618 -319.771646)
			(xy 68.791224 -319.704375) (xy 68.763617 -319.63377) (xy 68.743671 -319.560629) (xy 68.731612 -319.485784)
			(xy 68.727577 -319.41008) (xy 67.611498 -319.41008) (xy 67.610994 -319.447986) (xy 67.602935 -319.523367)
			(xy 67.58691 -319.597465) (xy 67.5631 -319.66944) (xy 67.531774 -319.738476) (xy 67.493287 -319.803791)
			(xy 67.448076 -319.864646) (xy 67.396652 -319.92035) (xy 67.339599 -319.970272) (xy 67.277563 -320.013847)
			(xy 67.211246 -320.050582) (xy 67.1414 -320.080059) (xy 67.068817 -320.101945) (xy 66.994319 -320.115992)
			(xy 66.918749 -320.122041) (xy 66.842965 -320.120022) (xy 66.767825 -320.10996) (xy 66.69418 -320.091968)
			(xy 66.622864 -320.06625) (xy 66.554687 -320.033098) (xy 66.490419 -319.992886) (xy 66.43079 -319.946071)
			(xy 66.376474 -319.893183) (xy 66.328088 -319.834821) (xy 66.28618 -319.771646) (xy 66.251224 -319.704375)
			(xy 66.223617 -319.63377) (xy 66.203671 -319.560629) (xy 66.191612 -319.485784) (xy 66.187577 -319.41008)
			(xy 65.071498 -319.41008) (xy 65.070994 -319.447986) (xy 65.062935 -319.523367) (xy 65.04691 -319.597465)
			(xy 65.0231 -319.66944) (xy 64.991774 -319.738476) (xy 64.953287 -319.803791) (xy 64.908076 -319.864646)
			(xy 64.856652 -319.92035) (xy 64.799599 -319.970272) (xy 64.737563 -320.013847) (xy 64.671246 -320.050582)
			(xy 64.6014 -320.080059) (xy 64.528817 -320.101945) (xy 64.454319 -320.115992) (xy 64.378749 -320.122041)
			(xy 64.302965 -320.120022) (xy 64.227825 -320.10996) (xy 64.15418 -320.091968) (xy 64.082864 -320.06625)
			(xy 64.014687 -320.033098) (xy 63.950419 -319.992886) (xy 63.89079 -319.946071) (xy 63.836474 -319.893183)
			(xy 63.788088 -319.834821) (xy 63.74618 -319.771646) (xy 63.711224 -319.704375) (xy 63.683617 -319.63377)
			(xy 63.663671 -319.560629) (xy 63.651612 -319.485784) (xy 63.647577 -319.41008) (xy 42.500813 -319.41008)
			(xy 42.479042 -319.426857) (xy 42.381609 -319.491665) (xy 42.279905 -319.54954) (xy 42.174422 -319.600202)
			(xy 42.065671 -319.643404) (xy 41.954179 -319.678939) (xy 41.840485 -319.706634) (xy 41.725141 -319.726354)
			(xy 41.608704 -319.738005) (xy 41.491739 -319.74153) (xy 41.374812 -319.736912) (xy 41.258489 -319.724173)
			(xy 41.143334 -319.703375) (xy 41.029905 -319.674618) (xy 40.91875 -319.638042) (xy 40.810407 -319.593825)
			(xy 40.705403 -319.542179) (xy 40.604244 -319.483356) (xy 40.507421 -319.41764) (xy 40.415403 -319.345349)
			(xy 40.328636 -319.266834) (xy 40.247539 -319.182474) (xy 40.172506 -319.092679) (xy 40.103899 -318.997883)
			(xy 40.042051 -318.898544) (xy 39.987262 -318.795145) (xy 39.939796 -318.688186) (xy 39.899884 -318.578185)
			(xy 39.86772 -318.465674) (xy 39.843457 -318.351199) (xy 39.827215 -318.235313) (xy 39.819072 -318.118579)
			(xy 39.818564 -318.06007) (xy 29.709872 -318.06007) (xy 29.709872 -319.517268) (xy 29.711583 -319.539403)
			(xy 29.721698 -319.582627) (xy 29.739164 -319.623439) (xy 29.763451 -319.660598) (xy 29.793821 -319.692975)
			(xy 29.829351 -319.719588) (xy 29.868962 -319.739628) (xy 29.911451 -319.752486) (xy 29.955527 -319.757772)
			(xy 29.999851 -319.755324) (xy 30.043078 -319.745218) (xy 30.063694 -319.736978) (xy 30.103694 -319.718964)
			(xy 30.186362 -319.689591) (xy 30.271408 -319.668045) (xy 30.35809 -319.654515) (xy 30.445656 -319.649117)
			(xy 30.533343 -319.651898) (xy 30.620391 -319.662835) (xy 30.706041 -319.681833) (xy 30.78955 -319.708725)
			(xy 30.870191 -319.743279) (xy 30.947263 -319.785193) (xy 31.020096 -319.834104) (xy 31.088056 -319.889587)
			(xy 31.150553 -319.951158) (xy 31.207044 -320.018282) (xy 31.257037 -320.090376) (xy 31.300098 -320.166814)
			(xy 31.335852 -320.24693) (xy 31.363988 -320.330027) (xy 31.384262 -320.415385) (xy 31.396497 -320.502259)
			(xy 31.400588 -320.589896) (xy 31.39856 -320.63336) (xy 34.599874 -320.63336) (xy 34.599874 -320.54646)
			(xy 34.607892 -320.459931) (xy 34.62386 -320.374511) (xy 34.647641 -320.290929) (xy 34.679033 -320.209897)
			(xy 34.717767 -320.132108) (xy 34.763514 -320.058224) (xy 34.815883 -319.988877) (xy 34.874427 -319.924657)
			(xy 34.938647 -319.866113) (xy 35.007994 -319.813744) (xy 35.081878 -319.767997) (xy 35.159667 -319.729263)
			(xy 35.240699 -319.697871) (xy 35.324281 -319.67409) (xy 35.409701 -319.658122) (xy 35.49623 -319.650104)
			(xy 35.58313 -319.650104) (xy 35.669659 -319.658122) (xy 35.755079 -319.67409) (xy 35.838661 -319.697871)
			(xy 35.919693 -319.729263) (xy 35.997482 -319.767997) (xy 36.071366 -319.813744) (xy 36.140713 -319.866113)
			(xy 36.204933 -319.924657) (xy 36.263477 -319.988877) (xy 36.315846 -320.058224) (xy 36.361593 -320.132108)
			(xy 36.400327 -320.209897) (xy 36.431719 -320.290929) (xy 36.4555 -320.374511) (xy 36.471468 -320.459931)
			(xy 36.479486 -320.54646) (xy 36.479988 -320.58991) (xy 36.479486 -320.63336) (xy 36.471468 -320.719889)
			(xy 36.4555 -320.805309) (xy 36.431719 -320.888891) (xy 36.400327 -320.969923) (xy 36.361593 -321.047712)
			(xy 36.315846 -321.121596) (xy 36.263477 -321.190943) (xy 36.204933 -321.255163) (xy 36.140713 -321.313707)
			(xy 36.071366 -321.366076) (xy 35.997482 -321.411823) (xy 35.919693 -321.450557) (xy 35.838661 -321.481949)
			(xy 35.755079 -321.50573) (xy 35.669659 -321.521698) (xy 35.58313 -321.529716) (xy 35.49623 -321.529716)
			(xy 35.409701 -321.521698) (xy 35.324281 -321.50573) (xy 35.240699 -321.481949) (xy 35.159667 -321.450557)
			(xy 35.081878 -321.411823) (xy 35.007994 -321.366076) (xy 34.938647 -321.313707) (xy 34.874427 -321.255163)
			(xy 34.815883 -321.190943) (xy 34.763514 -321.121596) (xy 34.717767 -321.047712) (xy 34.679033 -320.969923)
			(xy 34.647641 -320.888891) (xy 34.62386 -320.805309) (xy 34.607892 -320.719889) (xy 34.599874 -320.63336)
			(xy 31.39856 -320.63336) (xy 31.396498 -320.677532) (xy 31.384263 -320.764407) (xy 31.36399 -320.849764)
			(xy 31.335855 -320.932863) (xy 31.300101 -321.012979) (xy 31.257042 -321.089417) (xy 31.207049 -321.161511)
			(xy 31.150559 -321.228636) (xy 31.088062 -321.290208) (xy 31.020102 -321.345691) (xy 30.94727 -321.394602)
			(xy 30.870199 -321.436518) (xy 30.789558 -321.471072) (xy 30.70605 -321.497965) (xy 30.620399 -321.516963)
			(xy 30.533352 -321.527901) (xy 30.445664 -321.530683) (xy 30.358098 -321.525286) (xy 30.271416 -321.511756)
			(xy 30.18637 -321.490212) (xy 30.103701 -321.460839) (xy 30.063694 -321.442842) (xy 30.043103 -321.434515)
			(xy 29.999863 -321.424379) (xy 29.955519 -321.421912) (xy 29.911421 -321.427188) (xy 29.868911 -321.440046)
			(xy 29.829282 -321.460095) (xy 29.793739 -321.486725) (xy 29.763364 -321.519126) (xy 29.739082 -321.556313)
			(xy 29.72163 -321.597153) (xy 29.711541 -321.640404) (xy 29.709872 -321.662552) (xy 29.709872 -322.057268)
			(xy 29.711583 -322.079403) (xy 29.721698 -322.122627) (xy 29.739164 -322.163439) (xy 29.763451 -322.200598)
			(xy 29.793821 -322.232975) (xy 29.829351 -322.259588) (xy 29.868962 -322.279628) (xy 29.911451 -322.292486)
			(xy 29.955527 -322.297772) (xy 29.999851 -322.295324) (xy 30.043078 -322.285218) (xy 30.063694 -322.276978)
			(xy 30.103694 -322.258964) (xy 30.186362 -322.229591) (xy 30.271408 -322.208045) (xy 30.35809 -322.194515)
			(xy 30.445656 -322.189117) (xy 30.533343 -322.191898) (xy 30.620391 -322.202835) (xy 30.706041 -322.221833)
			(xy 30.78955 -322.248725) (xy 30.870191 -322.283279) (xy 30.947263 -322.325193) (xy 31.020096 -322.374104)
			(xy 31.088056 -322.429587) (xy 31.150553 -322.491158) (xy 31.207044 -322.558282) (xy 31.257037 -322.630376)
			(xy 31.300098 -322.706814) (xy 31.335852 -322.78693) (xy 31.363988 -322.870027) (xy 31.384262 -322.955385)
			(xy 31.396497 -323.042259) (xy 31.400588 -323.129896) (xy 31.39856 -323.17336) (xy 34.599874 -323.17336)
			(xy 34.599874 -323.08646) (xy 34.607892 -322.999931) (xy 34.62386 -322.914511) (xy 34.647641 -322.830929)
			(xy 34.679033 -322.749897) (xy 34.717767 -322.672108) (xy 34.763514 -322.598224) (xy 34.815883 -322.528877)
			(xy 34.874427 -322.464657) (xy 34.938647 -322.406113) (xy 35.007994 -322.353744) (xy 35.081878 -322.307997)
			(xy 35.159667 -322.269263) (xy 35.240699 -322.237871) (xy 35.324281 -322.21409) (xy 35.409701 -322.198122)
			(xy 35.49623 -322.190104) (xy 35.58313 -322.190104) (xy 35.669659 -322.198122) (xy 35.755079 -322.21409)
			(xy 35.838661 -322.237871) (xy 35.919693 -322.269263) (xy 35.997482 -322.307997) (xy 36.071366 -322.353744)
			(xy 36.140713 -322.406113) (xy 36.204933 -322.464657) (xy 36.263477 -322.528877) (xy 36.315846 -322.598224)
			(xy 36.361593 -322.672108) (xy 36.400327 -322.749897) (xy 36.431719 -322.830929) (xy 36.4555 -322.914511)
			(xy 36.471468 -322.999931) (xy 36.479486 -323.08646) (xy 36.479988 -323.12991) (xy 36.479486 -323.17336)
			(xy 36.477278 -323.197188) (xy 64.789715 -323.197188) (xy 64.793604 -323.142839) (xy 64.805188 -323.089597)
			(xy 64.824232 -323.038545) (xy 64.850347 -322.990723) (xy 64.883002 -322.947105) (xy 64.921533 -322.908578)
			(xy 64.965155 -322.875927) (xy 65.012979 -322.849816) (xy 65.064033 -322.830778) (xy 65.117276 -322.819199)
			(xy 65.171625 -322.815315) (xy 65.225974 -322.819206) (xy 65.279216 -322.830792) (xy 65.330267 -322.849837)
			(xy 65.378088 -322.875954) (xy 65.400174 -322.891912) (xy 65.419186 -322.905508) (xy 65.461069 -322.92624)
			(xy 65.506037 -322.938966) (xy 65.552574 -322.943256) (xy 65.599111 -322.938966) (xy 65.644079 -322.92624)
			(xy 65.685962 -322.905508) (xy 65.704974 -322.891912) (xy 65.727044 -322.875923) (xy 65.774873 -322.849795)
			(xy 65.825933 -322.830741) (xy 65.879185 -322.819148) (xy 65.933545 -322.815252) (xy 65.987906 -322.819132)
			(xy 66.041162 -322.83071) (xy 66.092228 -322.84975) (xy 66.140064 -322.875864) (xy 66.183696 -322.90852)
			(xy 66.222237 -322.947053) (xy 66.2549 -322.99068) (xy 66.281022 -323.038511) (xy 66.300071 -323.089574)
			(xy 66.311658 -323.142827) (xy 66.315548 -323.197188) (xy 67.594107 -323.197188) (xy 67.597996 -323.142837)
			(xy 67.609581 -323.089593) (xy 67.628625 -323.03854) (xy 67.654742 -322.990716) (xy 67.687398 -322.947097)
			(xy 67.725931 -322.908569) (xy 67.769554 -322.875917) (xy 67.817381 -322.849806) (xy 67.868436 -322.830768)
			(xy 67.921682 -322.819189) (xy 67.976033 -322.815307) (xy 68.030384 -322.819199) (xy 68.083627 -322.830786)
			(xy 68.13468 -322.849834) (xy 68.182502 -322.875953) (xy 68.204588 -322.891912) (xy 68.2236 -322.905508)
			(xy 68.265483 -322.92624) (xy 68.310451 -322.938966) (xy 68.356988 -322.943256) (xy 68.403525 -322.938966)
			(xy 68.448493 -322.92624) (xy 68.490376 -322.905508) (xy 68.509388 -322.891912) (xy 68.531458 -322.875924)
			(xy 68.579285 -322.849799) (xy 68.630344 -322.830747) (xy 68.683595 -322.819155) (xy 68.737953 -322.81526)
			(xy 68.792312 -322.819142) (xy 68.845566 -322.83072) (xy 68.89663 -322.84976) (xy 68.944463 -322.875873)
			(xy 68.988094 -322.908529) (xy 69.026633 -322.947062) (xy 69.059295 -322.990687) (xy 69.085416 -323.038517)
			(xy 69.104463 -323.089578) (xy 69.11605 -323.142829) (xy 69.11994 -323.197188) (xy 69.116053 -323.251547)
			(xy 69.10447 -323.304799) (xy 69.085426 -323.355861) (xy 69.059308 -323.403693) (xy 69.026648 -323.44732)
			(xy 68.988112 -323.485855) (xy 68.944484 -323.518514) (xy 68.896651 -323.54463) (xy 68.845589 -323.563673)
			(xy 68.792336 -323.575255) (xy 68.737977 -323.57914) (xy 68.683619 -323.575248) (xy 68.630367 -323.56366)
			(xy 68.579307 -323.544611) (xy 68.531478 -323.518489) (xy 68.509388 -323.502528) (xy 68.490376 -323.488932)
			(xy 68.448493 -323.4682) (xy 68.403525 -323.455474) (xy 68.356988 -323.451184) (xy 68.310451 -323.455474)
			(xy 68.265483 -323.4682) (xy 68.2236 -323.488932) (xy 68.204588 -323.502528) (xy 68.182481 -323.51846)
			(xy 68.134658 -323.544576) (xy 68.083604 -323.56362) (xy 68.03036 -323.575205) (xy 67.976009 -323.579093)
			(xy 67.921658 -323.575207) (xy 67.868413 -323.563625) (xy 67.817359 -323.544584) (xy 67.769534 -323.51847)
			(xy 67.725913 -323.485815) (xy 67.687383 -323.447285) (xy 67.654729 -323.403664) (xy 67.628615 -323.355839)
			(xy 67.609574 -323.304784) (xy 67.597992 -323.251539) (xy 67.594107 -323.197188) (xy 66.315548 -323.197188)
			(xy 66.311662 -323.251549) (xy 66.300078 -323.304803) (xy 66.281032 -323.355867) (xy 66.254913 -323.4037)
			(xy 66.222252 -323.447328) (xy 66.183714 -323.485865) (xy 66.140084 -323.518523) (xy 66.09225 -323.54464)
			(xy 66.041185 -323.563683) (xy 65.98793 -323.575264) (xy 65.933569 -323.579148) (xy 65.879209 -323.575255)
			(xy 65.825956 -323.563666) (xy 65.774894 -323.544615) (xy 65.727064 -323.51849) (xy 65.704974 -323.502528)
			(xy 65.685962 -323.488932) (xy 65.644079 -323.4682) (xy 65.599111 -323.455474) (xy 65.552574 -323.451184)
			(xy 65.506037 -323.455474) (xy 65.461069 -323.4682) (xy 65.419186 -323.488932) (xy 65.400174 -323.502528)
			(xy 65.378068 -323.518459) (xy 65.330245 -323.544573) (xy 65.279193 -323.563615) (xy 65.22595 -323.575198)
			(xy 65.171601 -323.579085) (xy 65.117252 -323.575198) (xy 65.064009 -323.563616) (xy 65.012957 -323.544574)
			(xy 64.965134 -323.51846) (xy 64.921515 -323.485806) (xy 64.882987 -323.447277) (xy 64.850334 -323.403657)
			(xy 64.824222 -323.355833) (xy 64.805181 -323.30478) (xy 64.793601 -323.251537) (xy 64.789715 -323.197188)
			(xy 36.477278 -323.197188) (xy 36.471468 -323.259889) (xy 36.4555 -323.345309) (xy 36.431719 -323.428891)
			(xy 36.400327 -323.509923) (xy 36.361593 -323.587712) (xy 36.315846 -323.661596) (xy 36.263477 -323.730943)
			(xy 36.204933 -323.795163) (xy 36.140713 -323.853707) (xy 36.071366 -323.906076) (xy 35.997482 -323.951823)
			(xy 35.919693 -323.990557) (xy 35.838661 -324.021949) (xy 35.755079 -324.04573) (xy 35.669659 -324.061698)
			(xy 35.58313 -324.069716) (xy 35.49623 -324.069716) (xy 35.409701 -324.061698) (xy 35.324281 -324.04573)
			(xy 35.240699 -324.021949) (xy 35.159667 -323.990557) (xy 35.081878 -323.951823) (xy 35.007994 -323.906076)
			(xy 34.938647 -323.853707) (xy 34.874427 -323.795163) (xy 34.815883 -323.730943) (xy 34.763514 -323.661596)
			(xy 34.717767 -323.587712) (xy 34.679033 -323.509923) (xy 34.647641 -323.428891) (xy 34.62386 -323.345309)
			(xy 34.607892 -323.259889) (xy 34.599874 -323.17336) (xy 31.39856 -323.17336) (xy 31.396498 -323.217532)
			(xy 31.384263 -323.304407) (xy 31.36399 -323.389764) (xy 31.335855 -323.472863) (xy 31.300101 -323.552979)
			(xy 31.257042 -323.629417) (xy 31.207049 -323.701511) (xy 31.150559 -323.768636) (xy 31.088062 -323.830208)
			(xy 31.020102 -323.885691) (xy 30.94727 -323.934602) (xy 30.870199 -323.976518) (xy 30.789558 -324.011072)
			(xy 30.70605 -324.037965) (xy 30.620399 -324.056963) (xy 30.533352 -324.067901) (xy 30.445664 -324.070683)
			(xy 30.358098 -324.065286) (xy 30.271416 -324.051756) (xy 30.18637 -324.030212) (xy 30.103701 -324.000839)
			(xy 30.063694 -323.982842) (xy 30.043103 -323.974515) (xy 29.999863 -323.964379) (xy 29.955519 -323.961912)
			(xy 29.911421 -323.967188) (xy 29.868911 -323.980046) (xy 29.829282 -324.000095) (xy 29.793739 -324.026725)
			(xy 29.763364 -324.059126) (xy 29.739082 -324.096313) (xy 29.72163 -324.137153) (xy 29.711541 -324.180404)
			(xy 29.709872 -324.202552) (xy 29.709872 -324.597268) (xy 29.711583 -324.619403) (xy 29.721698 -324.662627)
			(xy 29.739164 -324.703439) (xy 29.763451 -324.740598) (xy 29.793821 -324.772975) (xy 29.829351 -324.799588)
			(xy 29.868962 -324.819628) (xy 29.911451 -324.832486) (xy 29.955527 -324.837772) (xy 29.999851 -324.835324)
			(xy 30.043078 -324.825218) (xy 30.063694 -324.816978) (xy 30.103694 -324.798964) (xy 30.186362 -324.769591)
			(xy 30.271408 -324.748045) (xy 30.35809 -324.734515) (xy 30.445656 -324.729117) (xy 30.533343 -324.731898)
			(xy 30.620391 -324.742835) (xy 30.706041 -324.761833) (xy 30.78955 -324.788725) (xy 30.870191 -324.823279)
			(xy 30.947263 -324.865193) (xy 31.020096 -324.914104) (xy 31.088056 -324.969587) (xy 31.150553 -325.031158)
			(xy 31.207044 -325.098282) (xy 31.257037 -325.170376) (xy 31.300098 -325.246814) (xy 31.335852 -325.32693)
			(xy 31.363988 -325.410027) (xy 31.384262 -325.495385) (xy 31.396497 -325.582259) (xy 31.400588 -325.669896)
			(xy 31.39856 -325.71336) (xy 34.599874 -325.71336) (xy 34.599874 -325.62646) (xy 34.607892 -325.539931)
			(xy 34.62386 -325.454511) (xy 34.647641 -325.370929) (xy 34.679033 -325.289897) (xy 34.717767 -325.212108)
			(xy 34.763514 -325.138224) (xy 34.815883 -325.068877) (xy 34.874427 -325.004657) (xy 34.938647 -324.946113)
			(xy 35.007994 -324.893744) (xy 35.081878 -324.847997) (xy 35.159667 -324.809263) (xy 35.240699 -324.777871)
			(xy 35.324281 -324.75409) (xy 35.409701 -324.738122) (xy 35.49623 -324.730104) (xy 35.58313 -324.730104)
			(xy 35.669659 -324.738122) (xy 35.755079 -324.75409) (xy 35.838661 -324.777871) (xy 35.919693 -324.809263)
			(xy 35.997482 -324.847997) (xy 36.071366 -324.893744) (xy 36.140713 -324.946113) (xy 36.204933 -325.004657)
			(xy 36.209353 -325.009506) (xy 82.71559 -325.009506) (xy 82.71559 -324.94957) (xy 82.723413 -324.890148)
			(xy 82.738926 -324.832255) (xy 82.761862 -324.776882) (xy 82.791829 -324.724976) (xy 82.828316 -324.677426)
			(xy 82.870696 -324.635046) (xy 82.918246 -324.598559) (xy 82.970152 -324.568592) (xy 83.025525 -324.545656)
			(xy 83.083418 -324.530143) (xy 83.14284 -324.52232) (xy 83.202776 -324.52232) (xy 83.262198 -324.530143)
			(xy 83.320091 -324.545656) (xy 83.375464 -324.568592) (xy 83.42737 -324.598559) (xy 83.47492 -324.635046)
			(xy 83.5173 -324.677426) (xy 83.553787 -324.724976) (xy 83.583754 -324.776882) (xy 83.60669 -324.832255)
			(xy 83.622203 -324.890148) (xy 83.630026 -324.94957) (xy 83.630516 -324.979538) (xy 83.630026 -325.009506)
			(xy 83.622203 -325.068928) (xy 83.60669 -325.126821) (xy 83.583754 -325.182194) (xy 83.553787 -325.2341)
			(xy 83.5173 -325.28165) (xy 83.47492 -325.32403) (xy 83.42737 -325.360517) (xy 83.375464 -325.390484)
			(xy 83.320091 -325.41342) (xy 83.262198 -325.428933) (xy 83.202776 -325.436756) (xy 83.14284 -325.436756)
			(xy 83.083418 -325.428933) (xy 83.025525 -325.41342) (xy 82.970152 -325.390484) (xy 82.918246 -325.360517)
			(xy 82.870696 -325.32403) (xy 82.828316 -325.28165) (xy 82.791829 -325.2341) (xy 82.761862 -325.182194)
			(xy 82.738926 -325.126821) (xy 82.723413 -325.068928) (xy 82.71559 -325.009506) (xy 36.209353 -325.009506)
			(xy 36.263477 -325.068877) (xy 36.315846 -325.138224) (xy 36.361593 -325.212108) (xy 36.400327 -325.289897)
			(xy 36.431719 -325.370929) (xy 36.4555 -325.454511) (xy 36.471468 -325.539931) (xy 36.479486 -325.62646)
			(xy 36.479988 -325.66991) (xy 36.479486 -325.71336) (xy 36.471468 -325.799889) (xy 36.458739 -325.867982)
			(xy 64.789723 -325.867982) (xy 64.793613 -325.813634) (xy 64.805198 -325.760393) (xy 64.824242 -325.709343)
			(xy 64.850357 -325.661523) (xy 64.883012 -325.617906) (xy 64.921543 -325.57938) (xy 64.965164 -325.54673)
			(xy 65.012988 -325.520621) (xy 65.064041 -325.501584) (xy 65.117283 -325.490006) (xy 65.171631 -325.486123)
			(xy 65.225979 -325.490015) (xy 65.279219 -325.501601) (xy 65.330269 -325.520647) (xy 65.378089 -325.546764)
			(xy 65.400174 -325.562722) (xy 65.419186 -325.576318) (xy 65.461069 -325.59705) (xy 65.506037 -325.609776)
			(xy 65.552574 -325.614066) (xy 65.599111 -325.609776) (xy 65.644079 -325.59705) (xy 65.685962 -325.576318)
			(xy 65.704974 -325.562722) (xy 65.727035 -325.546719) (xy 65.774864 -325.520591) (xy 65.825925 -325.501535)
			(xy 65.879178 -325.489941) (xy 65.933539 -325.486044) (xy 65.987902 -325.489924) (xy 66.041159 -325.501501)
			(xy 66.092226 -325.52054) (xy 66.140063 -325.546654) (xy 66.183697 -325.57931) (xy 66.222239 -325.617844)
			(xy 66.254904 -325.661471) (xy 66.281027 -325.709303) (xy 66.300077 -325.760366) (xy 66.311665 -325.81362)
			(xy 66.315556 -325.867982) (xy 67.594115 -325.867982) (xy 67.598005 -325.813632) (xy 67.60959 -325.760389)
			(xy 67.628635 -325.709337) (xy 67.654752 -325.661516) (xy 67.687408 -325.617897) (xy 67.725941 -325.579371)
			(xy 67.769564 -325.546721) (xy 67.81739 -325.520611) (xy 67.868444 -325.501574) (xy 67.921689 -325.489996)
			(xy 67.976039 -325.486115) (xy 68.030389 -325.490008) (xy 68.083631 -325.501596) (xy 68.134682 -325.520644)
			(xy 68.182502 -325.546763) (xy 68.204588 -325.562722) (xy 68.2236 -325.576318) (xy 68.265483 -325.59705)
			(xy 68.310451 -325.609776) (xy 68.356988 -325.614066) (xy 68.403525 -325.609776) (xy 68.448493 -325.59705)
			(xy 68.490376 -325.576318) (xy 68.509388 -325.562722) (xy 68.531448 -325.546721) (xy 68.579276 -325.520594)
			(xy 68.630336 -325.501541) (xy 68.683588 -325.489948) (xy 68.737947 -325.486052) (xy 68.792308 -325.489933)
			(xy 68.845562 -325.501511) (xy 68.896627 -325.52055) (xy 68.944463 -325.546663) (xy 68.988095 -325.579319)
			(xy 69.026635 -325.617852) (xy 69.059298 -325.661478) (xy 69.069311 -325.679812) (xy 81.325194 -325.679812)
			(xy 81.325194 -325.619876) (xy 81.333017 -325.560454) (xy 81.34853 -325.502561) (xy 81.371466 -325.447188)
			(xy 81.401433 -325.395282) (xy 81.43792 -325.347732) (xy 81.4803 -325.305352) (xy 81.52785 -325.268865)
			(xy 81.579756 -325.238898) (xy 81.635129 -325.215962) (xy 81.693022 -325.200449) (xy 81.752444 -325.192626)
			(xy 81.81238 -325.192626) (xy 81.871802 -325.200449) (xy 81.929695 -325.215962) (xy 81.985068 -325.238898)
			(xy 82.036974 -325.268865) (xy 82.084524 -325.305352) (xy 82.126904 -325.347732) (xy 82.163391 -325.395282)
			(xy 82.193358 -325.447188) (xy 82.216294 -325.502561) (xy 82.231807 -325.560454) (xy 82.23963 -325.619876)
			(xy 82.24012 -325.649844) (xy 82.23963 -325.679812) (xy 82.231807 -325.739234) (xy 82.216294 -325.797127)
			(xy 82.193358 -325.8525) (xy 82.163391 -325.904406) (xy 82.126904 -325.951956) (xy 82.084524 -325.994336)
			(xy 82.036974 -326.030823) (xy 81.985068 -326.06079) (xy 81.929695 -326.083726) (xy 81.871802 -326.099239)
			(xy 81.81238 -326.107062) (xy 81.752444 -326.107062) (xy 81.693022 -326.099239) (xy 81.635129 -326.083726)
			(xy 81.579756 -326.06079) (xy 81.52785 -326.030823) (xy 81.4803 -325.994336) (xy 81.43792 -325.951956)
			(xy 81.401433 -325.904406) (xy 81.371466 -325.8525) (xy 81.34853 -325.797127) (xy 81.333017 -325.739234)
			(xy 81.325194 -325.679812) (xy 69.069311 -325.679812) (xy 69.08542 -325.709308) (xy 69.104469 -325.76037)
			(xy 69.116057 -325.813622) (xy 69.119948 -325.867982) (xy 69.116062 -325.922342) (xy 69.104479 -325.975596)
			(xy 69.085435 -326.026659) (xy 69.059318 -326.074492) (xy 69.026658 -326.118121) (xy 68.988122 -326.156657)
			(xy 68.970255 -326.170032) (xy 83.266008 -326.170032) (xy 83.266008 -326.110096) (xy 83.273831 -326.050674)
			(xy 83.289344 -325.992781) (xy 83.31228 -325.937408) (xy 83.342247 -325.885502) (xy 83.378734 -325.837952)
			(xy 83.421114 -325.795572) (xy 83.468664 -325.759085) (xy 83.52057 -325.729118) (xy 83.575943 -325.706182)
			(xy 83.633836 -325.690669) (xy 83.693258 -325.682846) (xy 83.753194 -325.682846) (xy 83.812616 -325.690669)
			(xy 83.870509 -325.706182) (xy 83.925882 -325.729118) (xy 83.977788 -325.759085) (xy 84.025338 -325.795572)
			(xy 84.067718 -325.837952) (xy 84.104205 -325.885502) (xy 84.134172 -325.937408) (xy 84.157108 -325.992781)
			(xy 84.172621 -326.050674) (xy 84.180444 -326.110096) (xy 84.180934 -326.140064) (xy 84.180444 -326.170032)
			(xy 84.172621 -326.229454) (xy 84.157108 -326.287347) (xy 84.134172 -326.34272) (xy 84.104205 -326.394626)
			(xy 84.067718 -326.442176) (xy 84.025338 -326.484556) (xy 83.977788 -326.521043) (xy 83.925882 -326.55101)
			(xy 83.870509 -326.573946) (xy 83.812616 -326.589459) (xy 83.753194 -326.597282) (xy 83.693258 -326.597282)
			(xy 83.633836 -326.589459) (xy 83.575943 -326.573946) (xy 83.52057 -326.55101) (xy 83.468664 -326.521043)
			(xy 83.421114 -326.484556) (xy 83.378734 -326.442176) (xy 83.342247 -326.394626) (xy 83.31228 -326.34272)
			(xy 83.289344 -326.287347) (xy 83.273831 -326.229454) (xy 83.266008 -326.170032) (xy 68.970255 -326.170032)
			(xy 68.944493 -326.189317) (xy 68.89666 -326.215435) (xy 68.845597 -326.234479) (xy 68.792343 -326.246062)
			(xy 68.737983 -326.249948) (xy 68.683623 -326.246057) (xy 68.630371 -326.23447) (xy 68.579309 -326.215421)
			(xy 68.531479 -326.189299) (xy 68.509388 -326.173338) (xy 68.490376 -326.159742) (xy 68.448493 -326.13901)
			(xy 68.403525 -326.126284) (xy 68.356988 -326.121994) (xy 68.310451 -326.126284) (xy 68.265483 -326.13901)
			(xy 68.2236 -326.159742) (xy 68.204588 -326.173338) (xy 68.182472 -326.189256) (xy 68.134649 -326.215371)
			(xy 68.083596 -326.234414) (xy 68.030353 -326.245998) (xy 67.976003 -326.249885) (xy 67.921653 -326.245998)
			(xy 67.86841 -326.234416) (xy 67.817357 -326.215374) (xy 67.769533 -326.18926) (xy 67.725913 -326.156605)
			(xy 67.687385 -326.118075) (xy 67.654732 -326.074454) (xy 67.62862 -326.02663) (xy 67.60958 -325.975576)
			(xy 67.597999 -325.922332) (xy 67.594115 -325.867982) (xy 66.315556 -325.867982) (xy 66.31167 -325.922344)
			(xy 66.300087 -325.9756) (xy 66.281042 -326.026665) (xy 66.254923 -326.074499) (xy 66.222262 -326.118129)
			(xy 66.183724 -326.156667) (xy 66.140093 -326.189327) (xy 66.092258 -326.215445) (xy 66.041193 -326.234489)
			(xy 65.987937 -326.246071) (xy 65.933575 -326.249956) (xy 65.879214 -326.246064) (xy 65.825959 -326.234475)
			(xy 65.774896 -326.215424) (xy 65.727065 -326.1893) (xy 65.704974 -326.173338) (xy 65.685962 -326.159742)
			(xy 65.644079 -326.13901) (xy 65.599111 -326.126284) (xy 65.552574 -326.121994) (xy 65.506037 -326.126284)
			(xy 65.461069 -326.13901) (xy 65.419186 -326.159742) (xy 65.400174 -326.173338) (xy 65.378058 -326.189255)
			(xy 65.330236 -326.215368) (xy 65.279185 -326.234409) (xy 65.225943 -326.24599) (xy 65.171595 -326.249877)
			(xy 65.117247 -326.245989) (xy 65.064006 -326.234406) (xy 65.012955 -326.215364) (xy 64.965134 -326.18925)
			(xy 64.921516 -326.156596) (xy 64.882989 -326.118067) (xy 64.850338 -326.074447) (xy 64.824227 -326.026624)
			(xy 64.805187 -325.975572) (xy 64.793608 -325.92233) (xy 64.789723 -325.867982) (xy 36.458739 -325.867982)
			(xy 36.4555 -325.885309) (xy 36.431719 -325.968891) (xy 36.400327 -326.049923) (xy 36.361593 -326.127712)
			(xy 36.315846 -326.201596) (xy 36.263477 -326.270943) (xy 36.204933 -326.335163) (xy 36.140713 -326.393707)
			(xy 36.071366 -326.446076) (xy 35.997482 -326.491823) (xy 35.919693 -326.530557) (xy 35.838661 -326.561949)
			(xy 35.755079 -326.58573) (xy 35.669659 -326.601698) (xy 35.58313 -326.609716) (xy 35.49623 -326.609716)
			(xy 35.409701 -326.601698) (xy 35.324281 -326.58573) (xy 35.240699 -326.561949) (xy 35.159667 -326.530557)
			(xy 35.081878 -326.491823) (xy 35.007994 -326.446076) (xy 34.938647 -326.393707) (xy 34.874427 -326.335163)
			(xy 34.815883 -326.270943) (xy 34.763514 -326.201596) (xy 34.717767 -326.127712) (xy 34.679033 -326.049923)
			(xy 34.647641 -325.968891) (xy 34.62386 -325.885309) (xy 34.607892 -325.799889) (xy 34.599874 -325.71336)
			(xy 31.39856 -325.71336) (xy 31.396498 -325.757532) (xy 31.384263 -325.844407) (xy 31.36399 -325.929764)
			(xy 31.335855 -326.012863) (xy 31.300101 -326.092979) (xy 31.257042 -326.169417) (xy 31.207049 -326.241511)
			(xy 31.150559 -326.308636) (xy 31.088062 -326.370208) (xy 31.020102 -326.425691) (xy 30.94727 -326.474602)
			(xy 30.870199 -326.516518) (xy 30.789558 -326.551072) (xy 30.70605 -326.577965) (xy 30.620399 -326.596963)
			(xy 30.533352 -326.607901) (xy 30.445664 -326.610683) (xy 30.358098 -326.605286) (xy 30.271416 -326.591756)
			(xy 30.18637 -326.570212) (xy 30.103701 -326.540839) (xy 30.063694 -326.522842) (xy 30.043103 -326.514515)
			(xy 29.999863 -326.504379) (xy 29.955519 -326.501912) (xy 29.911421 -326.507188) (xy 29.868911 -326.520046)
			(xy 29.829282 -326.540095) (xy 29.793739 -326.566725) (xy 29.763364 -326.599126) (xy 29.739082 -326.636313)
			(xy 29.72163 -326.677153) (xy 29.711541 -326.720404) (xy 29.709872 -326.742552) (xy 29.709872 -326.967107)
			(xy 55.2985 -326.967107) (xy 55.302386 -326.912757) (xy 55.313968 -326.859513) (xy 55.333009 -326.808459)
			(xy 55.359122 -326.760635) (xy 55.391776 -326.717013) (xy 55.430305 -326.678483) (xy 55.473925 -326.645828)
			(xy 55.521749 -326.619714) (xy 55.572802 -326.600671) (xy 55.626046 -326.589088) (xy 55.680396 -326.5852)
			(xy 55.734746 -326.589087) (xy 55.78799 -326.600669) (xy 55.839044 -326.61971) (xy 55.886868 -326.645824)
			(xy 55.908956 -326.66178) (xy 55.927968 -326.675376) (xy 55.969851 -326.696108) (xy 56.014819 -326.708834)
			(xy 56.061356 -326.713124) (xy 56.107893 -326.708834) (xy 56.152861 -326.696108) (xy 56.194744 -326.675376)
			(xy 56.213756 -326.66178) (xy 56.235856 -326.645833) (xy 56.283684 -326.619706) (xy 56.334744 -326.600653)
			(xy 56.387995 -326.589061) (xy 56.442354 -326.585167) (xy 56.496714 -326.589048) (xy 56.549968 -326.600627)
			(xy 56.601032 -326.619668) (xy 56.648866 -326.645783) (xy 56.692497 -326.67844) (xy 56.731035 -326.716974)
			(xy 56.763696 -326.760601) (xy 56.789816 -326.808433) (xy 56.808862 -326.859495) (xy 56.820446 -326.912748)
			(xy 56.824333 -326.967107) (xy 57.185193 -326.967107) (xy 57.189079 -326.912755) (xy 57.200661 -326.85951)
			(xy 57.219703 -326.808454) (xy 57.245817 -326.760629) (xy 57.278472 -326.717006) (xy 57.317003 -326.678475)
			(xy 57.360625 -326.64582) (xy 57.40845 -326.619705) (xy 57.459505 -326.600663) (xy 57.512751 -326.58908)
			(xy 57.567103 -326.585193) (xy 57.621455 -326.589081) (xy 57.6747 -326.600664) (xy 57.725755 -326.619707)
			(xy 57.77358 -326.645823) (xy 57.795668 -326.66178) (xy 57.81468 -326.675376) (xy 57.856563 -326.696108)
			(xy 57.901531 -326.708834) (xy 57.948068 -326.713124) (xy 57.994605 -326.708834) (xy 58.039573 -326.696108)
			(xy 58.081456 -326.675376) (xy 58.100468 -326.66178) (xy 58.122568 -326.645834) (xy 58.170395 -326.619709)
			(xy 58.221453 -326.600658) (xy 58.274703 -326.589068) (xy 58.329061 -326.585174) (xy 58.383419 -326.589056)
			(xy 58.436672 -326.600636) (xy 58.487734 -326.619677) (xy 58.535566 -326.645791) (xy 58.579195 -326.678448)
			(xy 58.617731 -326.716981) (xy 58.650391 -326.760607) (xy 58.67651 -326.808437) (xy 58.695555 -326.859498)
			(xy 58.707139 -326.912749) (xy 58.711026 -326.967107) (xy 58.707137 -327.021465) (xy 58.695551 -327.074716)
			(xy 58.676504 -327.125776) (xy 58.650384 -327.173605) (xy 58.617722 -327.21723) (xy 58.579184 -327.255762)
			(xy 58.535554 -327.288416) (xy 58.487721 -327.314529) (xy 58.436658 -327.333568) (xy 58.383405 -327.345146)
			(xy 58.329047 -327.349026) (xy 58.274689 -327.34513) (xy 58.22144 -327.333538) (xy 58.170382 -327.314485)
			(xy 58.122556 -327.288359) (xy 58.100468 -327.272396) (xy 58.081456 -327.2588) (xy 58.039573 -327.238068)
			(xy 57.994605 -327.225342) (xy 57.948068 -327.221052) (xy 57.901531 -327.225342) (xy 57.856563 -327.238068)
			(xy 57.81468 -327.2588) (xy 57.795668 -327.272396) (xy 57.773592 -327.288369) (xy 57.725768 -327.314487)
			(xy 57.674714 -327.333532) (xy 57.621469 -327.345117) (xy 57.567117 -327.349007) (xy 57.512765 -327.345122)
			(xy 57.459519 -327.333541) (xy 57.408463 -327.314501) (xy 57.360637 -327.288388) (xy 57.317014 -327.255734)
			(xy 57.278482 -327.217205) (xy 57.245825 -327.173584) (xy 57.219709 -327.125759) (xy 57.200665 -327.074704)
			(xy 57.189081 -327.021459) (xy 57.185193 -326.967107) (xy 56.824333 -326.967107) (xy 56.820444 -327.021467)
			(xy 56.808858 -327.074719) (xy 56.78981 -327.125781) (xy 56.763688 -327.173611) (xy 56.731025 -327.217237)
			(xy 56.692486 -327.25577) (xy 56.648854 -327.288425) (xy 56.601019 -327.314538) (xy 56.549954 -327.333577)
			(xy 56.4967 -327.345154) (xy 56.44234 -327.349033) (xy 56.387981 -327.345136) (xy 56.33473 -327.333543)
			(xy 56.283671 -327.314488) (xy 56.235844 -327.28836) (xy 56.213756 -327.272396) (xy 56.194744 -327.2588)
			(xy 56.152861 -327.238068) (xy 56.107893 -327.225342) (xy 56.061356 -327.221052) (xy 56.014819 -327.225342)
			(xy 55.969851 -327.238068) (xy 55.927968 -327.2588) (xy 55.908956 -327.272396) (xy 55.88688 -327.288368)
			(xy 55.839057 -327.314484) (xy 55.788004 -327.333527) (xy 55.73476 -327.345111) (xy 55.68041 -327.349)
			(xy 55.62606 -327.345114) (xy 55.572816 -327.333533) (xy 55.521762 -327.314492) (xy 55.473937 -327.288379)
			(xy 55.430316 -327.255726) (xy 55.391785 -327.217198) (xy 55.35913 -327.173578) (xy 55.333015 -327.125754)
			(xy 55.313972 -327.074701) (xy 55.302388 -327.021457) (xy 55.2985 -326.967107) (xy 29.709872 -326.967107)
			(xy 29.709872 -327.137268) (xy 29.711583 -327.159403) (xy 29.721698 -327.202627) (xy 29.739164 -327.243439)
			(xy 29.763451 -327.280598) (xy 29.793821 -327.312975) (xy 29.829351 -327.339588) (xy 29.868962 -327.359628)
			(xy 29.911451 -327.372486) (xy 29.955527 -327.377772) (xy 29.999851 -327.375324) (xy 30.043078 -327.365218)
			(xy 30.063694 -327.356978) (xy 30.103694 -327.338964) (xy 30.186362 -327.309591) (xy 30.271408 -327.288045)
			(xy 30.35809 -327.274515) (xy 30.445656 -327.269117) (xy 30.533343 -327.271898) (xy 30.620391 -327.282835)
			(xy 30.706041 -327.301833) (xy 30.78955 -327.328725) (xy 30.870191 -327.363279) (xy 30.947263 -327.405193)
			(xy 31.020096 -327.454104) (xy 31.088056 -327.509587) (xy 31.150553 -327.571158) (xy 31.207044 -327.638282)
			(xy 31.257037 -327.710376) (xy 31.300098 -327.786814) (xy 31.335852 -327.86693) (xy 31.363988 -327.950027)
			(xy 31.384262 -328.035385) (xy 31.396497 -328.122259) (xy 31.400588 -328.209896) (xy 31.39856 -328.25336)
			(xy 34.599874 -328.25336) (xy 34.599874 -328.16646) (xy 34.607892 -328.079931) (xy 34.62386 -327.994511)
			(xy 34.647641 -327.910929) (xy 34.679033 -327.829897) (xy 34.717767 -327.752108) (xy 34.763514 -327.678224)
			(xy 34.815883 -327.608877) (xy 34.874427 -327.544657) (xy 34.938647 -327.486113) (xy 35.007994 -327.433744)
			(xy 35.081878 -327.387997) (xy 35.159667 -327.349263) (xy 35.240699 -327.317871) (xy 35.324281 -327.29409)
			(xy 35.409701 -327.278122) (xy 35.49623 -327.270104) (xy 35.58313 -327.270104) (xy 35.669659 -327.278122)
			(xy 35.755079 -327.29409) (xy 35.838661 -327.317871) (xy 35.919693 -327.349263) (xy 35.997482 -327.387997)
			(xy 36.071366 -327.433744) (xy 36.140713 -327.486113) (xy 36.147283 -327.492102) (xy 82.83751 -327.492102)
			(xy 82.83751 -327.432166) (xy 82.845333 -327.372744) (xy 82.860846 -327.314851) (xy 82.883782 -327.259478)
			(xy 82.913749 -327.207572) (xy 82.950236 -327.160022) (xy 82.992616 -327.117642) (xy 83.040166 -327.081155)
			(xy 83.092072 -327.051188) (xy 83.147445 -327.028252) (xy 83.205338 -327.012739) (xy 83.26476 -327.004916)
			(xy 83.324696 -327.004916) (xy 83.384118 -327.012739) (xy 83.442011 -327.028252) (xy 83.497384 -327.051188)
			(xy 83.54929 -327.081155) (xy 83.59684 -327.117642) (xy 83.63922 -327.160022) (xy 83.675707 -327.207572)
			(xy 83.705674 -327.259478) (xy 83.72861 -327.314851) (xy 83.744123 -327.372744) (xy 83.751946 -327.432166)
			(xy 83.752436 -327.462134) (xy 83.751946 -327.492102) (xy 83.744123 -327.551524) (xy 83.72861 -327.609417)
			(xy 83.705674 -327.66479) (xy 83.675707 -327.716696) (xy 83.63922 -327.764246) (xy 83.59684 -327.806626)
			(xy 83.54929 -327.843113) (xy 83.497384 -327.87308) (xy 83.442011 -327.896016) (xy 83.384118 -327.911529)
			(xy 83.324696 -327.919352) (xy 83.26476 -327.919352) (xy 83.205338 -327.911529) (xy 83.147445 -327.896016)
			(xy 83.092072 -327.87308) (xy 83.040166 -327.843113) (xy 82.992616 -327.806626) (xy 82.950236 -327.764246)
			(xy 82.913749 -327.716696) (xy 82.883782 -327.66479) (xy 82.860846 -327.609417) (xy 82.845333 -327.551524)
			(xy 82.83751 -327.492102) (xy 36.147283 -327.492102) (xy 36.204933 -327.544657) (xy 36.263477 -327.608877)
			(xy 36.315846 -327.678224) (xy 36.361593 -327.752108) (xy 36.400327 -327.829897) (xy 36.431719 -327.910929)
			(xy 36.4555 -327.994511) (xy 36.471468 -328.079931) (xy 36.479486 -328.16646) (xy 36.479988 -328.20991)
			(xy 36.479486 -328.25336) (xy 36.471468 -328.339889) (xy 36.4555 -328.425309) (xy 36.431719 -328.508891)
			(xy 36.400327 -328.589923) (xy 36.361593 -328.667712) (xy 36.315846 -328.741596) (xy 36.271218 -328.800692)
			(xy 55.298521 -328.800692) (xy 55.302409 -328.746344) (xy 55.313992 -328.693104) (xy 55.333035 -328.642053)
			(xy 55.359148 -328.594233) (xy 55.391802 -328.550615) (xy 55.43033 -328.512089) (xy 55.473949 -328.479437)
			(xy 55.521771 -328.453326) (xy 55.572823 -328.434287) (xy 55.626064 -328.422706) (xy 55.680411 -328.418821)
			(xy 55.734759 -328.42271) (xy 55.787999 -328.434293) (xy 55.839049 -328.453336) (xy 55.88687 -328.47945)
			(xy 55.908956 -328.495406) (xy 55.927968 -328.509002) (xy 55.969851 -328.529734) (xy 56.014819 -328.54246)
			(xy 56.061356 -328.54675) (xy 56.107893 -328.54246) (xy 56.152861 -328.529734) (xy 56.194744 -328.509002)
			(xy 56.213756 -328.495406) (xy 56.235832 -328.479423) (xy 56.283661 -328.453294) (xy 56.334723 -328.434238)
			(xy 56.387977 -328.422643) (xy 56.442339 -328.418746) (xy 56.496702 -328.422626) (xy 56.549959 -328.434203)
			(xy 56.601027 -328.453243) (xy 56.648864 -328.479357) (xy 56.692499 -328.512014) (xy 56.73104 -328.550549)
			(xy 56.763705 -328.594177) (xy 56.789828 -328.64201) (xy 56.808877 -328.693074) (xy 56.820464 -328.746329)
			(xy 56.824354 -328.800692) (xy 57.185214 -328.800692) (xy 57.189102 -328.746343) (xy 57.200686 -328.6931)
			(xy 57.219729 -328.642049) (xy 57.245843 -328.594227) (xy 57.278498 -328.550608) (xy 57.317028 -328.512081)
			(xy 57.360649 -328.479429) (xy 57.408473 -328.453318) (xy 57.459526 -328.434278) (xy 57.512769 -328.422698)
			(xy 57.567118 -328.418814) (xy 57.621467 -328.422704) (xy 57.674709 -328.434289) (xy 57.72576 -328.453333)
			(xy 57.773582 -328.479449) (xy 57.795668 -328.495406) (xy 57.81468 -328.509002) (xy 57.856563 -328.529734)
			(xy 57.901531 -328.54246) (xy 57.948068 -328.54675) (xy 57.994605 -328.54246) (xy 58.039573 -328.529734)
			(xy 58.081456 -328.509002) (xy 58.100468 -328.495406) (xy 58.122544 -328.479424) (xy 58.170372 -328.453297)
			(xy 58.221433 -328.434242) (xy 58.274685 -328.422649) (xy 58.329045 -328.418753) (xy 58.383407 -328.422634)
			(xy 58.436663 -328.434212) (xy 58.487728 -328.453251) (xy 58.535564 -328.479365) (xy 58.579197 -328.512022)
			(xy 58.617737 -328.550556) (xy 58.650401 -328.594183) (xy 58.676522 -328.642014) (xy 58.695571 -328.693077)
			(xy 58.707157 -328.746331) (xy 58.711047 -328.800692) (xy 59.426189 -328.800692) (xy 59.430078 -328.746337)
			(xy 59.441663 -328.693089) (xy 59.460709 -328.642032) (xy 59.486827 -328.594206) (xy 59.519486 -328.550583)
			(xy 59.558022 -328.512053) (xy 59.601648 -328.4794) (xy 59.649478 -328.453288) (xy 59.700538 -328.434249)
			(xy 59.753787 -328.42267) (xy 59.808142 -328.418789) (xy 59.862496 -328.422682) (xy 59.915743 -328.434272)
			(xy 59.966798 -328.453323) (xy 60.014623 -328.479445) (xy 60.03671 -328.495406) (xy 60.055722 -328.509002)
			(xy 60.097605 -328.529734) (xy 60.142573 -328.54246) (xy 60.18911 -328.54675) (xy 60.235647 -328.54246)
			(xy 60.280615 -328.529734) (xy 60.322498 -328.509002) (xy 60.34151 -328.495406) (xy 60.363585 -328.479428)
			(xy 60.41141 -328.453307) (xy 60.462467 -328.434259) (xy 60.515714 -328.42267) (xy 60.570069 -328.418778)
			(xy 60.624425 -328.422662) (xy 60.677674 -328.434241) (xy 60.728734 -328.453282) (xy 60.776563 -328.479395)
			(xy 60.82019 -328.512049) (xy 60.858725 -328.55058) (xy 60.891384 -328.594204) (xy 60.917502 -328.642031)
			(xy 60.936548 -328.693088) (xy 60.948133 -328.746337) (xy 60.952022 -328.800692) (xy 61.330198 -328.800692)
			(xy 61.334087 -328.746339) (xy 61.345672 -328.693093) (xy 61.364716 -328.642039) (xy 61.390833 -328.594214)
			(xy 61.423491 -328.550593) (xy 61.462024 -328.512064) (xy 61.505649 -328.479411) (xy 61.553476 -328.453299)
			(xy 61.604533 -328.43426) (xy 61.65778 -328.422681) (xy 61.712133 -328.418798) (xy 61.766485 -328.422691)
			(xy 61.81973 -328.434279) (xy 61.870784 -328.453326) (xy 61.918607 -328.479447) (xy 61.940694 -328.495406)
			(xy 61.959706 -328.509002) (xy 62.001589 -328.529734) (xy 62.046557 -328.54246) (xy 62.093094 -328.54675)
			(xy 62.139631 -328.54246) (xy 62.184599 -328.529734) (xy 62.226482 -328.509002) (xy 62.245494 -328.495406)
			(xy 62.267569 -328.479427) (xy 62.315396 -328.453303) (xy 62.366454 -328.434252) (xy 62.419703 -328.422662)
			(xy 62.47406 -328.418769) (xy 62.528418 -328.422651) (xy 62.58167 -328.43423) (xy 62.632732 -328.45327)
			(xy 62.680564 -328.479384) (xy 62.724193 -328.512039) (xy 62.748457 -328.5363) (xy 64.789699 -328.5363)
			(xy 64.793586 -328.481949) (xy 64.805169 -328.428704) (xy 64.824212 -328.377649) (xy 64.850327 -328.329825)
			(xy 64.882982 -328.286204) (xy 64.921514 -328.247674) (xy 64.965136 -328.21502) (xy 65.012961 -328.188907)
			(xy 65.064016 -328.169866) (xy 65.117262 -328.158285) (xy 65.171613 -328.154399) (xy 65.225964 -328.158288)
			(xy 65.279209 -328.169873) (xy 65.330263 -328.188918) (xy 65.378086 -328.215034) (xy 65.400174 -328.230992)
			(xy 65.419186 -328.244588) (xy 65.461069 -328.26532) (xy 65.506037 -328.278046) (xy 65.552574 -328.282336)
			(xy 65.599111 -328.278046) (xy 65.644079 -328.26532) (xy 65.685962 -328.244588) (xy 65.704974 -328.230992)
			(xy 65.727063 -328.21503) (xy 65.77489 -328.188905) (xy 65.825949 -328.169853) (xy 65.879199 -328.158262)
			(xy 65.933557 -328.154368) (xy 65.987916 -328.15825) (xy 66.041169 -328.169829) (xy 66.092232 -328.188869)
			(xy 66.140065 -328.214984) (xy 66.183695 -328.24764) (xy 66.222232 -328.286173) (xy 66.254893 -328.329799)
			(xy 66.281013 -328.377629) (xy 66.300059 -328.42869) (xy 66.311644 -328.481942) (xy 66.315532 -328.5363)
			(xy 67.594091 -328.5363) (xy 67.597978 -328.481947) (xy 67.609562 -328.4287) (xy 67.628605 -328.377644)
			(xy 67.654722 -328.329818) (xy 67.687379 -328.286195) (xy 67.725911 -328.247665) (xy 67.769536 -328.21501)
			(xy 67.817363 -328.188897) (xy 67.86842 -328.169856) (xy 67.921668 -328.158275) (xy 67.976021 -328.154391)
			(xy 68.030374 -328.158281) (xy 68.08362 -328.169868) (xy 68.134675 -328.188914) (xy 68.1825 -328.215033)
			(xy 68.204588 -328.230992) (xy 68.2236 -328.244588) (xy 68.265483 -328.26532) (xy 68.310451 -328.278046)
			(xy 68.356988 -328.282336) (xy 68.403525 -328.278046) (xy 68.448493 -328.26532) (xy 68.490376 -328.244588)
			(xy 68.509388 -328.230992) (xy 68.531476 -328.215031) (xy 68.579303 -328.188908) (xy 68.63036 -328.169858)
			(xy 68.683609 -328.158269) (xy 68.737965 -328.154376) (xy 68.792322 -328.158259) (xy 68.845573 -328.169839)
			(xy 68.896634 -328.188879) (xy 68.944465 -328.214993) (xy 68.988092 -328.247649) (xy 69.026628 -328.286181)
			(xy 69.059288 -328.329806) (xy 69.085406 -328.377635) (xy 69.104451 -328.428694) (xy 69.116036 -328.481943)
			(xy 69.119924 -328.5363) (xy 69.116036 -328.590657) (xy 69.104451 -328.643906) (xy 69.085406 -328.694965)
			(xy 69.059288 -328.742794) (xy 69.026628 -328.786419) (xy 68.988092 -328.824951) (xy 68.944465 -328.857607)
			(xy 68.896634 -328.883721) (xy 68.845573 -328.902761) (xy 68.792322 -328.914341) (xy 68.737965 -328.918224)
			(xy 68.683609 -328.914331) (xy 68.63036 -328.902742) (xy 68.579303 -328.883692) (xy 68.531476 -328.857569)
			(xy 68.509388 -328.841608) (xy 68.490376 -328.828012) (xy 68.448493 -328.80728) (xy 68.403525 -328.794554)
			(xy 68.356988 -328.790264) (xy 68.310451 -328.794554) (xy 68.265483 -328.80728) (xy 68.2236 -328.828012)
			(xy 68.204588 -328.841608) (xy 68.1825 -328.857567) (xy 68.134675 -328.883686) (xy 68.08362 -328.902732)
			(xy 68.030374 -328.914319) (xy 67.976021 -328.918209) (xy 67.921668 -328.914325) (xy 67.86842 -328.902744)
			(xy 67.817363 -328.883703) (xy 67.769536 -328.85759) (xy 67.725911 -328.824935) (xy 67.687379 -328.786405)
			(xy 67.654722 -328.742782) (xy 67.628605 -328.694956) (xy 67.609562 -328.6439) (xy 67.597978 -328.590653)
			(xy 67.594091 -328.5363) (xy 66.315532 -328.5363) (xy 66.311644 -328.590658) (xy 66.300059 -328.64391)
			(xy 66.281013 -328.694971) (xy 66.254893 -328.742801) (xy 66.222232 -328.786427) (xy 66.183695 -328.82496)
			(xy 66.140065 -328.857616) (xy 66.092232 -328.883731) (xy 66.041169 -328.902771) (xy 65.987916 -328.91435)
			(xy 65.933557 -328.918232) (xy 65.879199 -328.914338) (xy 65.825949 -328.902747) (xy 65.77489 -328.883695)
			(xy 65.727063 -328.85757) (xy 65.704974 -328.841608) (xy 65.685962 -328.828012) (xy 65.644079 -328.80728)
			(xy 65.599111 -328.794554) (xy 65.552574 -328.790264) (xy 65.506037 -328.794554) (xy 65.461069 -328.80728)
			(xy 65.419186 -328.828012) (xy 65.400174 -328.841608) (xy 65.378086 -328.857566) (xy 65.330263 -328.883682)
			(xy 65.279209 -328.902727) (xy 65.225964 -328.914312) (xy 65.171613 -328.918201) (xy 65.117262 -328.914315)
			(xy 65.064016 -328.902734) (xy 65.012961 -328.883693) (xy 64.965136 -328.85758) (xy 64.921514 -328.824926)
			(xy 64.882982 -328.786396) (xy 64.850327 -328.742775) (xy 64.824212 -328.694951) (xy 64.805169 -328.643896)
			(xy 64.793586 -328.590651) (xy 64.789699 -328.5363) (xy 62.748457 -328.5363) (xy 62.76273 -328.550571)
			(xy 62.79539 -328.594196) (xy 62.82151 -328.642025) (xy 62.840556 -328.693084) (xy 62.852142 -328.746334)
			(xy 62.856031 -328.800692) (xy 62.852145 -328.855049) (xy 62.840561 -328.9083) (xy 62.821517 -328.95936)
			(xy 62.795399 -329.00719) (xy 62.762741 -329.050816) (xy 62.724205 -329.08935) (xy 62.680578 -329.122007)
			(xy 62.632747 -329.148123) (xy 62.581686 -329.167165) (xy 62.528435 -329.178747) (xy 62.474077 -329.182631)
			(xy 62.41972 -329.17874) (xy 62.36647 -329.167152) (xy 62.315411 -329.148104) (xy 62.267583 -329.121982)
			(xy 62.245494 -329.106022) (xy 62.226482 -329.092426) (xy 62.184599 -329.071694) (xy 62.139631 -329.058968)
			(xy 62.093094 -329.054678) (xy 62.046557 -329.058968) (xy 62.001589 -329.071694) (xy 61.959706 -329.092426)
			(xy 61.940694 -329.106022) (xy 61.918593 -329.121963) (xy 61.870769 -329.14808) (xy 61.819714 -329.167126)
			(xy 61.766469 -329.178712) (xy 61.712116 -329.182602) (xy 61.657764 -329.178717) (xy 61.604517 -329.167135)
			(xy 61.553461 -329.148094) (xy 61.505634 -329.12198) (xy 61.462011 -329.089325) (xy 61.42348 -329.050795)
			(xy 61.390824 -329.007172) (xy 61.364709 -328.959346) (xy 61.345667 -328.90829) (xy 61.334085 -328.855044)
			(xy 61.330198 -328.800692) (xy 60.952022 -328.800692) (xy 60.948135 -328.855047) (xy 60.936552 -328.908296)
			(xy 60.917509 -328.959354) (xy 60.891393 -329.007182) (xy 60.858736 -329.050807) (xy 60.820203 -329.08934)
			(xy 60.776578 -329.121996) (xy 60.728749 -329.148111) (xy 60.67769 -329.167154) (xy 60.624441 -329.178736)
			(xy 60.570086 -329.182622) (xy 60.515731 -329.178732) (xy 60.462483 -329.167146) (xy 60.411426 -329.1481)
			(xy 60.363599 -329.121981) (xy 60.34151 -329.106022) (xy 60.322498 -329.092426) (xy 60.280615 -329.071694)
			(xy 60.235647 -329.058968) (xy 60.18911 -329.054678) (xy 60.142573 -329.058968) (xy 60.097605 -329.071694)
			(xy 60.055722 -329.092426) (xy 60.03671 -329.106022) (xy 60.014608 -329.121964) (xy 59.966783 -329.148084)
			(xy 59.915727 -329.167132) (xy 59.86248 -329.17872) (xy 59.808125 -329.182611) (xy 59.75377 -329.178727)
			(xy 59.700522 -329.167147) (xy 59.649463 -329.148105) (xy 59.601634 -329.121991) (xy 59.558009 -329.089336)
			(xy 59.519475 -329.050804) (xy 59.486818 -329.00718) (xy 59.460702 -328.959352) (xy 59.441658 -328.908295)
			(xy 59.430075 -328.855046) (xy 59.426189 -328.800692) (xy 58.711047 -328.800692) (xy 58.70716 -328.855053)
			(xy 58.695575 -328.908307) (xy 58.676529 -328.95937) (xy 58.65041 -329.007203) (xy 58.617748 -329.050832)
			(xy 58.579209 -329.089367) (xy 58.535578 -329.122026) (xy 58.487744 -329.148142) (xy 58.436679 -329.167184)
			(xy 58.383423 -329.178764) (xy 58.329062 -329.182647) (xy 58.274702 -329.178753) (xy 58.221449 -329.167162)
			(xy 58.170388 -329.14811) (xy 58.122558 -329.121985) (xy 58.100468 -329.106022) (xy 58.081456 -329.092426)
			(xy 58.039573 -329.071694) (xy 57.994605 -329.058968) (xy 57.948068 -329.054678) (xy 57.901531 -329.058968)
			(xy 57.856563 -329.071694) (xy 57.81468 -329.092426) (xy 57.795668 -329.106022) (xy 57.773567 -329.12196)
			(xy 57.725745 -329.148074) (xy 57.674693 -329.167116) (xy 57.62145 -329.178699) (xy 57.567101 -329.182586)
			(xy 57.512752 -329.178699) (xy 57.45951 -329.167117) (xy 57.408458 -329.148075) (xy 57.360635 -329.121962)
			(xy 57.317015 -329.089308) (xy 57.278487 -329.050779) (xy 57.245834 -329.007159) (xy 57.219722 -328.959336)
			(xy 57.200681 -328.908283) (xy 57.1891 -328.855041) (xy 57.185214 -328.800692) (xy 56.824354 -328.800692)
			(xy 56.820467 -328.855054) (xy 56.808882 -328.90831) (xy 56.789835 -328.959375) (xy 56.763714 -329.007209)
			(xy 56.731051 -329.050839) (xy 56.692511 -329.089375) (xy 56.648879 -329.122034) (xy 56.601042 -329.14815)
			(xy 56.549975 -329.167192) (xy 56.496718 -329.178772) (xy 56.442355 -329.182654) (xy 56.387993 -329.178759)
			(xy 56.334739 -329.167167) (xy 56.283677 -329.148113) (xy 56.235846 -329.121986) (xy 56.213756 -329.106022)
			(xy 56.194744 -329.092426) (xy 56.152861 -329.071694) (xy 56.107893 -329.058968) (xy 56.061356 -329.054678)
			(xy 56.014819 -329.058968) (xy 55.969851 -329.071694) (xy 55.927968 -329.092426) (xy 55.908956 -329.106022)
			(xy 55.886856 -329.121959) (xy 55.839034 -329.148071) (xy 55.787983 -329.167112) (xy 55.734742 -329.178693)
			(xy 55.680395 -329.182579) (xy 55.626047 -329.178691) (xy 55.572807 -329.167108) (xy 55.521756 -329.148067)
			(xy 55.473935 -329.121954) (xy 55.430317 -329.0893) (xy 55.391791 -329.050772) (xy 55.359139 -329.007153)
			(xy 55.333028 -328.959331) (xy 55.313988 -328.90828) (xy 55.302407 -328.855039) (xy 55.298521 -328.800692)
			(xy 36.271218 -328.800692) (xy 36.263477 -328.810943) (xy 36.204933 -328.875163) (xy 36.140713 -328.933707)
			(xy 36.071366 -328.986076) (xy 35.997482 -329.031823) (xy 35.919693 -329.070557) (xy 35.838661 -329.101949)
			(xy 35.755079 -329.12573) (xy 35.669659 -329.141698) (xy 35.618829 -329.146408) (xy 51.402996 -329.146408)
			(xy 53.055012 -329.146408) (xy 53.055012 -330.70157) (xy 55.29855 -330.70157) (xy 55.302441 -330.647227)
			(xy 55.314026 -330.593991) (xy 55.33307 -330.542946) (xy 55.359184 -330.49513) (xy 55.391837 -330.451518)
			(xy 55.430365 -330.412996) (xy 55.473983 -330.38035) (xy 55.521803 -330.354244) (xy 55.572852 -330.335208)
			(xy 55.626089 -330.323632) (xy 55.680433 -330.31975) (xy 55.734776 -330.323641) (xy 55.788012 -330.335227)
			(xy 55.839057 -330.354271) (xy 55.886872 -330.380386) (xy 55.908956 -330.396342) (xy 55.927968 -330.409938)
			(xy 55.969851 -330.43067) (xy 56.014819 -330.443396) (xy 56.061356 -330.447686) (xy 56.107893 -330.443396)
			(xy 56.152861 -330.43067) (xy 56.194744 -330.409938) (xy 56.213756 -330.396342) (xy 56.235798 -330.380311)
			(xy 56.28363 -330.354177) (xy 56.334694 -330.335116) (xy 56.387951 -330.323518) (xy 56.442317 -330.319617)
			(xy 56.496684 -330.323494) (xy 56.549947 -330.335069) (xy 56.601019 -330.354108) (xy 56.648862 -330.380221)
			(xy 56.692501 -330.412878) (xy 56.731048 -330.451413) (xy 56.763718 -330.495043) (xy 56.789845 -330.542878)
			(xy 56.808899 -330.593945) (xy 56.82049 -330.647204) (xy 56.824383 -330.70157) (xy 57.185243 -330.70157)
			(xy 57.189134 -330.647225) (xy 57.20072 -330.593988) (xy 57.219764 -330.542941) (xy 57.245879 -330.495124)
			(xy 57.278534 -330.451511) (xy 57.317063 -330.412988) (xy 57.360683 -330.380342) (xy 57.408505 -330.354235)
			(xy 57.459555 -330.3352) (xy 57.512795 -330.323624) (xy 57.56714 -330.319743) (xy 57.621484 -330.323635)
			(xy 57.674722 -330.335222) (xy 57.725768 -330.354268) (xy 57.773584 -330.380385) (xy 57.795668 -330.396342)
			(xy 57.81468 -330.409938) (xy 57.856563 -330.43067) (xy 57.901531 -330.443396) (xy 57.948068 -330.447686)
			(xy 57.994605 -330.443396) (xy 58.039573 -330.43067) (xy 58.081456 -330.409938) (xy 58.100468 -330.396342)
			(xy 58.12251 -330.380312) (xy 58.170341 -330.35418) (xy 58.221404 -330.335121) (xy 58.27466 -330.323524)
			(xy 58.329024 -330.319624) (xy 58.383389 -330.323502) (xy 58.43665 -330.335078) (xy 58.487721 -330.354116)
			(xy 58.535562 -330.380229) (xy 58.579199 -330.412886) (xy 58.617745 -330.451421) (xy 58.650413 -330.495049)
			(xy 58.67654 -330.542883) (xy 58.695592 -330.593948) (xy 58.707183 -330.647205) (xy 58.711076 -330.70157)
			(xy 59.426218 -330.70157) (xy 59.430109 -330.64722) (xy 59.441697 -330.593977) (xy 59.460744 -330.542925)
			(xy 59.486863 -330.495103) (xy 59.519522 -330.451486) (xy 59.558057 -330.412961) (xy 59.601682 -330.380312)
			(xy 59.64951 -330.354205) (xy 59.700567 -330.33517) (xy 59.753813 -330.323596) (xy 59.808164 -330.319718)
			(xy 59.862514 -330.323614) (xy 59.915756 -330.335206) (xy 59.966806 -330.354258) (xy 60.014625 -330.380381)
			(xy 60.03671 -330.396342) (xy 60.055722 -330.409938) (xy 60.097605 -330.43067) (xy 60.142573 -330.443396)
			(xy 60.18911 -330.447686) (xy 60.235647 -330.443396) (xy 60.280615 -330.43067) (xy 60.322498 -330.409938)
			(xy 60.34151 -330.396342) (xy 60.363551 -330.380315) (xy 60.411379 -330.35419) (xy 60.462438 -330.335137)
			(xy 60.515689 -330.323545) (xy 60.570048 -330.319649) (xy 60.624407 -330.32353) (xy 60.677662 -330.335108)
			(xy 60.728726 -330.354146) (xy 60.776561 -330.380259) (xy 60.820193 -330.412913) (xy 60.858733 -330.451445)
			(xy 60.891397 -330.49507) (xy 60.917519 -330.542899) (xy 60.936569 -330.593959) (xy 60.948158 -330.647211)
			(xy 60.952051 -330.70157) (xy 61.330227 -330.70157) (xy 61.334119 -330.647222) (xy 61.345705 -330.593981)
			(xy 61.364751 -330.542931) (xy 61.390869 -330.495111) (xy 61.423527 -330.451495) (xy 61.462059 -330.412971)
			(xy 61.505682 -330.380323) (xy 61.553508 -330.354216) (xy 61.604562 -330.335182) (xy 61.657806 -330.323607)
			(xy 61.712155 -330.319727) (xy 61.766502 -330.323622) (xy 61.819743 -330.335212) (xy 61.870792 -330.354262)
			(xy 61.91861 -330.380382) (xy 61.940694 -330.396342) (xy 61.959706 -330.409938) (xy 62.001589 -330.43067)
			(xy 62.046557 -330.443396) (xy 62.093094 -330.447686) (xy 62.139631 -330.443396) (xy 62.184599 -330.43067)
			(xy 62.226482 -330.409938) (xy 62.245494 -330.396342) (xy 62.267535 -330.380314) (xy 62.315364 -330.354186)
			(xy 62.366425 -330.335131) (xy 62.419678 -330.323537) (xy 62.474039 -330.31964) (xy 62.528401 -330.323519)
			(xy 62.581657 -330.335096) (xy 62.632724 -330.354135) (xy 62.680561 -330.380248) (xy 62.724195 -330.412903)
			(xy 62.762737 -330.451436) (xy 62.795403 -330.495062) (xy 62.821527 -330.542893) (xy 62.840578 -330.593955)
			(xy 62.852168 -330.647209) (xy 62.85606 -330.70157) (xy 62.852176 -330.755932) (xy 62.840595 -330.809187)
			(xy 62.821552 -330.860252) (xy 62.795537 -330.907901) (xy 64.789697 -330.907901) (xy 64.793585 -330.85355)
			(xy 64.805168 -330.800304) (xy 64.82421 -330.74925) (xy 64.850325 -330.701425) (xy 64.88298 -330.657803)
			(xy 64.921512 -330.619273) (xy 64.965134 -330.586619) (xy 65.01296 -330.560506) (xy 65.064015 -330.541464)
			(xy 65.11726 -330.529883) (xy 65.171612 -330.525997) (xy 65.225964 -330.529887) (xy 65.279208 -330.541471)
			(xy 65.330262 -330.560516) (xy 65.378086 -330.586632) (xy 65.400174 -330.60259) (xy 65.419186 -330.616186)
			(xy 65.461069 -330.636918) (xy 65.506037 -330.649644) (xy 65.552574 -330.653934) (xy 65.599111 -330.649644)
			(xy 65.644079 -330.636918) (xy 65.685962 -330.616186) (xy 65.704974 -330.60259) (xy 65.727065 -330.586631)
			(xy 65.774892 -330.560506) (xy 65.82595 -330.541454) (xy 65.879201 -330.529863) (xy 65.933558 -330.525969)
			(xy 65.987917 -330.529852) (xy 66.04117 -330.541431) (xy 66.092232 -330.560471) (xy 66.140065 -330.586586)
			(xy 66.183695 -330.619242) (xy 66.222232 -330.657775) (xy 66.254893 -330.701401) (xy 66.281012 -330.749231)
			(xy 66.300058 -330.800291) (xy 66.311643 -330.853543) (xy 66.315531 -330.907901) (xy 67.594089 -330.907901)
			(xy 67.597976 -330.853548) (xy 67.60956 -330.800301) (xy 67.628604 -330.749244) (xy 67.65472 -330.701418)
			(xy 67.687377 -330.657795) (xy 67.725909 -330.619264) (xy 67.769534 -330.586609) (xy 67.817361 -330.560496)
			(xy 67.868419 -330.541455) (xy 67.921666 -330.529874) (xy 67.97602 -330.525989) (xy 68.030373 -330.529879)
			(xy 68.08362 -330.541466) (xy 68.134675 -330.560512) (xy 68.1825 -330.586631) (xy 68.204588 -330.60259)
			(xy 68.2236 -330.616186) (xy 68.265483 -330.636918) (xy 68.310451 -330.649644) (xy 68.356988 -330.653934)
			(xy 68.403525 -330.649644) (xy 68.448493 -330.636918) (xy 68.490376 -330.616186) (xy 68.509388 -330.60259)
			(xy 68.531478 -330.586632) (xy 68.579305 -330.560509) (xy 68.630362 -330.54146) (xy 68.68361 -330.529871)
			(xy 68.737966 -330.525978) (xy 68.792323 -330.529861) (xy 68.845574 -330.541441) (xy 68.896634 -330.560481)
			(xy 68.944465 -330.586595) (xy 68.988092 -330.619251) (xy 69.026628 -330.657783) (xy 69.059287 -330.701408)
			(xy 69.085405 -330.749236) (xy 69.10445 -330.800295) (xy 69.116034 -330.853545) (xy 69.119922 -330.907901)
			(xy 69.116034 -330.962258) (xy 69.104449 -331.015507) (xy 69.085404 -331.066566) (xy 69.059286 -331.114394)
			(xy 69.026626 -331.158019) (xy 69.024525 -331.16012) (xy 86.39887 -331.16012) (xy 86.402874 -330.960022)
			(xy 86.414881 -330.760244) (xy 86.434872 -330.561107) (xy 86.462814 -330.362929) (xy 86.498662 -330.166027)
			(xy 86.54236 -329.970718) (xy 86.593837 -329.777313) (xy 86.653011 -329.586123) (xy 86.719787 -329.397453)
			(xy 86.794059 -329.211606) (xy 86.875706 -329.028879) (xy 86.964599 -328.849566) (xy 87.060595 -328.673952)
			(xy 87.16354 -328.50232) (xy 87.27327 -328.334944) (xy 87.389608 -328.172093) (xy 87.512369 -328.014026)
			(xy 87.641356 -327.860998) (xy 87.776363 -327.713253) (xy 87.917172 -327.571027) (xy 88.063559 -327.43455)
			(xy 88.215289 -327.304038) (xy 88.37212 -327.179702) (xy 88.533799 -327.06174) (xy 88.700069 -326.950341)
			(xy 88.870662 -326.845684) (xy 89.045306 -326.747936) (xy 89.223722 -326.657253) (xy 89.405622 -326.573782)
			(xy 89.590717 -326.497655) (xy 89.778709 -326.428995) (xy 89.969298 -326.367911) (xy 90.162178 -326.314501)
			(xy 90.35704 -326.268852) (xy 90.553573 -326.231035) (xy 90.751462 -326.201111) (xy 90.950389 -326.179129)
			(xy 91.150037 -326.165124) (xy 91.350085 -326.159118) (xy 91.550213 -326.16112) (xy 91.750101 -326.171128)
			(xy 91.949428 -326.189125) (xy 92.147876 -326.215083) (xy 92.345126 -326.24896) (xy 92.540863 -326.290702)
			(xy 92.734773 -326.340241) (xy 92.926546 -326.397499) (xy 93.115875 -326.462384) (xy 93.302455 -326.534792)
			(xy 93.48599 -326.614608) (xy 93.666184 -326.701702) (xy 93.842749 -326.795936) (xy 94.015402 -326.897159)
			(xy 94.183867 -327.005209) (xy 94.347875 -327.119912) (xy 94.507162 -327.241086) (xy 94.661473 -327.368535)
			(xy 94.810561 -327.502056) (xy 94.954188 -327.641436) (xy 95.092124 -327.78645) (xy 95.224147 -327.936867)
			(xy 95.350046 -328.092445) (xy 95.46962 -328.252937) (xy 95.582676 -328.418083) (xy 95.689035 -328.587621)
			(xy 95.788526 -328.761279) (xy 95.880989 -328.938778) (xy 95.966276 -329.119834) (xy 96.044251 -329.304158)
			(xy 96.114788 -329.491454) (xy 96.177776 -329.681422) (xy 96.233113 -329.873758) (xy 96.28071 -330.068154)
			(xy 96.320491 -330.264299) (xy 96.352393 -330.461878) (xy 96.376364 -330.660575) (xy 96.392366 -330.860073)
			(xy 96.400373 -331.060051) (xy 96.400874 -331.16012) (xy 96.400373 -331.260189) (xy 96.392366 -331.460167)
			(xy 96.376364 -331.659665) (xy 96.352393 -331.858362) (xy 96.320491 -332.055941) (xy 96.28071 -332.252086)
			(xy 96.233113 -332.446482) (xy 96.177776 -332.638818) (xy 96.114788 -332.828786) (xy 96.044251 -333.016082)
			(xy 95.966276 -333.200406) (xy 95.880989 -333.381462) (xy 95.788526 -333.558961) (xy 95.689035 -333.732619)
			(xy 95.582676 -333.902157) (xy 95.46962 -334.067303) (xy 95.350046 -334.227795) (xy 95.224147 -334.383373)
			(xy 95.092124 -334.53379) (xy 94.954188 -334.678804) (xy 94.810561 -334.818184) (xy 94.661473 -334.951705)
			(xy 94.507162 -335.079154) (xy 94.347875 -335.200328) (xy 94.183867 -335.315031) (xy 94.015402 -335.423081)
			(xy 93.842749 -335.524304) (xy 93.666184 -335.618538) (xy 93.48599 -335.705632) (xy 93.302455 -335.785448)
			(xy 93.115875 -335.857856) (xy 92.926546 -335.922741) (xy 92.734773 -335.979999) (xy 92.540863 -336.029538)
			(xy 92.345126 -336.07128) (xy 92.147876 -336.105157) (xy 91.949428 -336.131115) (xy 91.750101 -336.149112)
			(xy 91.550213 -336.15912) (xy 91.350085 -336.161122) (xy 91.150037 -336.155116) (xy 90.950389 -336.141111)
			(xy 90.751462 -336.119129) (xy 90.553573 -336.089205) (xy 90.35704 -336.051388) (xy 90.162178 -336.005739)
			(xy 89.969298 -335.952329) (xy 89.778709 -335.891245) (xy 89.590717 -335.822585) (xy 89.405622 -335.746458)
			(xy 89.223722 -335.662987) (xy 89.045306 -335.572304) (xy 88.870662 -335.474556) (xy 88.700069 -335.369899)
			(xy 88.533799 -335.2585) (xy 88.37212 -335.140538) (xy 88.215289 -335.016202) (xy 88.063559 -334.88569)
			(xy 87.917172 -334.749213) (xy 87.776363 -334.606987) (xy 87.641356 -334.459242) (xy 87.512369 -334.306214)
			(xy 87.389608 -334.148147) (xy 87.27327 -333.985296) (xy 87.16354 -333.81792) (xy 87.060595 -333.646288)
			(xy 86.964599 -333.470674) (xy 86.875706 -333.291361) (xy 86.794059 -333.108634) (xy 86.719787 -332.922787)
			(xy 86.653011 -332.734117) (xy 86.593837 -332.542927) (xy 86.54236 -332.349522) (xy 86.498662 -332.154213)
			(xy 86.462814 -331.957311) (xy 86.434872 -331.759133) (xy 86.414881 -331.559996) (xy 86.402874 -331.360218)
			(xy 86.39887 -331.16012) (xy 69.024525 -331.16012) (xy 68.988091 -331.196551) (xy 68.944463 -331.229206)
			(xy 68.896632 -331.25532) (xy 68.845571 -331.27436) (xy 68.792321 -331.285939) (xy 68.737964 -331.289822)
			(xy 68.683608 -331.285929) (xy 68.630359 -331.27434) (xy 68.579302 -331.25529) (xy 68.531476 -331.229167)
			(xy 68.509388 -331.213206) (xy 68.490376 -331.19961) (xy 68.448493 -331.178878) (xy 68.403525 -331.166152)
			(xy 68.356988 -331.161862) (xy 68.310451 -331.166152) (xy 68.265483 -331.178878) (xy 68.2236 -331.19961)
			(xy 68.204588 -331.213206) (xy 68.182502 -331.229168) (xy 68.134677 -331.255287) (xy 68.083622 -331.274333)
			(xy 68.030376 -331.28592) (xy 67.976022 -331.289811) (xy 67.921669 -331.285927) (xy 67.868421 -331.274346)
			(xy 67.817364 -331.255305) (xy 67.769536 -331.229192) (xy 67.725911 -331.196537) (xy 67.687378 -331.158007)
			(xy 67.654721 -331.114384) (xy 67.628605 -331.066558) (xy 67.609561 -331.015502) (xy 67.597977 -330.962255)
			(xy 67.594089 -330.907901) (xy 66.315531 -330.907901) (xy 66.311642 -330.962259) (xy 66.300057 -331.015511)
			(xy 66.281011 -331.066571) (xy 66.254891 -331.114401) (xy 66.22223 -331.158027) (xy 66.183693 -331.19656)
			(xy 66.140063 -331.229216) (xy 66.09223 -331.25533) (xy 66.041167 -331.27437) (xy 65.987915 -331.285949)
			(xy 65.933556 -331.289831) (xy 65.879198 -331.285936) (xy 65.825948 -331.274345) (xy 65.77489 -331.255293)
			(xy 65.727063 -331.229168) (xy 65.704974 -331.213206) (xy 65.685962 -331.19961) (xy 65.644079 -331.178878)
			(xy 65.599111 -331.166152) (xy 65.552574 -331.161862) (xy 65.506037 -331.166152) (xy 65.461069 -331.178878)
			(xy 65.419186 -331.19961) (xy 65.400174 -331.213206) (xy 65.378088 -331.229166) (xy 65.330264 -331.255283)
			(xy 65.279211 -331.274328) (xy 65.225966 -331.285913) (xy 65.171614 -331.289803) (xy 65.117263 -331.285917)
			(xy 65.064017 -331.274336) (xy 65.012962 -331.255295) (xy 64.965136 -331.229182) (xy 64.921513 -331.196528)
			(xy 64.882982 -331.157998) (xy 64.850326 -331.114377) (xy 64.824211 -331.066552) (xy 64.805168 -331.015498)
			(xy 64.793585 -330.962253) (xy 64.789697 -330.907901) (xy 62.795537 -330.907901) (xy 62.795435 -330.908088)
			(xy 62.762777 -330.951719) (xy 62.72424 -330.990258) (xy 62.680612 -331.02292) (xy 62.632778 -331.04904)
			(xy 62.581715 -331.068087) (xy 62.52846 -331.079672) (xy 62.474099 -331.08356) (xy 62.419737 -331.079672)
			(xy 62.366483 -331.068086) (xy 62.315419 -331.049039) (xy 62.267586 -331.022918) (xy 62.245494 -331.006958)
			(xy 62.226482 -330.993362) (xy 62.184599 -330.97263) (xy 62.139631 -330.959904) (xy 62.093094 -330.955614)
			(xy 62.046557 -330.959904) (xy 62.001589 -330.97263) (xy 61.959706 -330.993362) (xy 61.940694 -331.006958)
			(xy 61.918559 -331.02285) (xy 61.870737 -331.048963) (xy 61.819685 -331.068005) (xy 61.766443 -331.079586)
			(xy 61.712095 -331.083473) (xy 61.657746 -331.079585) (xy 61.604505 -331.068002) (xy 61.553453 -331.048959)
			(xy 61.505632 -331.022844) (xy 61.462014 -330.990189) (xy 61.423487 -330.951659) (xy 61.390837 -330.908038)
			(xy 61.364727 -330.860215) (xy 61.345688 -330.809162) (xy 61.33411 -330.755919) (xy 61.330227 -330.70157)
			(xy 60.952051 -330.70157) (xy 60.948167 -330.75593) (xy 60.936586 -330.809183) (xy 60.917544 -330.860246)
			(xy 60.891429 -330.90808) (xy 60.858772 -330.951709) (xy 60.820238 -330.990247) (xy 60.776611 -331.022909)
			(xy 60.728781 -331.049029) (xy 60.677719 -331.068076) (xy 60.624467 -331.079661) (xy 60.570108 -331.083551)
			(xy 60.515748 -331.079664) (xy 60.462496 -331.06808) (xy 60.411433 -331.049035) (xy 60.363602 -331.022917)
			(xy 60.34151 -331.006958) (xy 60.322498 -330.993362) (xy 60.280615 -330.97263) (xy 60.235647 -330.959904)
			(xy 60.18911 -330.955614) (xy 60.142573 -330.959904) (xy 60.097605 -330.97263) (xy 60.055722 -330.993362)
			(xy 60.03671 -331.006958) (xy 60.014575 -331.022851) (xy 59.966751 -331.048967) (xy 59.915698 -331.068011)
			(xy 59.862454 -331.079595) (xy 59.808104 -331.083482) (xy 59.753753 -331.079596) (xy 59.700509 -331.068013)
			(xy 59.649455 -331.04897) (xy 59.601632 -331.022855) (xy 59.558011 -330.9902) (xy 59.519483 -330.951669)
			(xy 59.48683 -330.908046) (xy 59.460719 -330.860221) (xy 59.44168 -330.809166) (xy 59.430101 -330.755921)
			(xy 59.426218 -330.70157) (xy 58.711076 -330.70157) (xy 58.707191 -330.755935) (xy 58.695609 -330.809194)
			(xy 58.676565 -330.860263) (xy 58.650446 -330.908101) (xy 58.617784 -330.951734) (xy 58.579245 -330.990275)
			(xy 58.535612 -331.022938) (xy 58.487775 -331.049059) (xy 58.436707 -331.068105) (xy 58.383449 -331.079689)
			(xy 58.329084 -331.083576) (xy 58.274719 -331.079685) (xy 58.221461 -331.068096) (xy 58.170395 -331.049045)
			(xy 58.122561 -331.022921) (xy 58.100468 -331.006958) (xy 58.081456 -330.993362) (xy 58.039573 -330.97263)
			(xy 57.994605 -330.959904) (xy 57.948068 -330.955614) (xy 57.901531 -330.959904) (xy 57.856563 -330.97263)
			(xy 57.81468 -330.993362) (xy 57.795668 -331.006958) (xy 57.773534 -331.022848) (xy 57.725713 -331.048957)
			(xy 57.674664 -331.067995) (xy 57.621425 -331.079573) (xy 57.56708 -331.083457) (xy 57.512735 -331.079568)
			(xy 57.459497 -331.067983) (xy 57.40845 -331.04894) (xy 57.360632 -331.022826) (xy 57.317018 -330.990172)
			(xy 57.278495 -330.951644) (xy 57.245847 -330.908025) (xy 57.219739 -330.860204) (xy 57.200703 -330.809155)
			(xy 57.189125 -330.755915) (xy 57.185243 -330.70157) (xy 56.824383 -330.70157) (xy 56.820498 -330.755937)
			(xy 56.808916 -330.809197) (xy 56.78987 -330.860267) (xy 56.76375 -330.908107) (xy 56.731087 -330.951741)
			(xy 56.692546 -330.990283) (xy 56.648912 -331.022947) (xy 56.601074 -331.049067) (xy 56.550004 -331.068114)
			(xy 56.496744 -331.079697) (xy 56.442377 -331.083583) (xy 56.388011 -331.079691) (xy 56.334752 -331.068101)
			(xy 56.283684 -331.049048) (xy 56.235849 -331.022922) (xy 56.213756 -331.006958) (xy 56.194744 -330.993362)
			(xy 56.152861 -330.97263) (xy 56.107893 -330.959904) (xy 56.061356 -330.955614) (xy 56.014819 -330.959904)
			(xy 55.969851 -330.97263) (xy 55.927968 -330.993362) (xy 55.908956 -331.006958) (xy 55.886822 -331.022847)
			(xy 55.839002 -331.048954) (xy 55.787954 -331.06799) (xy 55.734716 -331.079567) (xy 55.680373 -331.08345)
			(xy 55.62603 -331.07956) (xy 55.572794 -331.067975) (xy 55.521748 -331.048932) (xy 55.473933 -331.022818)
			(xy 55.43032 -330.990164) (xy 55.391798 -330.951637) (xy 55.359152 -330.908019) (xy 55.333045 -330.8602)
			(xy 55.314009 -330.809151) (xy 55.302432 -330.755914) (xy 55.29855 -330.70157) (xy 53.055012 -330.70157)
			(xy 53.055012 -330.798424) (xy 51.402996 -330.798424) (xy 51.402996 -329.146408) (xy 35.618829 -329.146408)
			(xy 35.58313 -329.149716) (xy 35.49623 -329.149716) (xy 35.409701 -329.141698) (xy 35.324281 -329.12573)
			(xy 35.240699 -329.101949) (xy 35.159667 -329.070557) (xy 35.081878 -329.031823) (xy 35.007994 -328.986076)
			(xy 34.938647 -328.933707) (xy 34.874427 -328.875163) (xy 34.815883 -328.810943) (xy 34.763514 -328.741596)
			(xy 34.717767 -328.667712) (xy 34.679033 -328.589923) (xy 34.647641 -328.508891) (xy 34.62386 -328.425309)
			(xy 34.607892 -328.339889) (xy 34.599874 -328.25336) (xy 31.39856 -328.25336) (xy 31.396498 -328.297532)
			(xy 31.384263 -328.384407) (xy 31.36399 -328.469764) (xy 31.335855 -328.552863) (xy 31.300101 -328.632979)
			(xy 31.257042 -328.709417) (xy 31.207049 -328.781511) (xy 31.150559 -328.848636) (xy 31.088062 -328.910208)
			(xy 31.020102 -328.965691) (xy 30.94727 -329.014602) (xy 30.870199 -329.056518) (xy 30.789558 -329.091072)
			(xy 30.70605 -329.117965) (xy 30.620399 -329.136963) (xy 30.533352 -329.147901) (xy 30.445664 -329.150683)
			(xy 30.358098 -329.145286) (xy 30.271416 -329.131756) (xy 30.18637 -329.110212) (xy 30.103701 -329.080839)
			(xy 30.063694 -329.062842) (xy 30.043103 -329.054515) (xy 29.999863 -329.044379) (xy 29.955519 -329.041912)
			(xy 29.911421 -329.047188) (xy 29.868911 -329.060046) (xy 29.829282 -329.080095) (xy 29.793739 -329.106725)
			(xy 29.763364 -329.139126) (xy 29.739082 -329.176313) (xy 29.72163 -329.217153) (xy 29.711541 -329.260404)
			(xy 29.709872 -329.282552) (xy 29.709872 -329.677268) (xy 29.711583 -329.699403) (xy 29.721698 -329.742627)
			(xy 29.739164 -329.783439) (xy 29.763451 -329.820598) (xy 29.793821 -329.852975) (xy 29.829351 -329.879588)
			(xy 29.868962 -329.899628) (xy 29.911451 -329.912486) (xy 29.955527 -329.917772) (xy 29.999851 -329.915324)
			(xy 30.043078 -329.905218) (xy 30.063694 -329.896978) (xy 30.103694 -329.878964) (xy 30.186362 -329.849591)
			(xy 30.271408 -329.828045) (xy 30.35809 -329.814515) (xy 30.445656 -329.809117) (xy 30.533343 -329.811898)
			(xy 30.620391 -329.822835) (xy 30.706041 -329.841833) (xy 30.78955 -329.868725) (xy 30.870191 -329.903279)
			(xy 30.947263 -329.945193) (xy 31.020096 -329.994104) (xy 31.088056 -330.049587) (xy 31.150553 -330.111158)
			(xy 31.207044 -330.178282) (xy 31.257037 -330.250376) (xy 31.300098 -330.326814) (xy 31.335852 -330.40693)
			(xy 31.363988 -330.490027) (xy 31.384262 -330.575385) (xy 31.396497 -330.662259) (xy 31.400588 -330.749896)
			(xy 31.39856 -330.79336) (xy 34.599874 -330.79336) (xy 34.599874 -330.70646) (xy 34.607892 -330.619931)
			(xy 34.62386 -330.534511) (xy 34.647641 -330.450929) (xy 34.679033 -330.369897) (xy 34.717767 -330.292108)
			(xy 34.763514 -330.218224) (xy 34.815883 -330.148877) (xy 34.874427 -330.084657) (xy 34.938647 -330.026113)
			(xy 35.007994 -329.973744) (xy 35.081878 -329.927997) (xy 35.159667 -329.889263) (xy 35.240699 -329.857871)
			(xy 35.324281 -329.83409) (xy 35.409701 -329.818122) (xy 35.49623 -329.810104) (xy 35.58313 -329.810104)
			(xy 35.669659 -329.818122) (xy 35.755079 -329.83409) (xy 35.838661 -329.857871) (xy 35.919693 -329.889263)
			(xy 35.997482 -329.927997) (xy 36.071366 -329.973744) (xy 36.12331 -330.012971) (xy 47.903374 -330.012971)
			(xy 47.903374 -329.931861) (xy 47.911324 -329.851142) (xy 47.927147 -329.771591) (xy 47.950692 -329.693975)
			(xy 47.981731 -329.619039) (xy 48.019966 -329.547507) (xy 48.065028 -329.480067) (xy 48.116483 -329.417368)
			(xy 48.173836 -329.360015) (xy 48.236535 -329.30856) (xy 48.303975 -329.263498) (xy 48.375507 -329.225263)
			(xy 48.450443 -329.194224) (xy 48.528059 -329.170679) (xy 48.60761 -329.154856) (xy 48.688329 -329.146906)
			(xy 48.769439 -329.146906) (xy 48.850158 -329.154856) (xy 48.929709 -329.170679) (xy 49.007325 -329.194224)
			(xy 49.082261 -329.225263) (xy 49.153793 -329.263498) (xy 49.221233 -329.30856) (xy 49.283932 -329.360015)
			(xy 49.341285 -329.417368) (xy 49.39274 -329.480067) (xy 49.437802 -329.547507) (xy 49.476037 -329.619039)
			(xy 49.507076 -329.693975) (xy 49.530621 -329.771591) (xy 49.546444 -329.851142) (xy 49.554394 -329.931861)
			(xy 49.554892 -329.972416) (xy 49.554394 -330.012971) (xy 49.546444 -330.09369) (xy 49.530621 -330.173241)
			(xy 49.507076 -330.250857) (xy 49.476037 -330.325793) (xy 49.437802 -330.397325) (xy 49.39274 -330.464765)
			(xy 49.341285 -330.527464) (xy 49.283932 -330.584817) (xy 49.221233 -330.636272) (xy 49.153793 -330.681334)
			(xy 49.082261 -330.719569) (xy 49.007325 -330.750608) (xy 48.929709 -330.774153) (xy 48.850158 -330.789976)
			(xy 48.769439 -330.797926) (xy 48.688329 -330.797926) (xy 48.60761 -330.789976) (xy 48.528059 -330.774153)
			(xy 48.450443 -330.750608) (xy 48.375507 -330.719569) (xy 48.303975 -330.681334) (xy 48.236535 -330.636272)
			(xy 48.173836 -330.584817) (xy 48.116483 -330.527464) (xy 48.065028 -330.464765) (xy 48.019966 -330.397325)
			(xy 47.981731 -330.325793) (xy 47.950692 -330.250857) (xy 47.927147 -330.173241) (xy 47.911324 -330.09369)
			(xy 47.903374 -330.012971) (xy 36.12331 -330.012971) (xy 36.140713 -330.026113) (xy 36.204933 -330.084657)
			(xy 36.263477 -330.148877) (xy 36.315846 -330.218224) (xy 36.361593 -330.292108) (xy 36.400327 -330.369897)
			(xy 36.431719 -330.450929) (xy 36.4555 -330.534511) (xy 36.471468 -330.619931) (xy 36.479486 -330.70646)
			(xy 36.479988 -330.74991) (xy 36.479486 -330.79336) (xy 36.471468 -330.879889) (xy 36.4555 -330.965309)
			(xy 36.431719 -331.048891) (xy 36.400327 -331.129923) (xy 36.361593 -331.207712) (xy 36.315846 -331.281596)
			(xy 36.263477 -331.350943) (xy 36.204933 -331.415163) (xy 36.140713 -331.473707) (xy 36.071366 -331.526076)
			(xy 35.997482 -331.571823) (xy 35.919693 -331.610557) (xy 35.838661 -331.641949) (xy 35.755079 -331.66573)
			(xy 35.669659 -331.681698) (xy 35.58313 -331.689716) (xy 35.49623 -331.689716) (xy 35.409701 -331.681698)
			(xy 35.324281 -331.66573) (xy 35.240699 -331.641949) (xy 35.159667 -331.610557) (xy 35.081878 -331.571823)
			(xy 35.007994 -331.526076) (xy 34.938647 -331.473707) (xy 34.874427 -331.415163) (xy 34.815883 -331.350943)
			(xy 34.763514 -331.281596) (xy 34.717767 -331.207712) (xy 34.679033 -331.129923) (xy 34.647641 -331.048891)
			(xy 34.62386 -330.965309) (xy 34.607892 -330.879889) (xy 34.599874 -330.79336) (xy 31.39856 -330.79336)
			(xy 31.396498 -330.837532) (xy 31.384263 -330.924407) (xy 31.36399 -331.009764) (xy 31.335855 -331.092863)
			(xy 31.300101 -331.172979) (xy 31.257042 -331.249417) (xy 31.207049 -331.321511) (xy 31.150559 -331.388636)
			(xy 31.088062 -331.450208) (xy 31.020102 -331.505691) (xy 30.94727 -331.554602) (xy 30.870199 -331.596518)
			(xy 30.789558 -331.631072) (xy 30.70605 -331.657965) (xy 30.620399 -331.676963) (xy 30.533352 -331.687901)
			(xy 30.445664 -331.690683) (xy 30.358098 -331.685286) (xy 30.271416 -331.671756) (xy 30.18637 -331.650212)
			(xy 30.103701 -331.620839) (xy 30.063694 -331.602842) (xy 30.043103 -331.594515) (xy 29.999863 -331.584379)
			(xy 29.955519 -331.581912) (xy 29.911421 -331.587188) (xy 29.868911 -331.600046) (xy 29.829282 -331.620095)
			(xy 29.793739 -331.646725) (xy 29.763364 -331.679126) (xy 29.739082 -331.716313) (xy 29.72163 -331.757153)
			(xy 29.711541 -331.800404) (xy 29.709872 -331.822552) (xy 29.709872 -332.164211) (xy 39.178241 -332.164211)
			(xy 39.182128 -332.109847) (xy 39.193713 -332.056591) (xy 39.21276 -332.005525) (xy 39.238881 -331.95769)
			(xy 39.271544 -331.91406) (xy 39.310085 -331.875523) (xy 39.353718 -331.842863) (xy 39.401555 -331.816746)
			(xy 39.452622 -331.797704) (xy 39.50588 -331.786124) (xy 39.560243 -331.782242) (xy 39.614606 -331.786136)
			(xy 39.667861 -331.797729) (xy 39.718924 -331.816783) (xy 39.766755 -331.84291) (xy 39.788846 -331.858874)
			(xy 39.807858 -331.87247) (xy 39.849741 -331.893202) (xy 39.894709 -331.905928) (xy 39.941246 -331.910218)
			(xy 39.987783 -331.905928) (xy 40.032751 -331.893202) (xy 40.074634 -331.87247) (xy 40.093646 -331.858874)
			(xy 40.11575 -331.842942) (xy 40.163571 -331.816831) (xy 40.214622 -331.797792) (xy 40.267862 -331.786211)
			(xy 40.322209 -331.782325) (xy 40.376555 -331.786214) (xy 40.429795 -331.797797) (xy 40.480845 -331.816839)
			(xy 40.528665 -331.842952) (xy 40.572282 -331.875605) (xy 40.610808 -331.914133) (xy 40.643459 -331.957752)
			(xy 40.66957 -332.005573) (xy 40.688609 -332.056624) (xy 40.700189 -332.109864) (xy 40.704075 -332.164211)
			(xy 40.700186 -332.218557) (xy 40.688603 -332.271797) (xy 40.669561 -332.322847) (xy 40.643447 -332.370667)
			(xy 40.610794 -332.414283) (xy 40.572266 -332.452809) (xy 40.553706 -332.466702) (xy 55.332653 -332.466702)
			(xy 55.336541 -332.412341) (xy 55.348126 -332.359086) (xy 55.367174 -332.308022) (xy 55.393295 -332.260189)
			(xy 55.425958 -332.216561) (xy 55.464498 -332.178026) (xy 55.508131 -332.145368) (xy 55.555967 -332.119253)
			(xy 55.607033 -332.100212) (xy 55.66029 -332.088634) (xy 55.714652 -332.084753) (xy 55.769013 -332.088648)
			(xy 55.822266 -332.100242) (xy 55.873327 -332.119296) (xy 55.921156 -332.145424) (xy 55.943246 -332.161388)
			(xy 55.962258 -332.174984) (xy 56.004141 -332.195716) (xy 56.049109 -332.208442) (xy 56.095646 -332.212732)
			(xy 56.142183 -332.208442) (xy 56.187151 -332.195716) (xy 56.229034 -332.174984) (xy 56.248046 -332.161388)
			(xy 56.270137 -332.145437) (xy 56.317959 -332.119324) (xy 56.369011 -332.100283) (xy 56.422252 -332.088701)
			(xy 56.476601 -332.084814) (xy 56.530949 -332.088701) (xy 56.58419 -332.100284) (xy 56.635242 -332.119325)
			(xy 56.683064 -332.145438) (xy 56.726683 -332.178091) (xy 56.765211 -332.216619) (xy 56.797864 -332.260238)
			(xy 56.823976 -332.308061) (xy 56.843017 -332.359112) (xy 56.854599 -332.412354) (xy 56.858486 -332.466702)
			(xy 57.219505 -332.466702) (xy 57.223392 -332.412353) (xy 57.234974 -332.359109) (xy 57.254016 -332.308056)
			(xy 57.280129 -332.260233) (xy 57.312783 -332.216613) (xy 57.351312 -332.178083) (xy 57.394932 -332.14543)
			(xy 57.442756 -332.119316) (xy 57.493809 -332.100275) (xy 57.547052 -332.088692) (xy 57.601402 -332.084805)
			(xy 57.655751 -332.088693) (xy 57.708995 -332.100276) (xy 57.760047 -332.119318) (xy 57.807871 -332.145432)
			(xy 57.829958 -332.161388) (xy 57.84897 -332.174984) (xy 57.890853 -332.195716) (xy 57.935821 -332.208442)
			(xy 57.982358 -332.212732) (xy 58.028895 -332.208442) (xy 58.073863 -332.195716) (xy 58.115746 -332.174984)
			(xy 58.134758 -332.161388) (xy 58.156851 -332.14543) (xy 58.204679 -332.119303) (xy 58.255739 -332.100249)
			(xy 58.308991 -332.088657) (xy 58.36335 -332.084762) (xy 58.417711 -332.088643) (xy 58.470966 -332.100221)
			(xy 58.522031 -332.119262) (xy 58.569866 -332.145376) (xy 58.613497 -332.178033) (xy 58.652036 -332.216567)
			(xy 58.684698 -332.260195) (xy 58.710819 -332.308026) (xy 58.729865 -332.359089) (xy 58.741451 -332.412342)
			(xy 58.745338 -332.466702) (xy 59.46048 -332.466702) (xy 59.464368 -332.412347) (xy 59.475951 -332.359098)
			(xy 59.494996 -332.30804) (xy 59.521113 -332.260212) (xy 59.553771 -332.216588) (xy 59.592306 -332.178056)
			(xy 59.635932 -332.1454) (xy 59.683761 -332.119286) (xy 59.73482 -332.100245) (xy 59.78807 -332.088664)
			(xy 59.842426 -332.08478) (xy 59.896781 -332.088672) (xy 59.950029 -332.100259) (xy 60.001085 -332.119307)
			(xy 60.048912 -332.145428) (xy 60.071 -332.161388) (xy 60.090012 -332.174984) (xy 60.131895 -332.195716)
			(xy 60.176863 -332.208442) (xy 60.2234 -332.212732) (xy 60.269937 -332.208442) (xy 60.314905 -332.195716)
			(xy 60.356788 -332.174984) (xy 60.3758 -332.161388) (xy 60.397892 -332.145433) (xy 60.445717 -332.119313)
			(xy 60.496773 -332.100266) (xy 60.55002 -332.088678) (xy 60.604374 -332.084787) (xy 60.658729 -332.088671)
			(xy 60.711978 -332.100251) (xy 60.763036 -332.119292) (xy 60.810865 -332.145406) (xy 60.85449 -332.178061)
			(xy 60.893024 -332.216592) (xy 60.925682 -332.260216) (xy 60.951798 -332.308043) (xy 60.970842 -332.3591)
			(xy 60.982426 -332.412348) (xy 60.986313 -332.466702) (xy 61.36449 -332.466702) (xy 61.368377 -332.412349)
			(xy 61.37996 -332.359102) (xy 61.399003 -332.308046) (xy 61.425119 -332.26022) (xy 61.457776 -332.216597)
			(xy 61.496308 -332.178066) (xy 61.539932 -332.145412) (xy 61.587759 -332.119298) (xy 61.638816 -332.100256)
			(xy 61.692063 -332.088675) (xy 61.746417 -332.08479) (xy 61.80077 -332.08868) (xy 61.854016 -332.100266)
			(xy 61.905071 -332.119311) (xy 61.952896 -332.145429) (xy 61.974984 -332.161388) (xy 61.993996 -332.174984)
			(xy 62.035879 -332.195716) (xy 62.080847 -332.208442) (xy 62.127384 -332.212732) (xy 62.173921 -332.208442)
			(xy 62.218889 -332.195716) (xy 62.260772 -332.174984) (xy 62.279784 -332.161388) (xy 62.301876 -332.145432)
			(xy 62.349703 -332.119309) (xy 62.40076 -332.100259) (xy 62.454009 -332.08867) (xy 62.508365 -332.084777)
			(xy 62.562722 -332.08866) (xy 62.615973 -332.10024) (xy 62.667034 -332.11928) (xy 62.714865 -332.145395)
			(xy 62.758493 -332.17805) (xy 62.797029 -332.216583) (xy 62.829688 -332.260208) (xy 62.855806 -332.308036)
			(xy 62.874851 -332.359096) (xy 62.886435 -332.412346) (xy 62.890323 -332.466702) (xy 62.886435 -332.521059)
			(xy 62.87485 -332.574309) (xy 62.855804 -332.625368) (xy 62.829685 -332.673196) (xy 62.797025 -332.716821)
			(xy 62.758489 -332.755353) (xy 62.714861 -332.788008) (xy 62.66703 -332.814122) (xy 62.615969 -332.833162)
			(xy 62.562717 -332.844741) (xy 62.50836 -332.848623) (xy 62.454004 -332.844729) (xy 62.400755 -332.833139)
			(xy 62.349698 -332.814089) (xy 62.301872 -332.787965) (xy 62.279784 -332.772004) (xy 62.260772 -332.758408)
			(xy 62.218889 -332.737676) (xy 62.173921 -332.72495) (xy 62.127384 -332.72066) (xy 62.080847 -332.72495)
			(xy 62.035879 -332.737676) (xy 61.993996 -332.758408) (xy 61.974984 -332.772004) (xy 61.9529 -332.787968)
			(xy 61.905075 -332.814087) (xy 61.85402 -332.833133) (xy 61.800774 -332.84472) (xy 61.746421 -332.84861)
			(xy 61.692068 -332.844726) (xy 61.638821 -332.833145) (xy 61.587764 -332.814104) (xy 61.539936 -332.787991)
			(xy 61.496312 -332.755337) (xy 61.457779 -332.716806) (xy 61.425122 -332.673184) (xy 61.399005 -332.625358)
			(xy 61.379962 -332.574302) (xy 61.368378 -332.521056) (xy 61.36449 -332.466702) (xy 60.986313 -332.466702)
			(xy 60.982425 -332.521057) (xy 60.970841 -332.574305) (xy 60.951796 -332.625362) (xy 60.925679 -332.673189)
			(xy 60.893021 -332.716811) (xy 60.854487 -332.755342) (xy 60.810861 -332.787997) (xy 60.763032 -332.81411)
			(xy 60.711973 -332.83315) (xy 60.658724 -332.84473) (xy 60.60437 -332.848613) (xy 60.550015 -332.844721)
			(xy 60.496768 -332.833133) (xy 60.445713 -332.814085) (xy 60.397888 -332.787964) (xy 60.3758 -332.772004)
			(xy 60.356788 -332.758408) (xy 60.314905 -332.737676) (xy 60.269937 -332.72495) (xy 60.2234 -332.72066)
			(xy 60.176863 -332.72495) (xy 60.131895 -332.737676) (xy 60.090012 -332.758408) (xy 60.071 -332.772004)
			(xy 60.048916 -332.787969) (xy 60.00109 -332.814091) (xy 59.950033 -332.833139) (xy 59.896786 -332.844728)
			(xy 59.84243 -332.84862) (xy 59.788075 -332.844736) (xy 59.734825 -332.833156) (xy 59.683766 -332.814116)
			(xy 59.635936 -332.788002) (xy 59.592309 -332.755347) (xy 59.553774 -332.716816) (xy 59.521115 -332.673192)
			(xy 59.494998 -332.625364) (xy 59.475953 -332.574306) (xy 59.464368 -332.521058) (xy 59.46048 -332.466702)
			(xy 58.745338 -332.466702) (xy 58.74145 -332.521063) (xy 58.729864 -332.574316) (xy 58.710817 -332.625378)
			(xy 58.684696 -332.673209) (xy 58.652033 -332.716836) (xy 58.613493 -332.75537) (xy 58.569862 -332.788026)
			(xy 58.522026 -332.81414) (xy 58.470961 -332.83318) (xy 58.417706 -332.844758) (xy 58.363346 -332.848638)
			(xy 58.308986 -332.844743) (xy 58.255734 -332.833149) (xy 58.204675 -332.814095) (xy 58.156847 -332.787968)
			(xy 58.134758 -332.772004) (xy 58.115746 -332.758408) (xy 58.073863 -332.737676) (xy 58.028895 -332.72495)
			(xy 57.982358 -332.72066) (xy 57.935821 -332.72495) (xy 57.890853 -332.737676) (xy 57.84897 -332.758408)
			(xy 57.829958 -332.772004) (xy 57.807875 -332.787966) (xy 57.760052 -332.81408) (xy 57.708999 -332.833123)
			(xy 57.655756 -332.844706) (xy 57.601407 -332.848595) (xy 57.547057 -332.844708) (xy 57.493813 -332.833127)
			(xy 57.44276 -332.814086) (xy 57.394936 -332.787973) (xy 57.351316 -332.75532) (xy 57.312786 -332.716791)
			(xy 57.280132 -332.673171) (xy 57.254018 -332.625348) (xy 57.234976 -332.574295) (xy 57.223393 -332.521052)
			(xy 57.219505 -332.466702) (xy 56.858486 -332.466702) (xy 56.854598 -332.521051) (xy 56.843016 -332.574292)
			(xy 56.823974 -332.625344) (xy 56.797861 -332.673166) (xy 56.765208 -332.716784) (xy 56.726679 -332.755312)
			(xy 56.68306 -332.787965) (xy 56.635238 -332.814077) (xy 56.584186 -332.833118) (xy 56.530944 -332.844699)
			(xy 56.476596 -332.848586) (xy 56.422248 -332.844698) (xy 56.369006 -332.833115) (xy 56.317955 -332.814074)
			(xy 56.270133 -332.78796) (xy 56.248046 -332.772004) (xy 56.229034 -332.758408) (xy 56.187151 -332.737676)
			(xy 56.142183 -332.72495) (xy 56.095646 -332.72066) (xy 56.049109 -332.72495) (xy 56.004141 -332.737676)
			(xy 55.962258 -332.758408) (xy 55.943246 -332.772004) (xy 55.921161 -332.787973) (xy 55.873332 -332.814102)
			(xy 55.822271 -332.833157) (xy 55.769018 -332.844751) (xy 55.714657 -332.848647) (xy 55.660294 -332.844767)
			(xy 55.607038 -332.833189) (xy 55.555971 -332.814149) (xy 55.508135 -332.788034) (xy 55.464502 -332.755377)
			(xy 55.425961 -332.716843) (xy 55.393297 -332.673215) (xy 55.367176 -332.625382) (xy 55.348128 -332.574319)
			(xy 55.336541 -332.521064) (xy 55.332653 -332.466702) (xy 40.553706 -332.466702) (xy 40.528647 -332.48546)
			(xy 40.480825 -332.51157) (xy 40.429775 -332.530609) (xy 40.376534 -332.542189) (xy 40.322187 -332.546075)
			(xy 40.267841 -332.542186) (xy 40.214601 -332.530602) (xy 40.163552 -332.51156) (xy 40.115732 -332.485446)
			(xy 40.093646 -332.46949) (xy 40.074634 -332.455894) (xy 40.032751 -332.435162) (xy 39.987783 -332.422436)
			(xy 39.941246 -332.418146) (xy 39.894709 -332.422436) (xy 39.849741 -332.435162) (xy 39.807858 -332.455894)
			(xy 39.788846 -332.46949) (xy 39.766774 -332.485478) (xy 39.718944 -332.511609) (xy 39.667882 -332.530665)
			(xy 39.614628 -332.542261) (xy 39.560265 -332.546158) (xy 39.505901 -332.542279) (xy 39.452643 -332.530702)
			(xy 39.401574 -332.511663) (xy 39.353736 -332.485548) (xy 39.310101 -332.452891) (xy 39.271558 -332.414356)
			(xy 39.238893 -332.370728) (xy 39.212769 -332.322895) (xy 39.193719 -332.27183) (xy 39.182132 -332.218574)
			(xy 39.178241 -332.164211) (xy 29.709872 -332.164211) (xy 29.709872 -332.217268) (xy 29.711583 -332.239403)
			(xy 29.721698 -332.282627) (xy 29.739164 -332.323439) (xy 29.763451 -332.360598) (xy 29.793821 -332.392975)
			(xy 29.829351 -332.419588) (xy 29.868962 -332.439628) (xy 29.911451 -332.452486) (xy 29.955527 -332.457772)
			(xy 29.999851 -332.455324) (xy 30.043078 -332.445218) (xy 30.063694 -332.436978) (xy 30.103694 -332.418964)
			(xy 30.186362 -332.389591) (xy 30.271408 -332.368045) (xy 30.35809 -332.354515) (xy 30.445656 -332.349117)
			(xy 30.533343 -332.351898) (xy 30.620391 -332.362835) (xy 30.706041 -332.381833) (xy 30.78955 -332.408725)
			(xy 30.870191 -332.443279) (xy 30.947263 -332.485193) (xy 31.020096 -332.534104) (xy 31.088056 -332.589587)
			(xy 31.150553 -332.651158) (xy 31.207044 -332.718282) (xy 31.257037 -332.790376) (xy 31.300098 -332.866814)
			(xy 31.335852 -332.94693) (xy 31.363988 -333.030027) (xy 31.384262 -333.115385) (xy 31.396497 -333.202259)
			(xy 31.400588 -333.289896) (xy 31.39856 -333.33336) (xy 34.599874 -333.33336) (xy 34.599874 -333.24646)
			(xy 34.607892 -333.159931) (xy 34.62386 -333.074511) (xy 34.647641 -332.990929) (xy 34.679033 -332.909897)
			(xy 34.717767 -332.832108) (xy 34.763514 -332.758224) (xy 34.815883 -332.688877) (xy 34.874427 -332.624657)
			(xy 34.938647 -332.566113) (xy 35.007994 -332.513744) (xy 35.081878 -332.467997) (xy 35.159667 -332.429263)
			(xy 35.240699 -332.397871) (xy 35.324281 -332.37409) (xy 35.409701 -332.358122) (xy 35.49623 -332.350104)
			(xy 35.58313 -332.350104) (xy 35.669659 -332.358122) (xy 35.755079 -332.37409) (xy 35.838661 -332.397871)
			(xy 35.919693 -332.429263) (xy 35.997482 -332.467997) (xy 36.071366 -332.513744) (xy 36.140713 -332.566113)
			(xy 36.204933 -332.624657) (xy 36.263477 -332.688877) (xy 36.315846 -332.758224) (xy 36.361593 -332.832108)
			(xy 36.380856 -332.870794) (xy 64.789707 -332.870794) (xy 64.793595 -332.816444) (xy 64.805179 -332.7632)
			(xy 64.824222 -332.712147) (xy 64.850337 -332.664324) (xy 64.882992 -332.620704) (xy 64.921523 -332.582176)
			(xy 64.965145 -332.549523) (xy 65.01297 -332.523411) (xy 65.064024 -332.504372) (xy 65.117269 -332.492792)
			(xy 65.171619 -332.488907) (xy 65.225969 -332.492797) (xy 65.279212 -332.504383) (xy 65.330265 -332.523427)
			(xy 65.378087 -332.549544) (xy 65.400174 -332.565502) (xy 65.419186 -332.579098) (xy 65.461069 -332.59983)
			(xy 65.506037 -332.612556) (xy 65.552574 -332.616846) (xy 65.599111 -332.612556) (xy 65.644079 -332.59983)
			(xy 65.685962 -332.579098) (xy 65.704974 -332.565502) (xy 65.727053 -332.549526) (xy 65.774881 -332.5234)
			(xy 65.825941 -332.504347) (xy 65.879192 -332.492755) (xy 65.933551 -332.48886) (xy 65.987911 -332.492741)
			(xy 66.041166 -332.50432) (xy 66.09223 -332.52336) (xy 66.140064 -332.549474) (xy 66.183695 -332.58213)
			(xy 66.222234 -332.620663) (xy 66.254897 -332.664289) (xy 66.281018 -332.71212) (xy 66.300065 -332.763182)
			(xy 66.311651 -332.816434) (xy 66.31554 -332.870794) (xy 67.594099 -332.870794) (xy 67.597987 -332.816442)
			(xy 67.609571 -332.763197) (xy 67.628615 -332.712142) (xy 67.654732 -332.664317) (xy 67.687388 -332.620696)
			(xy 67.725921 -332.582167) (xy 67.769545 -332.549514) (xy 67.817372 -332.523401) (xy 67.868428 -332.504362)
			(xy 67.921675 -332.492782) (xy 67.976027 -332.488899) (xy 68.030379 -332.49279) (xy 68.083624 -332.504377)
			(xy 68.134678 -332.523424) (xy 68.182501 -332.549543) (xy 68.204588 -332.565502) (xy 68.2236 -332.579098)
			(xy 68.265483 -332.59983) (xy 68.310451 -332.612556) (xy 68.356988 -332.616846) (xy 68.403525 -332.612556)
			(xy 68.448493 -332.59983) (xy 68.490376 -332.579098) (xy 68.509388 -332.565502) (xy 68.531467 -332.549528)
			(xy 68.579294 -332.523404) (xy 68.630352 -332.504353) (xy 68.683602 -332.492762) (xy 68.737959 -332.488868)
			(xy 68.792317 -332.49275) (xy 68.845569 -332.504329) (xy 68.896632 -332.52337) (xy 68.944464 -332.549483)
			(xy 68.988093 -332.582139) (xy 69.02663 -332.620671) (xy 69.059291 -332.664296) (xy 69.085411 -332.712126)
			(xy 69.104457 -332.763186) (xy 69.116043 -332.816436) (xy 69.119932 -332.870794) (xy 69.116045 -332.925152)
			(xy 69.104461 -332.978403) (xy 69.085416 -333.029463) (xy 69.059298 -333.077293) (xy 69.026638 -333.12092)
			(xy 68.988102 -333.159453) (xy 68.944474 -333.19211) (xy 68.896643 -333.218225) (xy 68.845581 -333.237267)
			(xy 68.792329 -333.248848) (xy 68.737971 -333.252732) (xy 68.683614 -333.24884) (xy 68.630364 -333.237251)
			(xy 68.579305 -333.218201) (xy 68.531477 -333.192079) (xy 68.509388 -333.176118) (xy 68.490376 -333.162522)
			(xy 68.448493 -333.14179) (xy 68.403525 -333.129064) (xy 68.356988 -333.124774) (xy 68.310451 -333.129064)
			(xy 68.265483 -333.14179) (xy 68.2236 -333.162522) (xy 68.204588 -333.176118) (xy 68.182491 -333.192063)
			(xy 68.134667 -333.218181) (xy 68.083612 -333.237226) (xy 68.030367 -333.248812) (xy 67.976015 -333.252701)
			(xy 67.921663 -333.248816) (xy 67.868417 -333.237235) (xy 67.817361 -333.218194) (xy 67.769535 -333.19208)
			(xy 67.725912 -333.159425) (xy 67.687381 -333.120895) (xy 67.654725 -333.077273) (xy 67.62861 -333.029447)
			(xy 67.609568 -332.978392) (xy 67.597985 -332.925146) (xy 67.594099 -332.870794) (xy 66.31554 -332.870794)
			(xy 66.311653 -332.925154) (xy 66.300068 -332.978407) (xy 66.281023 -333.029469) (xy 66.254903 -333.0773)
			(xy 66.222242 -333.120928) (xy 66.183704 -333.159462) (xy 66.140075 -333.19212) (xy 66.092241 -333.218235)
			(xy 66.041177 -333.237277) (xy 65.987923 -333.248857) (xy 65.933563 -333.25274) (xy 65.879204 -333.248847)
			(xy 65.825952 -333.237256) (xy 65.774892 -333.218205) (xy 65.727063 -333.19208) (xy 65.704974 -333.176118)
			(xy 65.685962 -333.162522) (xy 65.644079 -333.14179) (xy 65.599111 -333.129064) (xy 65.552574 -333.124774)
			(xy 65.506037 -333.129064) (xy 65.461069 -333.14179) (xy 65.419186 -333.162522) (xy 65.400174 -333.176118)
			(xy 65.378077 -333.192062) (xy 65.330254 -333.218178) (xy 65.279201 -333.237221) (xy 65.225957 -333.248805)
			(xy 65.171607 -333.252693) (xy 65.117257 -333.248807) (xy 65.064013 -333.237225) (xy 65.012959 -333.218184)
			(xy 64.965135 -333.19207) (xy 64.921514 -333.159416) (xy 64.882985 -333.120887) (xy 64.850331 -333.077266)
			(xy 64.824217 -333.029442) (xy 64.805175 -332.978388) (xy 64.793594 -332.925144) (xy 64.789707 -332.870794)
			(xy 36.380856 -332.870794) (xy 36.400327 -332.909897) (xy 36.431719 -332.990929) (xy 36.4555 -333.074511)
			(xy 36.471468 -333.159931) (xy 36.479486 -333.24646) (xy 36.479988 -333.28991) (xy 36.479486 -333.33336)
			(xy 36.471468 -333.419889) (xy 36.4555 -333.505309) (xy 36.431719 -333.588891) (xy 36.400327 -333.669923)
			(xy 36.361593 -333.747712) (xy 36.315846 -333.821596) (xy 36.263477 -333.890943) (xy 36.204933 -333.955163)
			(xy 36.140713 -334.013707) (xy 36.071366 -334.066076) (xy 35.997482 -334.111823) (xy 35.919693 -334.150557)
			(xy 35.838661 -334.181949) (xy 35.755079 -334.20573) (xy 35.669659 -334.221698) (xy 35.58313 -334.229716)
			(xy 35.49623 -334.229716) (xy 35.409701 -334.221698) (xy 35.324281 -334.20573) (xy 35.240699 -334.181949)
			(xy 35.159667 -334.150557) (xy 35.081878 -334.111823) (xy 35.007994 -334.066076) (xy 34.938647 -334.013707)
			(xy 34.874427 -333.955163) (xy 34.815883 -333.890943) (xy 34.763514 -333.821596) (xy 34.717767 -333.747712)
			(xy 34.679033 -333.669923) (xy 34.647641 -333.588891) (xy 34.62386 -333.505309) (xy 34.607892 -333.419889)
			(xy 34.599874 -333.33336) (xy 31.39856 -333.33336) (xy 31.396498 -333.377532) (xy 31.384263 -333.464407)
			(xy 31.36399 -333.549764) (xy 31.335855 -333.632863) (xy 31.300101 -333.712979) (xy 31.257042 -333.789417)
			(xy 31.207049 -333.861511) (xy 31.150559 -333.928636) (xy 31.088062 -333.990208) (xy 31.020102 -334.045691)
			(xy 30.94727 -334.094602) (xy 30.870199 -334.136518) (xy 30.789558 -334.171072) (xy 30.70605 -334.197965)
			(xy 30.620399 -334.216963) (xy 30.533352 -334.227901) (xy 30.445664 -334.230683) (xy 30.358098 -334.225286)
			(xy 30.271416 -334.211756) (xy 30.18637 -334.190212) (xy 30.103701 -334.160839) (xy 30.063694 -334.142842)
			(xy 30.043103 -334.134515) (xy 29.999863 -334.124379) (xy 29.955519 -334.121912) (xy 29.911421 -334.127188)
			(xy 29.868911 -334.140046) (xy 29.829282 -334.160095) (xy 29.793739 -334.186725) (xy 29.763364 -334.219126)
			(xy 29.739082 -334.256313) (xy 29.72163 -334.297153) (xy 29.711541 -334.340404) (xy 29.709872 -334.362552)
			(xy 29.709872 -334.757268) (xy 29.711583 -334.779403) (xy 29.721698 -334.822627) (xy 29.726995 -334.835005)
			(xy 39.17825 -334.835005) (xy 39.182137 -334.780643) (xy 39.193723 -334.727387) (xy 39.21277 -334.676323)
			(xy 39.238891 -334.628489) (xy 39.271554 -334.584861) (xy 39.310094 -334.546325) (xy 39.353727 -334.513667)
			(xy 39.401564 -334.487551) (xy 39.45263 -334.46851) (xy 39.505887 -334.456931) (xy 39.560249 -334.45305)
			(xy 39.614611 -334.456945) (xy 39.667865 -334.468538) (xy 39.718926 -334.487592) (xy 39.766756 -334.51372)
			(xy 39.788846 -334.529684) (xy 39.807858 -334.54328) (xy 39.849741 -334.564012) (xy 39.894709 -334.576738)
			(xy 39.941246 -334.581028) (xy 39.987783 -334.576738) (xy 40.032751 -334.564012) (xy 40.074634 -334.54328)
			(xy 40.093646 -334.529684) (xy 40.115741 -334.513739) (xy 40.163562 -334.487626) (xy 40.214614 -334.468586)
			(xy 40.267855 -334.457004) (xy 40.322203 -334.453117) (xy 40.376551 -334.457005) (xy 40.429792 -334.468587)
			(xy 40.454811 -334.477919) (xy 55.289251 -334.477919) (xy 55.293136 -334.423559) (xy 55.304719 -334.370305)
			(xy 55.323763 -334.319241) (xy 55.34988 -334.271408) (xy 55.38254 -334.227779) (xy 55.421076 -334.189242)
			(xy 55.464705 -334.156582) (xy 55.512538 -334.130464) (xy 55.563601 -334.11142) (xy 55.616855 -334.099837)
			(xy 55.671216 -334.095951) (xy 55.725576 -334.099841) (xy 55.778829 -334.111429) (xy 55.82989 -334.130477)
			(xy 55.877721 -334.156599) (xy 55.899812 -334.17256) (xy 55.918824 -334.186156) (xy 55.960707 -334.206888)
			(xy 56.005675 -334.219614) (xy 56.052212 -334.223904) (xy 56.098749 -334.219614) (xy 56.143717 -334.206888)
			(xy 56.1856 -334.186156) (xy 56.204612 -334.17256) (xy 56.22673 -334.156644) (xy 56.274553 -334.13053)
			(xy 56.325605 -334.111487) (xy 56.378848 -334.099904) (xy 56.433198 -334.096016) (xy 56.487548 -334.099903)
			(xy 56.540791 -334.111486) (xy 56.591844 -334.130528) (xy 56.639667 -334.156642) (xy 56.683286 -334.189297)
			(xy 56.721815 -334.227827) (xy 56.754467 -334.271448) (xy 56.780579 -334.319272) (xy 56.799619 -334.370326)
			(xy 56.811199 -334.423569) (xy 56.815084 -334.477919) (xy 57.175943 -334.477919) (xy 57.179829 -334.423557)
			(xy 57.191412 -334.370302) (xy 57.210457 -334.319237) (xy 57.236576 -334.271402) (xy 57.269236 -334.227772)
			(xy 57.307774 -334.189234) (xy 57.351405 -334.156574) (xy 57.39924 -334.130456) (xy 57.450305 -334.111411)
			(xy 57.50356 -334.099829) (xy 57.557922 -334.095943) (xy 57.612284 -334.099835) (xy 57.665538 -334.111424)
			(xy 57.716601 -334.130474) (xy 57.764433 -334.156598) (xy 57.786524 -334.17256) (xy 57.805536 -334.186156)
			(xy 57.847419 -334.206888) (xy 57.892387 -334.219614) (xy 57.938924 -334.223904) (xy 57.985461 -334.219614)
			(xy 58.030429 -334.206888) (xy 58.072312 -334.186156) (xy 58.091324 -334.17256) (xy 58.113442 -334.156645)
			(xy 58.161264 -334.130533) (xy 58.212315 -334.111492) (xy 58.265557 -334.09991) (xy 58.319905 -334.096023)
			(xy 58.374253 -334.099911) (xy 58.427494 -334.111494) (xy 58.478545 -334.130537) (xy 58.526366 -334.15665)
			(xy 58.569985 -334.189304) (xy 58.608511 -334.227834) (xy 58.641163 -334.271454) (xy 58.667273 -334.319277)
			(xy 58.686313 -334.370329) (xy 58.697892 -334.423571) (xy 58.701777 -334.477919) (xy 59.417078 -334.477919)
			(xy 59.420963 -334.423565) (xy 59.432544 -334.370317) (xy 59.451585 -334.319259) (xy 59.477698 -334.271431)
			(xy 59.510353 -334.227806) (xy 59.548884 -334.189272) (xy 59.592506 -334.156614) (xy 59.640332 -334.130497)
			(xy 59.691389 -334.111452) (xy 59.744636 -334.099867) (xy 59.798989 -334.095978) (xy 59.853344 -334.099864)
			(xy 59.906591 -334.111446) (xy 59.957649 -334.130488) (xy 60.005476 -334.156603) (xy 60.027566 -334.17256)
			(xy 60.046578 -334.186156) (xy 60.088461 -334.206888) (xy 60.133429 -334.219614) (xy 60.179966 -334.223904)
			(xy 60.226503 -334.219614) (xy 60.271471 -334.206888) (xy 60.313354 -334.186156) (xy 60.332366 -334.17256)
			(xy 60.354485 -334.15664) (xy 60.402311 -334.130518) (xy 60.453368 -334.111469) (xy 60.506616 -334.099881)
			(xy 60.560972 -334.095989) (xy 60.615328 -334.099873) (xy 60.668578 -334.111453) (xy 60.719638 -334.130495)
			(xy 60.767468 -334.15661) (xy 60.811094 -334.189266) (xy 60.849628 -334.2278) (xy 60.882285 -334.271425)
			(xy 60.908401 -334.319254) (xy 60.927444 -334.370313) (xy 60.939026 -334.423563) (xy 60.942911 -334.477919)
			(xy 61.320928 -334.477919) (xy 61.324814 -334.423554) (xy 61.336398 -334.370295) (xy 61.355444 -334.319227)
			(xy 61.381565 -334.271389) (xy 61.414229 -334.227757) (xy 61.45277 -334.189217) (xy 61.496404 -334.156556)
			(xy 61.544243 -334.130437) (xy 61.595312 -334.111393) (xy 61.648572 -334.099811) (xy 61.702937 -334.095928)
			(xy 61.757302 -334.099822) (xy 61.81056 -334.111414) (xy 61.861625 -334.130468) (xy 61.909458 -334.156596)
			(xy 61.93155 -334.17256) (xy 61.950562 -334.186156) (xy 61.992445 -334.206888) (xy 62.037413 -334.219614)
			(xy 62.08395 -334.223904) (xy 62.130487 -334.219614) (xy 62.175455 -334.206888) (xy 62.217338 -334.186156)
			(xy 62.23635 -334.17256) (xy 62.258469 -334.156639) (xy 62.306296 -334.130514) (xy 62.357355 -334.111463)
			(xy 62.410605 -334.099873) (xy 62.464963 -334.095979) (xy 62.519321 -334.099862) (xy 62.572574 -334.111442)
			(xy 62.623636 -334.130483) (xy 62.671468 -334.156599) (xy 62.715096 -334.189256) (xy 62.753632 -334.22779)
			(xy 62.786292 -334.271417) (xy 62.812409 -334.319248) (xy 62.831453 -334.370309) (xy 62.843035 -334.423561)
			(xy 62.846921 -334.477919) (xy 62.84303 -334.532277) (xy 62.831442 -334.585528) (xy 62.812393 -334.636587)
			(xy 62.786271 -334.684415) (xy 62.753607 -334.728039) (xy 62.715067 -334.766569) (xy 62.671436 -334.799222)
			(xy 62.623601 -334.825332) (xy 62.572537 -334.844369) (xy 62.519283 -334.855944) (xy 62.464924 -334.859821)
			(xy 62.410567 -334.855922) (xy 62.357318 -334.844326) (xy 62.306261 -334.82527) (xy 62.258437 -334.79914)
			(xy 62.23635 -334.783176) (xy 62.217338 -334.76958) (xy 62.175455 -334.748848) (xy 62.130487 -334.736122)
			(xy 62.08395 -334.731832) (xy 62.037413 -334.736122) (xy 61.992445 -334.748848) (xy 61.950562 -334.76958)
			(xy 61.93155 -334.783176) (xy 61.909491 -334.799183) (xy 61.86166 -334.825316) (xy 61.810596 -334.844375)
			(xy 61.75734 -334.855973) (xy 61.702976 -334.859872) (xy 61.64861 -334.855994) (xy 61.595349 -334.844418)
			(xy 61.544278 -334.825379) (xy 61.496437 -334.799265) (xy 61.452799 -334.766608) (xy 61.414254 -334.728072)
			(xy 61.381586 -334.684443) (xy 61.35546 -334.636608) (xy 61.336409 -334.585542) (xy 61.324819 -334.532284)
			(xy 61.320928 -334.477919) (xy 60.942911 -334.477919) (xy 60.939021 -334.532275) (xy 60.927433 -334.585524)
			(xy 60.908385 -334.636581) (xy 60.882265 -334.684407) (xy 60.849603 -334.728029) (xy 60.811065 -334.766559)
			(xy 60.767435 -334.799211) (xy 60.719603 -334.825321) (xy 60.668541 -334.844358) (xy 60.61529 -334.855933)
			(xy 60.560933 -334.859811) (xy 60.506578 -334.855914) (xy 60.453331 -334.84432) (xy 60.402276 -334.825266)
			(xy 60.354453 -334.799139) (xy 60.332366 -334.783176) (xy 60.313354 -334.76958) (xy 60.271471 -334.748848)
			(xy 60.226503 -334.736122) (xy 60.179966 -334.731832) (xy 60.133429 -334.736122) (xy 60.088461 -334.748848)
			(xy 60.046578 -334.76958) (xy 60.027566 -334.783176) (xy 60.005509 -334.799176) (xy 59.957684 -334.825296)
			(xy 59.906628 -334.844343) (xy 59.853382 -334.85593) (xy 59.799028 -334.859822) (xy 59.744674 -334.855938)
			(xy 59.691425 -334.844359) (xy 59.640367 -334.825319) (xy 59.592538 -334.799206) (xy 59.548913 -334.766553)
			(xy 59.510378 -334.728023) (xy 59.477719 -334.684401) (xy 59.451601 -334.636576) (xy 59.432555 -334.58552)
			(xy 59.420968 -334.532273) (xy 59.417078 -334.477919) (xy 58.701777 -334.477919) (xy 58.697887 -334.532267)
			(xy 58.686302 -334.585508) (xy 58.667257 -334.636558) (xy 58.641142 -334.684379) (xy 58.608486 -334.727995)
			(xy 58.569955 -334.766521) (xy 58.526334 -334.79917) (xy 58.47851 -334.825279) (xy 58.427457 -334.844317)
			(xy 58.374215 -334.855894) (xy 58.319866 -334.859777) (xy 58.265519 -334.855885) (xy 58.212278 -334.844298)
			(xy 58.161229 -334.825252) (xy 58.113409 -334.799134) (xy 58.091324 -334.783176) (xy 58.072312 -334.76958)
			(xy 58.030429 -334.748848) (xy 57.985461 -334.736122) (xy 57.938924 -334.731832) (xy 57.892387 -334.736122)
			(xy 57.847419 -334.748848) (xy 57.805536 -334.76958) (xy 57.786524 -334.783176) (xy 57.764465 -334.799181)
			(xy 57.716636 -334.82531) (xy 57.665575 -334.844365) (xy 57.612322 -334.85596) (xy 57.557961 -334.859857)
			(xy 57.503598 -334.855977) (xy 57.450342 -334.8444) (xy 57.399275 -334.82536) (xy 57.351437 -334.799247)
			(xy 57.307803 -334.766591) (xy 57.269262 -334.728057) (xy 57.236596 -334.68443) (xy 57.210473 -334.636598)
			(xy 57.191423 -334.585535) (xy 57.179835 -334.532281) (xy 57.175943 -334.477919) (xy 56.815084 -334.477919)
			(xy 56.811194 -334.532269) (xy 56.799608 -334.585511) (xy 56.780563 -334.636563) (xy 56.754446 -334.684385)
			(xy 56.72179 -334.728002) (xy 56.683257 -334.766529) (xy 56.639634 -334.799179) (xy 56.591809 -334.825288)
			(xy 56.540754 -334.844325) (xy 56.48751 -334.855902) (xy 56.43316 -334.859784) (xy 56.37881 -334.855891)
			(xy 56.325568 -334.844302) (xy 56.274518 -334.825254) (xy 56.226698 -334.799135) (xy 56.204612 -334.783176)
			(xy 56.1856 -334.76958) (xy 56.143717 -334.748848) (xy 56.098749 -334.736122) (xy 56.052212 -334.731832)
			(xy 56.005675 -334.736122) (xy 55.960707 -334.748848) (xy 55.918824 -334.76958) (xy 55.899812 -334.783176)
			(xy 55.877754 -334.79918) (xy 55.829925 -334.825307) (xy 55.778866 -334.844361) (xy 55.725614 -334.855953)
			(xy 55.671254 -334.859849) (xy 55.616893 -334.855969) (xy 55.563638 -334.844391) (xy 55.512573 -334.825352)
			(xy 55.464737 -334.799239) (xy 55.421105 -334.766583) (xy 55.382565 -334.72805) (xy 55.349901 -334.684424)
			(xy 55.323779 -334.636594) (xy 55.30473 -334.585532) (xy 55.293142 -334.532279) (xy 55.289251 -334.477919)
			(xy 40.454811 -334.477919) (xy 40.480843 -334.487629) (xy 40.528664 -334.513742) (xy 40.572283 -334.546395)
			(xy 40.61081 -334.584923) (xy 40.643462 -334.628542) (xy 40.669574 -334.676364) (xy 40.688615 -334.727416)
			(xy 40.700196 -334.780657) (xy 40.704083 -334.835005) (xy 40.700195 -334.889352) (xy 40.688612 -334.942594)
			(xy 40.66957 -334.993645) (xy 40.658297 -335.01429) (xy 64.789712 -335.01429) (xy 64.7936 -334.959941)
			(xy 64.805184 -334.906698) (xy 64.824228 -334.855646) (xy 64.850343 -334.807824) (xy 64.882998 -334.764205)
			(xy 64.921529 -334.725677) (xy 64.965151 -334.693026) (xy 65.012975 -334.666914) (xy 65.064029 -334.647875)
			(xy 65.117273 -334.636296) (xy 65.171623 -334.632412) (xy 65.225972 -334.636302) (xy 65.279215 -334.647888)
			(xy 65.330266 -334.666933) (xy 65.378088 -334.69305) (xy 65.400174 -334.709008) (xy 65.419186 -334.722604)
			(xy 65.461069 -334.743336) (xy 65.506037 -334.756062) (xy 65.552574 -334.760352) (xy 65.599111 -334.756062)
			(xy 65.644079 -334.743336) (xy 65.685962 -334.722604) (xy 65.704974 -334.709008) (xy 65.727048 -334.693024)
			(xy 65.774876 -334.666897) (xy 65.825936 -334.647844) (xy 65.879188 -334.636251) (xy 65.933548 -334.632355)
			(xy 65.987908 -334.636236) (xy 66.041163 -334.647814) (xy 66.092229 -334.666854) (xy 66.140064 -334.692968)
			(xy 66.183696 -334.725624) (xy 66.222236 -334.764157) (xy 66.254899 -334.807784) (xy 66.28102 -334.855615)
			(xy 66.300069 -334.906677) (xy 66.311655 -334.95993) (xy 66.315545 -335.01429) (xy 67.594103 -335.01429)
			(xy 67.597992 -334.959939) (xy 67.609577 -334.906694) (xy 67.628621 -334.85564) (xy 67.654738 -334.807817)
			(xy 67.687394 -334.764196) (xy 67.725927 -334.725668) (xy 67.769551 -334.693016) (xy 67.817377 -334.666904)
			(xy 67.868433 -334.647865) (xy 67.921679 -334.636287) (xy 67.976031 -334.632403) (xy 68.030382 -334.636295)
			(xy 68.083626 -334.647883) (xy 68.134679 -334.66693) (xy 68.182501 -334.693049) (xy 68.204588 -334.709008)
			(xy 68.2236 -334.722604) (xy 68.265483 -334.743336) (xy 68.310451 -334.756062) (xy 68.356988 -334.760352)
			(xy 68.403525 -334.756062) (xy 68.448493 -334.743336) (xy 68.490376 -334.722604) (xy 68.509388 -334.709008)
			(xy 68.531461 -334.693025) (xy 68.579289 -334.666901) (xy 68.630347 -334.647849) (xy 68.683598 -334.636258)
			(xy 68.737956 -334.632363) (xy 68.792314 -334.636245) (xy 68.845567 -334.647824) (xy 68.89663 -334.666864)
			(xy 68.944464 -334.692977) (xy 68.988094 -334.725633) (xy 69.026632 -334.764166) (xy 69.059293 -334.807791)
			(xy 69.085414 -334.85562) (xy 69.104461 -334.906681) (xy 69.116047 -334.959932) (xy 69.119937 -335.01429)
			(xy 69.11605 -335.068649) (xy 69.104466 -335.121901) (xy 69.085422 -335.172962) (xy 69.059304 -335.220793)
			(xy 69.026644 -335.26442) (xy 68.988108 -335.302955) (xy 68.94448 -335.335612) (xy 68.896648 -335.361728)
			(xy 68.845586 -335.380771) (xy 68.792333 -335.392352) (xy 68.737975 -335.396237) (xy 68.683617 -335.392345)
			(xy 68.630366 -335.380757) (xy 68.579306 -335.361707) (xy 68.531478 -335.335585) (xy 68.509388 -335.319624)
			(xy 68.490376 -335.306028) (xy 68.448493 -335.285296) (xy 68.403525 -335.27257) (xy 68.356988 -335.26828)
			(xy 68.310451 -335.27257) (xy 68.265483 -335.285296) (xy 68.2236 -335.306028) (xy 68.204588 -335.319624)
			(xy 68.182485 -335.335561) (xy 68.134661 -335.361678) (xy 68.083608 -335.380723) (xy 68.030363 -335.392307)
			(xy 67.976012 -335.396197) (xy 67.92166 -335.392311) (xy 67.868415 -335.380729) (xy 67.81736 -335.361688)
			(xy 67.769534 -335.335574) (xy 67.725912 -335.302919) (xy 67.687382 -335.264389) (xy 67.654727 -335.220767)
			(xy 67.628613 -335.172942) (xy 67.609571 -335.121887) (xy 67.59799 -335.068642) (xy 67.594103 -335.01429)
			(xy 66.315545 -335.01429) (xy 66.311658 -335.068651) (xy 66.300074 -335.121905) (xy 66.281028 -335.172968)
			(xy 66.254909 -335.2208) (xy 66.222248 -335.264428) (xy 66.18371 -335.302964) (xy 66.14008 -335.335622)
			(xy 66.092246 -335.361738) (xy 66.041182 -335.380781) (xy 65.987927 -335.392361) (xy 65.933567 -335.396245)
			(xy 65.879207 -335.392352) (xy 65.825954 -335.380762) (xy 65.774893 -335.361711) (xy 65.727064 -335.335586)
			(xy 65.704974 -335.319624) (xy 65.685962 -335.306028) (xy 65.644079 -335.285296) (xy 65.599111 -335.27257)
			(xy 65.552574 -335.26828) (xy 65.506037 -335.27257) (xy 65.461069 -335.285296) (xy 65.419186 -335.306028)
			(xy 65.400174 -335.319624) (xy 65.378071 -335.33556) (xy 65.330249 -335.361675) (xy 65.279196 -335.380717)
			(xy 65.225953 -335.3923) (xy 65.171604 -335.396188) (xy 65.117254 -335.392301) (xy 65.064011 -335.380719)
			(xy 65.012958 -335.361678) (xy 64.965135 -335.335564) (xy 64.921515 -335.30291) (xy 64.882986 -335.264381)
			(xy 64.850333 -335.22076) (xy 64.82422 -335.172937) (xy 64.805179 -335.121883) (xy 64.793598 -335.06864)
			(xy 64.789712 -335.01429) (xy 40.658297 -335.01429) (xy 40.643457 -335.041466) (xy 40.610804 -335.085084)
			(xy 40.572275 -335.123611) (xy 40.528656 -335.156263) (xy 40.480834 -335.182375) (xy 40.429783 -335.201415)
			(xy 40.376541 -335.212996) (xy 40.322193 -335.216883) (xy 40.267846 -335.212995) (xy 40.214605 -335.201412)
			(xy 40.163554 -335.18237) (xy 40.115733 -335.156256) (xy 40.093646 -335.1403) (xy 40.074634 -335.126704)
			(xy 40.032751 -335.105972) (xy 39.987783 -335.093246) (xy 39.941246 -335.088956) (xy 39.894709 -335.093246)
			(xy 39.849741 -335.105972) (xy 39.807858 -335.126704) (xy 39.788846 -335.1403) (xy 39.766764 -335.156275)
			(xy 39.718935 -335.182404) (xy 39.667874 -335.201459) (xy 39.614621 -335.213054) (xy 39.560259 -335.21695)
			(xy 39.505896 -335.21307) (xy 39.452639 -335.201493) (xy 39.401572 -335.182453) (xy 39.353735 -335.156338)
			(xy 39.310102 -335.123681) (xy 39.27156 -335.085147) (xy 39.238896 -335.041519) (xy 39.212774 -334.993686)
			(xy 39.193725 -334.942622) (xy 39.182139 -334.889367) (xy 39.17825 -334.835005) (xy 29.726995 -334.835005)
			(xy 29.739164 -334.863439) (xy 29.763451 -334.900598) (xy 29.793821 -334.932975) (xy 29.829351 -334.959588)
			(xy 29.868962 -334.979628) (xy 29.911451 -334.992486) (xy 29.955527 -334.997772) (xy 29.999851 -334.995324)
			(xy 30.043078 -334.985218) (xy 30.063694 -334.976978) (xy 30.103694 -334.958964) (xy 30.186362 -334.929591)
			(xy 30.271408 -334.908045) (xy 30.35809 -334.894515) (xy 30.445656 -334.889117) (xy 30.533343 -334.891898)
			(xy 30.620391 -334.902835) (xy 30.706041 -334.921833) (xy 30.78955 -334.948725) (xy 30.870191 -334.983279)
			(xy 30.947263 -335.025193) (xy 31.020096 -335.074104) (xy 31.088056 -335.129587) (xy 31.150553 -335.191158)
			(xy 31.207044 -335.258282) (xy 31.257037 -335.330376) (xy 31.300098 -335.406814) (xy 31.335852 -335.48693)
			(xy 31.363988 -335.570027) (xy 31.384262 -335.655385) (xy 31.396497 -335.742259) (xy 31.400588 -335.829896)
			(xy 31.39856 -335.87336) (xy 34.599874 -335.87336) (xy 34.599874 -335.78646) (xy 34.607892 -335.699931)
			(xy 34.62386 -335.614511) (xy 34.647641 -335.530929) (xy 34.679033 -335.449897) (xy 34.717767 -335.372108)
			(xy 34.763514 -335.298224) (xy 34.815883 -335.228877) (xy 34.874427 -335.164657) (xy 34.938647 -335.106113)
			(xy 35.007994 -335.053744) (xy 35.081878 -335.007997) (xy 35.159667 -334.969263) (xy 35.240699 -334.937871)
			(xy 35.324281 -334.91409) (xy 35.409701 -334.898122) (xy 35.49623 -334.890104) (xy 35.58313 -334.890104)
			(xy 35.669659 -334.898122) (xy 35.755079 -334.91409) (xy 35.838661 -334.937871) (xy 35.919693 -334.969263)
			(xy 35.997482 -335.007997) (xy 36.071366 -335.053744) (xy 36.140713 -335.106113) (xy 36.204933 -335.164657)
			(xy 36.263477 -335.228877) (xy 36.315846 -335.298224) (xy 36.361593 -335.372108) (xy 36.400327 -335.449897)
			(xy 36.431719 -335.530929) (xy 36.4555 -335.614511) (xy 36.471468 -335.699931) (xy 36.479486 -335.78646)
			(xy 36.479988 -335.82991) (xy 36.479486 -335.87336) (xy 36.471468 -335.959889) (xy 36.4555 -336.045309)
			(xy 36.431719 -336.128891) (xy 36.400327 -336.209923) (xy 36.361593 -336.287712) (xy 36.315846 -336.361596)
			(xy 36.310703 -336.368406) (xy 55.289268 -336.368406) (xy 55.293155 -336.314048) (xy 55.304739 -336.260797)
			(xy 55.323784 -336.209737) (xy 55.349902 -336.161907) (xy 55.382562 -336.11828) (xy 55.421098 -336.079747)
			(xy 55.464726 -336.04709) (xy 55.512557 -336.020975) (xy 55.563619 -336.001933) (xy 55.616871 -335.990352)
			(xy 55.671229 -335.986468) (xy 55.725586 -335.99036) (xy 55.778836 -336.001949) (xy 55.829895 -336.020999)
			(xy 55.877723 -336.047121) (xy 55.899812 -336.063082) (xy 55.918824 -336.076678) (xy 55.960707 -336.09741)
			(xy 56.005675 -336.110136) (xy 56.052212 -336.114426) (xy 56.098749 -336.110136) (xy 56.143717 -336.09741)
			(xy 56.1856 -336.076678) (xy 56.204612 -336.063082) (xy 56.226709 -336.047137) (xy 56.274533 -336.021019)
			(xy 56.325588 -336.001974) (xy 56.378833 -335.990388) (xy 56.433185 -335.986499) (xy 56.487537 -335.990384)
			(xy 56.540783 -336.001965) (xy 56.591839 -336.021006) (xy 56.639665 -336.04712) (xy 56.683288 -336.079775)
			(xy 56.721819 -336.118305) (xy 56.754475 -336.161927) (xy 56.78059 -336.209753) (xy 56.799632 -336.260808)
			(xy 56.811215 -336.314054) (xy 56.815101 -336.368406) (xy 57.175961 -336.368406) (xy 57.179848 -336.314047)
			(xy 57.191433 -336.260794) (xy 57.210478 -336.209732) (xy 57.236597 -336.161901) (xy 57.269258 -336.118273)
			(xy 57.307796 -336.079739) (xy 57.351426 -336.047081) (xy 57.399259 -336.020966) (xy 57.450322 -336.001924)
			(xy 57.503576 -335.990344) (xy 57.557936 -335.986461) (xy 57.612295 -335.990354) (xy 57.665546 -336.001944)
			(xy 57.716606 -336.020996) (xy 57.764435 -336.04712) (xy 57.786524 -336.063082) (xy 57.805536 -336.076678)
			(xy 57.847419 -336.09741) (xy 57.892387 -336.110136) (xy 57.938924 -336.114426) (xy 57.985461 -336.110136)
			(xy 58.030429 -336.09741) (xy 58.072312 -336.076678) (xy 58.091324 -336.063082) (xy 58.113421 -336.047138)
			(xy 58.161244 -336.021022) (xy 58.212297 -336.001978) (xy 58.265541 -335.990394) (xy 58.319892 -335.986506)
			(xy 58.374242 -335.990392) (xy 58.427486 -336.001974) (xy 58.47854 -336.021015) (xy 58.526365 -336.047129)
			(xy 58.569986 -336.079782) (xy 58.608516 -336.118312) (xy 58.64117 -336.161933) (xy 58.667284 -336.209757)
			(xy 58.686326 -336.260811) (xy 58.697908 -336.314055) (xy 58.701794 -336.368406) (xy 59.417096 -336.368406)
			(xy 59.420982 -336.314055) (xy 59.432564 -336.260809) (xy 59.451606 -336.209755) (xy 59.47772 -336.161929)
			(xy 59.510375 -336.118308) (xy 59.548905 -336.079777) (xy 59.592527 -336.047122) (xy 59.640352 -336.021008)
			(xy 59.691406 -336.001965) (xy 59.744651 -335.990383) (xy 59.799003 -335.986496) (xy 59.853354 -335.990384)
			(xy 59.906599 -336.001967) (xy 59.957653 -336.02101) (xy 60.005478 -336.047125) (xy 60.027566 -336.063082)
			(xy 60.046578 -336.076678) (xy 60.088461 -336.09741) (xy 60.133429 -336.110136) (xy 60.179966 -336.114426)
			(xy 60.226503 -336.110136) (xy 60.271471 -336.09741) (xy 60.313354 -336.076678) (xy 60.332366 -336.063082)
			(xy 60.354464 -336.047133) (xy 60.402292 -336.021008) (xy 60.45335 -336.001956) (xy 60.506601 -335.990365)
			(xy 60.560959 -335.986471) (xy 60.615317 -335.990353) (xy 60.66857 -336.001933) (xy 60.719633 -336.020973)
			(xy 60.767466 -336.047088) (xy 60.811095 -336.079744) (xy 60.849632 -336.118278) (xy 60.882293 -336.161904)
			(xy 60.908412 -336.209735) (xy 60.927457 -336.260796) (xy 60.939042 -336.314048) (xy 60.942929 -336.368406)
			(xy 61.320946 -336.368406) (xy 61.324833 -336.314043) (xy 61.336419 -336.260787) (xy 61.355466 -336.209722)
			(xy 61.381587 -336.161888) (xy 61.414251 -336.118258) (xy 61.452792 -336.079722) (xy 61.496425 -336.047063)
			(xy 61.544262 -336.020947) (xy 61.59533 -336.001906) (xy 61.648587 -335.990327) (xy 61.70295 -335.986446)
			(xy 61.757313 -335.990341) (xy 61.810567 -336.001934) (xy 61.86163 -336.020989) (xy 61.90946 -336.047118)
			(xy 61.93155 -336.063082) (xy 61.950562 -336.076678) (xy 61.992445 -336.09741) (xy 62.037413 -336.110136)
			(xy 62.08395 -336.114426) (xy 62.130487 -336.110136) (xy 62.175455 -336.09741) (xy 62.217338 -336.076678)
			(xy 62.23635 -336.063082) (xy 62.258449 -336.047131) (xy 62.306277 -336.021004) (xy 62.357337 -336.00195)
			(xy 62.410589 -335.990357) (xy 62.46495 -335.986462) (xy 62.519311 -335.990343) (xy 62.572566 -336.001921)
			(xy 62.623631 -336.020962) (xy 62.671466 -336.047077) (xy 62.715098 -336.079734) (xy 62.753637 -336.118269)
			(xy 62.786299 -336.161896) (xy 62.81242 -336.209728) (xy 62.831466 -336.260791) (xy 62.843051 -336.314045)
			(xy 62.846938 -336.368406) (xy 62.843049 -336.422767) (xy 62.831463 -336.47602) (xy 62.812415 -336.527082)
			(xy 62.786293 -336.574914) (xy 62.753629 -336.61854) (xy 62.715089 -336.657074) (xy 62.671456 -336.68973)
			(xy 62.62362 -336.715843) (xy 62.572554 -336.734882) (xy 62.519299 -336.746459) (xy 62.464938 -336.750338)
			(xy 62.410578 -336.746441) (xy 62.357326 -336.734847) (xy 62.306266 -336.715791) (xy 62.258439 -336.689662)
			(xy 62.23635 -336.673698) (xy 62.217338 -336.660102) (xy 62.175455 -336.63937) (xy 62.130487 -336.626644)
			(xy 62.08395 -336.622354) (xy 62.037413 -336.626644) (xy 61.992445 -336.63937) (xy 61.950562 -336.660102)
			(xy 61.93155 -336.673698) (xy 61.90947 -336.689676) (xy 61.86164 -336.715806) (xy 61.810579 -336.734862)
			(xy 61.757325 -336.746457) (xy 61.702962 -336.750354) (xy 61.648599 -336.746475) (xy 61.595341 -336.734897)
			(xy 61.544273 -336.715858) (xy 61.496435 -336.689743) (xy 61.452801 -336.657086) (xy 61.414259 -336.618551)
			(xy 61.381594 -336.574923) (xy 61.355471 -336.527089) (xy 61.336422 -336.476025) (xy 61.324835 -336.422769)
			(xy 61.320946 -336.368406) (xy 60.942929 -336.368406) (xy 60.93904 -336.422764) (xy 60.927454 -336.476016)
			(xy 60.908407 -336.527076) (xy 60.882286 -336.574906) (xy 60.849625 -336.618531) (xy 60.811086 -336.657063)
			(xy 60.767456 -336.689719) (xy 60.719622 -336.715832) (xy 60.668559 -336.734871) (xy 60.615306 -336.746448)
			(xy 60.560947 -336.750329) (xy 60.506589 -336.746433) (xy 60.453339 -336.734841) (xy 60.402281 -336.715787)
			(xy 60.354454 -336.689661) (xy 60.332366 -336.673698) (xy 60.313354 -336.660102) (xy 60.271471 -336.63937)
			(xy 60.226503 -336.626644) (xy 60.179966 -336.622354) (xy 60.133429 -336.626644) (xy 60.088461 -336.63937)
			(xy 60.046578 -336.660102) (xy 60.027566 -336.673698) (xy 60.005488 -336.689669) (xy 59.957664 -336.715785)
			(xy 59.90661 -336.73483) (xy 59.853366 -336.746415) (xy 59.799015 -336.750304) (xy 59.744663 -336.746419)
			(xy 59.691418 -336.734838) (xy 59.640362 -336.715797) (xy 59.592537 -336.689684) (xy 59.548914 -336.657031)
			(xy 59.510383 -336.618502) (xy 59.477727 -336.574881) (xy 59.451611 -336.527056) (xy 59.432568 -336.476002)
			(xy 59.420984 -336.422757) (xy 59.417096 -336.368406) (xy 58.701794 -336.368406) (xy 58.697906 -336.422756)
			(xy 58.686322 -336.476) (xy 58.667279 -336.527054) (xy 58.641164 -336.574877) (xy 58.608508 -336.618497)
			(xy 58.569977 -336.657025) (xy 58.526355 -336.689678) (xy 58.47853 -336.71579) (xy 58.427475 -336.73483)
			(xy 58.37423 -336.74641) (xy 58.31988 -336.750294) (xy 58.265529 -336.746404) (xy 58.212286 -336.734818)
			(xy 58.161233 -336.715773) (xy 58.113411 -336.689656) (xy 58.091324 -336.673698) (xy 58.072312 -336.660102)
			(xy 58.030429 -336.63937) (xy 57.985461 -336.626644) (xy 57.938924 -336.622354) (xy 57.892387 -336.626644)
			(xy 57.847419 -336.63937) (xy 57.805536 -336.660102) (xy 57.786524 -336.673698) (xy 57.764445 -336.689673)
			(xy 57.716617 -336.715799) (xy 57.665558 -336.734852) (xy 57.612307 -336.746444) (xy 57.557948 -336.750339)
			(xy 57.503588 -336.746458) (xy 57.450334 -336.734879) (xy 57.39927 -336.715839) (xy 57.351436 -336.689725)
			(xy 57.307805 -336.657069) (xy 57.269266 -336.618536) (xy 57.236604 -336.57491) (xy 57.210483 -336.527079)
			(xy 57.191436 -336.476018) (xy 57.17985 -336.422765) (xy 57.175961 -336.368406) (xy 56.815101 -336.368406)
			(xy 56.811213 -336.422758) (xy 56.799629 -336.476003) (xy 56.780585 -336.527058) (xy 56.754468 -336.574883)
			(xy 56.721812 -336.618504) (xy 56.683279 -336.657033) (xy 56.639655 -336.689686) (xy 56.591828 -336.715799)
			(xy 56.540772 -336.734838) (xy 56.487525 -336.746418) (xy 56.433173 -336.750301) (xy 56.378821 -336.74641)
			(xy 56.325576 -336.734823) (xy 56.274522 -336.715776) (xy 56.226699 -336.689657) (xy 56.204612 -336.673698)
			(xy 56.1856 -336.660102) (xy 56.143717 -336.63937) (xy 56.098749 -336.626644) (xy 56.052212 -336.622354)
			(xy 56.005675 -336.626644) (xy 55.960707 -336.63937) (xy 55.918824 -336.660102) (xy 55.899812 -336.673698)
			(xy 55.877733 -336.689672) (xy 55.829906 -336.715796) (xy 55.778848 -336.734847) (xy 55.725598 -336.746438)
			(xy 55.671241 -336.750332) (xy 55.616883 -336.74645) (xy 55.563631 -336.734871) (xy 55.512568 -336.71583)
			(xy 55.464736 -336.689717) (xy 55.421107 -336.657061) (xy 55.38257 -336.618529) (xy 55.349909 -336.574904)
			(xy 55.323789 -336.527074) (xy 55.304743 -336.476014) (xy 55.293157 -336.422764) (xy 55.289268 -336.368406)
			(xy 36.310703 -336.368406) (xy 36.263477 -336.430943) (xy 36.204933 -336.495163) (xy 36.140713 -336.553707)
			(xy 36.071366 -336.606076) (xy 35.997482 -336.651823) (xy 35.919693 -336.690557) (xy 35.838661 -336.721949)
			(xy 35.755079 -336.74573) (xy 35.669659 -336.761698) (xy 35.58313 -336.769716) (xy 35.49623 -336.769716)
			(xy 35.409701 -336.761698) (xy 35.324281 -336.74573) (xy 35.240699 -336.721949) (xy 35.159667 -336.690557)
			(xy 35.081878 -336.651823) (xy 35.007994 -336.606076) (xy 34.938647 -336.553707) (xy 34.874427 -336.495163)
			(xy 34.815883 -336.430943) (xy 34.763514 -336.361596) (xy 34.717767 -336.287712) (xy 34.679033 -336.209923)
			(xy 34.647641 -336.128891) (xy 34.62386 -336.045309) (xy 34.607892 -335.959889) (xy 34.599874 -335.87336)
			(xy 31.39856 -335.87336) (xy 31.396498 -335.917532) (xy 31.384263 -336.004407) (xy 31.36399 -336.089764)
			(xy 31.335855 -336.172863) (xy 31.300101 -336.252979) (xy 31.257042 -336.329417) (xy 31.207049 -336.401511)
			(xy 31.150559 -336.468636) (xy 31.088062 -336.530208) (xy 31.020102 -336.585691) (xy 30.94727 -336.634602)
			(xy 30.870199 -336.676518) (xy 30.789558 -336.711072) (xy 30.70605 -336.737965) (xy 30.620399 -336.756963)
			(xy 30.533352 -336.767901) (xy 30.445664 -336.770683) (xy 30.358098 -336.765286) (xy 30.271416 -336.751756)
			(xy 30.18637 -336.730212) (xy 30.103701 -336.700839) (xy 30.063694 -336.682842) (xy 30.043103 -336.674515)
			(xy 29.999863 -336.664379) (xy 29.955519 -336.661912) (xy 29.911421 -336.667188) (xy 29.868911 -336.680046)
			(xy 29.829282 -336.700095) (xy 29.793739 -336.726725) (xy 29.763364 -336.759126) (xy 29.739082 -336.796313)
			(xy 29.72163 -336.837153) (xy 29.711541 -336.880404) (xy 29.709872 -336.902552) (xy 29.709872 -337.297268)
			(xy 29.711583 -337.319403) (xy 29.721698 -337.362627) (xy 29.739164 -337.403439) (xy 29.763451 -337.440598)
			(xy 29.793821 -337.472975) (xy 29.829351 -337.499588) (xy 29.868962 -337.519628) (xy 29.911451 -337.532486)
			(xy 29.955527 -337.537772) (xy 29.999851 -337.535324) (xy 30.043078 -337.525218) (xy 30.063694 -337.516978)
			(xy 30.103694 -337.498964) (xy 30.186362 -337.469591) (xy 30.271408 -337.448045) (xy 30.35809 -337.434515)
			(xy 30.445656 -337.429117) (xy 30.533343 -337.431898) (xy 30.620391 -337.442835) (xy 30.706041 -337.461833)
			(xy 30.78955 -337.488725) (xy 30.870191 -337.523279) (xy 30.947263 -337.565193) (xy 31.020096 -337.614104)
			(xy 31.088056 -337.669587) (xy 31.150553 -337.731158) (xy 31.207044 -337.798282) (xy 31.257037 -337.870376)
			(xy 31.300098 -337.946814) (xy 31.335852 -338.02693) (xy 31.363988 -338.110027) (xy 31.384262 -338.195385)
			(xy 31.396497 -338.282259) (xy 31.400588 -338.369896) (xy 31.39856 -338.41336) (xy 34.599874 -338.41336)
			(xy 34.599874 -338.32646) (xy 34.607892 -338.239931) (xy 34.62386 -338.154511) (xy 34.647641 -338.070929)
			(xy 34.679033 -337.989897) (xy 34.717767 -337.912108) (xy 34.763514 -337.838224) (xy 34.815883 -337.768877)
			(xy 34.874427 -337.704657) (xy 34.938647 -337.646113) (xy 35.007994 -337.593744) (xy 35.081878 -337.547997)
			(xy 35.159667 -337.509263) (xy 35.240699 -337.477871) (xy 35.324281 -337.45409) (xy 35.409701 -337.438122)
			(xy 35.49623 -337.430104) (xy 35.58313 -337.430104) (xy 35.669659 -337.438122) (xy 35.755079 -337.45409)
			(xy 35.838661 -337.477871) (xy 35.90436 -337.503323) (xy 39.178225 -337.503323) (xy 39.182111 -337.448957)
			(xy 39.193694 -337.395698) (xy 39.21274 -337.344629) (xy 39.238861 -337.296792) (xy 39.271524 -337.253159)
			(xy 39.310065 -337.214618) (xy 39.353699 -337.181956) (xy 39.401537 -337.155837) (xy 39.452606 -337.136792)
			(xy 39.505866 -337.12521) (xy 39.560231 -337.121325) (xy 39.614597 -337.125219) (xy 39.667854 -337.13681)
			(xy 39.71892 -337.155863) (xy 39.766754 -337.18199) (xy 39.788846 -337.197954) (xy 39.807858 -337.21155)
			(xy 39.849741 -337.232282) (xy 39.894709 -337.245008) (xy 39.941246 -337.249298) (xy 39.987783 -337.245008)
			(xy 40.032751 -337.232282) (xy 40.074634 -337.21155) (xy 40.093646 -337.197954) (xy 40.115769 -337.182049)
			(xy 40.163589 -337.155941) (xy 40.214638 -337.136904) (xy 40.267876 -337.125325) (xy 40.322221 -337.121441)
			(xy 40.376565 -337.125331) (xy 40.429802 -337.136915) (xy 40.480849 -337.155958) (xy 40.528666 -337.182072)
			(xy 40.572281 -337.214725) (xy 40.610804 -337.253252) (xy 40.643452 -337.29687) (xy 40.66956 -337.344691)
			(xy 40.688597 -337.39574) (xy 40.700175 -337.448978) (xy 40.704059 -337.503323) (xy 40.700168 -337.557667)
			(xy 40.688584 -337.610904) (xy 40.669541 -337.661951) (xy 40.643427 -337.709768) (xy 40.610774 -337.753382)
			(xy 40.572246 -337.791905) (xy 40.528628 -337.824553) (xy 40.480808 -337.850661) (xy 40.429759 -337.869697)
			(xy 40.37652 -337.881275) (xy 40.322175 -337.885159) (xy 40.267831 -337.881268) (xy 40.214594 -337.869684)
			(xy 40.163547 -337.85064) (xy 40.11573 -337.824526) (xy 40.093646 -337.80857) (xy 40.074634 -337.794974)
			(xy 40.032751 -337.774242) (xy 39.987783 -337.761516) (xy 39.941246 -337.757226) (xy 39.894709 -337.761516)
			(xy 39.849741 -337.774242) (xy 39.807858 -337.794974) (xy 39.788846 -337.80857) (xy 39.766792 -337.824585)
			(xy 39.718961 -337.850718) (xy 39.667898 -337.869777) (xy 39.614642 -337.881375) (xy 39.560277 -337.885275)
			(xy 39.505911 -337.881397) (xy 39.45265 -337.869821) (xy 39.401579 -337.850782) (xy 39.353737 -337.824668)
			(xy 39.310099 -337.792011) (xy 39.271554 -337.753476) (xy 39.238886 -337.709847) (xy 39.212759 -337.662012)
			(xy 39.193707 -337.610946) (xy 39.182117 -337.557688) (xy 39.178225 -337.503323) (xy 35.90436 -337.503323)
			(xy 35.919693 -337.509263) (xy 35.997482 -337.547997) (xy 36.071366 -337.593744) (xy 36.140713 -337.646113)
			(xy 36.204933 -337.704657) (xy 36.263477 -337.768877) (xy 36.315846 -337.838224) (xy 36.361593 -337.912108)
			(xy 36.400327 -337.989897) (xy 36.431719 -338.070929) (xy 36.4555 -338.154511) (xy 36.471468 -338.239931)
			(xy 36.479486 -338.32646) (xy 36.479988 -338.36991) (xy 36.479531 -338.40948) (xy 55.289304 -338.40948)
			(xy 55.293194 -338.355127) (xy 55.304781 -338.301882) (xy 55.323827 -338.250827) (xy 55.349946 -338.203003)
			(xy 55.382606 -338.159384) (xy 55.421141 -338.120856) (xy 55.464767 -338.088205) (xy 55.512596 -338.062096)
			(xy 55.563654 -338.043059) (xy 55.616902 -338.031483) (xy 55.671255 -338.027604) (xy 55.725607 -338.031499)
			(xy 55.778852 -338.04309) (xy 55.829904 -338.062142) (xy 55.877726 -338.088265) (xy 55.899812 -338.104226)
			(xy 55.918824 -338.117822) (xy 55.960707 -338.138554) (xy 56.005675 -338.15128) (xy 56.052212 -338.15557)
			(xy 56.098749 -338.15128) (xy 56.143717 -338.138554) (xy 56.1856 -338.117822) (xy 56.204612 -338.104226)
			(xy 56.226668 -338.088221) (xy 56.274495 -338.062098) (xy 56.325552 -338.043047) (xy 56.378802 -338.031457)
			(xy 56.433158 -338.027563) (xy 56.487516 -338.031445) (xy 56.540768 -338.043024) (xy 56.59183 -338.062063)
			(xy 56.639662 -338.088176) (xy 56.683291 -338.120831) (xy 56.721829 -338.159362) (xy 56.75449 -338.202986)
			(xy 56.780611 -338.250814) (xy 56.799659 -338.301873) (xy 56.811246 -338.355123) (xy 56.815137 -338.40948)
			(xy 57.175996 -338.40948) (xy 57.179887 -338.355125) (xy 57.191474 -338.301878) (xy 57.210521 -338.250823)
			(xy 57.236641 -338.202997) (xy 57.269302 -338.159377) (xy 57.307839 -338.120848) (xy 57.351467 -338.088197)
			(xy 57.399298 -338.062087) (xy 57.450358 -338.043051) (xy 57.503607 -338.031475) (xy 57.557962 -338.027596)
			(xy 57.612316 -338.031493) (xy 57.665562 -338.043086) (xy 57.716615 -338.062139) (xy 57.764438 -338.088264)
			(xy 57.786524 -338.104226) (xy 57.805536 -338.117822) (xy 57.847419 -338.138554) (xy 57.892387 -338.15128)
			(xy 57.938924 -338.15557) (xy 57.985461 -338.15128) (xy 58.030429 -338.138554) (xy 58.072312 -338.117822)
			(xy 58.091324 -338.104226) (xy 58.11338 -338.088222) (xy 58.161206 -338.062101) (xy 58.212262 -338.043052)
			(xy 58.26551 -338.031463) (xy 58.319865 -338.027571) (xy 58.374221 -338.031453) (xy 58.427471 -338.043032)
			(xy 58.478531 -338.062072) (xy 58.526362 -338.088185) (xy 58.569989 -338.120839) (xy 58.608525 -338.159369)
			(xy 58.641186 -338.202992) (xy 58.667305 -338.250819) (xy 58.686352 -338.301876) (xy 58.697939 -338.355124)
			(xy 58.701829 -338.40948) (xy 59.417131 -338.40948) (xy 59.421021 -338.355133) (xy 59.432606 -338.301894)
			(xy 59.451649 -338.250845) (xy 59.477764 -338.203026) (xy 59.510419 -338.159411) (xy 59.548948 -338.120886)
			(xy 59.592568 -338.088237) (xy 59.64039 -338.062129) (xy 59.691441 -338.043092) (xy 59.744682 -338.031514)
			(xy 59.799029 -338.027631) (xy 59.853375 -338.031522) (xy 59.906614 -338.043108) (xy 59.957663 -338.062153)
			(xy 60.005481 -338.088269) (xy 60.027566 -338.104226) (xy 60.046578 -338.117822) (xy 60.088461 -338.138554)
			(xy 60.133429 -338.15128) (xy 60.179966 -338.15557) (xy 60.226503 -338.15128) (xy 60.271471 -338.138554)
			(xy 60.313354 -338.117822) (xy 60.332366 -338.104226) (xy 60.354423 -338.088217) (xy 60.402253 -338.062087)
			(xy 60.453315 -338.04303) (xy 60.506569 -338.031434) (xy 60.560932 -338.027536) (xy 60.615296 -338.031415)
			(xy 60.668555 -338.042991) (xy 60.719624 -338.06203) (xy 60.767463 -338.088144) (xy 60.811098 -338.1208)
			(xy 60.849642 -338.159335) (xy 60.882308 -338.202963) (xy 60.908433 -338.250796) (xy 60.927484 -338.30186)
			(xy 60.939073 -338.355116) (xy 60.942964 -338.40948) (xy 61.320981 -338.40948) (xy 61.324872 -338.355122)
			(xy 61.33646 -338.301871) (xy 61.355509 -338.250812) (xy 61.381631 -338.202984) (xy 61.414295 -338.159361)
			(xy 61.452835 -338.120831) (xy 61.496466 -338.088179) (xy 61.544301 -338.062068) (xy 61.595365 -338.043032)
			(xy 61.648618 -338.031458) (xy 61.702977 -338.027581) (xy 61.757334 -338.03148) (xy 61.810583 -338.043076)
			(xy 61.861639 -338.062132) (xy 61.909463 -338.088262) (xy 61.93155 -338.104226) (xy 61.950562 -338.117822)
			(xy 61.992445 -338.138554) (xy 62.037413 -338.15128) (xy 62.08395 -338.15557) (xy 62.130487 -338.15128)
			(xy 62.175455 -338.138554) (xy 62.217338 -338.117822) (xy 62.23635 -338.104226) (xy 62.258407 -338.088216)
			(xy 62.306238 -338.062083) (xy 62.357302 -338.043023) (xy 62.410558 -338.031426) (xy 62.464923 -338.027526)
			(xy 62.519289 -338.031404) (xy 62.57255 -338.04298) (xy 62.623622 -338.062019) (xy 62.671463 -338.088133)
			(xy 62.715101 -338.12079) (xy 62.753646 -338.159326) (xy 62.786315 -338.202955) (xy 62.812441 -338.25079)
			(xy 62.831492 -338.301856) (xy 62.843082 -338.355114) (xy 62.846974 -338.40948) (xy 62.843088 -338.463845)
			(xy 62.831504 -338.517105) (xy 62.812458 -338.568173) (xy 62.786337 -338.616011) (xy 62.753673 -338.659644)
			(xy 62.715132 -338.698183) (xy 62.671498 -338.730845) (xy 62.623659 -338.756964) (xy 62.57259 -338.776008)
			(xy 62.51933 -338.78759) (xy 62.464964 -338.791474) (xy 62.410599 -338.78758) (xy 62.357341 -338.775988)
			(xy 62.306276 -338.756934) (xy 62.258442 -338.730806) (xy 62.23635 -338.714842) (xy 62.217338 -338.701246)
			(xy 62.175455 -338.680514) (xy 62.130487 -338.667788) (xy 62.08395 -338.663498) (xy 62.037413 -338.667788)
			(xy 61.992445 -338.680514) (xy 61.950562 -338.701246) (xy 61.93155 -338.714842) (xy 61.909429 -338.73076)
			(xy 61.861602 -338.756885) (xy 61.810544 -338.775936) (xy 61.757294 -338.787526) (xy 61.702936 -338.791419)
			(xy 61.648578 -338.787536) (xy 61.595326 -338.775956) (xy 61.544264 -338.756915) (xy 61.496432 -338.730799)
			(xy 61.452804 -338.698142) (xy 61.414268 -338.659608) (xy 61.381609 -338.615981) (xy 61.355492 -338.56815)
			(xy 61.336448 -338.517089) (xy 61.324866 -338.463838) (xy 61.320981 -338.40948) (xy 60.942964 -338.40948)
			(xy 60.939079 -338.463843) (xy 60.927495 -338.5171) (xy 60.90845 -338.568167) (xy 60.88233 -338.616003)
			(xy 60.849668 -338.659634) (xy 60.811129 -338.698173) (xy 60.767497 -338.730834) (xy 60.719661 -338.756953)
			(xy 60.668594 -338.775997) (xy 60.615337 -338.787579) (xy 60.560973 -338.791464) (xy 60.50661 -338.787572)
			(xy 60.453354 -338.775982) (xy 60.40229 -338.75693) (xy 60.354457 -338.730805) (xy 60.332366 -338.714842)
			(xy 60.313354 -338.701246) (xy 60.271471 -338.680514) (xy 60.226503 -338.667788) (xy 60.179966 -338.663498)
			(xy 60.133429 -338.667788) (xy 60.088461 -338.680514) (xy 60.046578 -338.701246) (xy 60.027566 -338.714842)
			(xy 60.005447 -338.730753) (xy 59.957626 -338.756864) (xy 59.906575 -338.775903) (xy 59.853335 -338.787484)
			(xy 59.798988 -338.791369) (xy 59.744642 -338.78748) (xy 59.691402 -338.775897) (xy 59.640353 -338.756854)
			(xy 59.592534 -338.730741) (xy 59.548917 -338.698087) (xy 59.510392 -338.659559) (xy 59.477742 -338.615939)
			(xy 59.451632 -338.568118) (xy 59.432594 -338.517067) (xy 59.421015 -338.463826) (xy 59.417131 -338.40948)
			(xy 58.701829 -338.40948) (xy 58.697945 -338.463835) (xy 58.686364 -338.517085) (xy 58.667322 -338.568144)
			(xy 58.641208 -338.615974) (xy 58.608552 -338.6596) (xy 58.57002 -338.698135) (xy 58.526396 -338.730793)
			(xy 58.478568 -338.756911) (xy 58.42751 -338.775956) (xy 58.374261 -338.787541) (xy 58.319906 -338.791429)
			(xy 58.26555 -338.787543) (xy 58.212301 -338.775959) (xy 58.161243 -338.756916) (xy 58.113414 -338.7308)
			(xy 58.091324 -338.714842) (xy 58.072312 -338.701246) (xy 58.030429 -338.680514) (xy 57.985461 -338.667788)
			(xy 57.938924 -338.663498) (xy 57.892387 -338.667788) (xy 57.847419 -338.680514) (xy 57.805536 -338.701246)
			(xy 57.786524 -338.714842) (xy 57.764403 -338.730758) (xy 57.716578 -338.756878) (xy 57.665522 -338.775926)
			(xy 57.612275 -338.787513) (xy 57.557921 -338.791404) (xy 57.503567 -338.787519) (xy 57.450318 -338.775938)
			(xy 57.39926 -338.756896) (xy 57.351432 -338.730781) (xy 57.307808 -338.698125) (xy 57.269275 -338.659593)
			(xy 57.236619 -338.615968) (xy 57.210504 -338.56814) (xy 57.191462 -338.517082) (xy 57.179881 -338.463834)
			(xy 57.175996 -338.40948) (xy 56.815137 -338.40948) (xy 56.811252 -338.463837) (xy 56.79967 -338.517088)
			(xy 56.780628 -338.568149) (xy 56.754512 -338.61598) (xy 56.721855 -338.659607) (xy 56.683322 -338.698143)
			(xy 56.639696 -338.730802) (xy 56.591867 -338.75692) (xy 56.540807 -338.775965) (xy 56.487556 -338.787549)
			(xy 56.433199 -338.791437) (xy 56.378842 -338.787549) (xy 56.325592 -338.775964) (xy 56.274532 -338.756919)
			(xy 56.226702 -338.730801) (xy 56.204612 -338.714842) (xy 56.1856 -338.701246) (xy 56.143717 -338.680514)
			(xy 56.098749 -338.667788) (xy 56.052212 -338.663498) (xy 56.005675 -338.667788) (xy 55.960707 -338.680514)
			(xy 55.918824 -338.701246) (xy 55.899812 -338.714842) (xy 55.877692 -338.730757) (xy 55.829867 -338.756875)
			(xy 55.778813 -338.775921) (xy 55.725567 -338.787507) (xy 55.671214 -338.791396) (xy 55.616862 -338.787511)
			(xy 55.563615 -338.775929) (xy 55.512559 -338.756887) (xy 55.464733 -338.730773) (xy 55.42111 -338.698117)
			(xy 55.382579 -338.659586) (xy 55.349924 -338.615962) (xy 55.32381 -338.568136) (xy 55.304769 -338.517079)
			(xy 55.293188 -338.463832) (xy 55.289304 -338.40948) (xy 36.479531 -338.40948) (xy 36.479486 -338.41336)
			(xy 36.471468 -338.499889) (xy 36.4555 -338.585309) (xy 36.431719 -338.668891) (xy 36.400327 -338.749923)
			(xy 36.361593 -338.827712) (xy 36.315846 -338.901596) (xy 36.263477 -338.970943) (xy 36.204933 -339.035163)
			(xy 36.140713 -339.093707) (xy 36.071366 -339.146076) (xy 35.997482 -339.191823) (xy 35.919693 -339.230557)
			(xy 35.838661 -339.261949) (xy 35.755079 -339.28573) (xy 35.669659 -339.301698) (xy 35.58313 -339.309716)
			(xy 35.49623 -339.309716) (xy 35.409701 -339.301698) (xy 35.324281 -339.28573) (xy 35.240699 -339.261949)
			(xy 35.159667 -339.230557) (xy 35.081878 -339.191823) (xy 35.007994 -339.146076) (xy 34.938647 -339.093707)
			(xy 34.874427 -339.035163) (xy 34.815883 -338.970943) (xy 34.763514 -338.901596) (xy 34.717767 -338.827712)
			(xy 34.679033 -338.749923) (xy 34.647641 -338.668891) (xy 34.62386 -338.585309) (xy 34.607892 -338.499889)
			(xy 34.599874 -338.41336) (xy 31.39856 -338.41336) (xy 31.396498 -338.457532) (xy 31.384263 -338.544407)
			(xy 31.36399 -338.629764) (xy 31.335855 -338.712863) (xy 31.300101 -338.792979) (xy 31.257042 -338.869417)
			(xy 31.207049 -338.941511) (xy 31.150559 -339.008636) (xy 31.088062 -339.070208) (xy 31.020102 -339.125691)
			(xy 30.94727 -339.174602) (xy 30.870199 -339.216518) (xy 30.789558 -339.251072) (xy 30.70605 -339.277965)
			(xy 30.620399 -339.296963) (xy 30.533352 -339.307901) (xy 30.445664 -339.310683) (xy 30.358098 -339.305286)
			(xy 30.271416 -339.291756) (xy 30.18637 -339.270212) (xy 30.103701 -339.240839) (xy 30.063694 -339.222842)
			(xy 30.043103 -339.214515) (xy 29.999863 -339.204379) (xy 29.955519 -339.201912) (xy 29.911421 -339.207188)
			(xy 29.868911 -339.220046) (xy 29.829282 -339.240095) (xy 29.793739 -339.266725) (xy 29.763364 -339.299126)
			(xy 29.739082 -339.336313) (xy 29.72163 -339.377153) (xy 29.711541 -339.420404) (xy 29.709872 -339.442552)
			(xy 29.709872 -339.837268) (xy 29.711583 -339.859403) (xy 29.715215 -339.874924) (xy 39.178224 -339.874924)
			(xy 39.182109 -339.820558) (xy 39.193693 -339.767298) (xy 39.212738 -339.71623) (xy 39.238859 -339.668392)
			(xy 39.271522 -339.624758) (xy 39.310063 -339.586218) (xy 39.353697 -339.553556) (xy 39.401535 -339.527436)
			(xy 39.452604 -339.508391) (xy 39.505864 -339.496808) (xy 39.56023 -339.492924) (xy 39.614596 -339.496817)
			(xy 39.667854 -339.508408) (xy 39.71892 -339.527461) (xy 39.766754 -339.553588) (xy 39.788846 -339.569552)
			(xy 39.807858 -339.583148) (xy 39.849741 -339.60388) (xy 39.894709 -339.616606) (xy 39.941246 -339.620896)
			(xy 39.987783 -339.616606) (xy 40.032751 -339.60388) (xy 40.074634 -339.583148) (xy 40.093646 -339.569552)
			(xy 40.115771 -339.55365) (xy 40.163591 -339.527542) (xy 40.214639 -339.508505) (xy 40.267878 -339.496927)
			(xy 40.322222 -339.493043) (xy 40.376566 -339.496933) (xy 40.429803 -339.508517) (xy 40.48085 -339.52756)
			(xy 40.528667 -339.553674) (xy 40.57228 -339.586327) (xy 40.610803 -339.624854) (xy 40.643451 -339.668472)
			(xy 40.669559 -339.716292) (xy 40.688596 -339.767341) (xy 40.700174 -339.82058) (xy 40.704057 -339.874924)
			(xy 40.700167 -339.929268) (xy 40.688582 -339.982505) (xy 40.669539 -340.033551) (xy 40.643425 -340.081368)
			(xy 40.610772 -340.124982) (xy 40.572244 -340.163505) (xy 40.528626 -340.196152) (xy 40.480806 -340.22226)
			(xy 40.429757 -340.241296) (xy 40.376518 -340.252874) (xy 40.322174 -340.256757) (xy 40.26783 -340.252866)
			(xy 40.214593 -340.241282) (xy 40.163547 -340.222238) (xy 40.11573 -340.196124) (xy 40.093646 -340.180168)
			(xy 40.074634 -340.166572) (xy 40.032751 -340.14584) (xy 39.987783 -340.133114) (xy 39.941246 -340.128824)
			(xy 39.894709 -340.133114) (xy 39.849741 -340.14584) (xy 39.807858 -340.166572) (xy 39.788846 -340.180168)
			(xy 39.766794 -340.196186) (xy 39.718963 -340.222319) (xy 39.6679 -340.241379) (xy 39.614643 -340.252976)
			(xy 39.560278 -340.256876) (xy 39.505912 -340.252999) (xy 39.45265 -340.241423) (xy 39.401579 -340.222384)
			(xy 39.353737 -340.19627) (xy 39.310099 -340.163613) (xy 39.271554 -340.125078) (xy 39.238885 -340.081449)
			(xy 39.212758 -340.033614) (xy 39.193706 -339.982548) (xy 39.182116 -339.92929) (xy 39.178224 -339.874924)
			(xy 29.715215 -339.874924) (xy 29.721698 -339.902627) (xy 29.739164 -339.943439) (xy 29.763451 -339.980598)
			(xy 29.793821 -340.012975) (xy 29.829351 -340.039588) (xy 29.868962 -340.059628) (xy 29.911451 -340.072486)
			(xy 29.955527 -340.077772) (xy 29.999851 -340.075324) (xy 30.043078 -340.065218) (xy 30.063694 -340.056978)
			(xy 30.103694 -340.038964) (xy 30.186362 -340.009591) (xy 30.271408 -339.988045) (xy 30.35809 -339.974515)
			(xy 30.445656 -339.969117) (xy 30.533343 -339.971898) (xy 30.620391 -339.982835) (xy 30.706041 -340.001833)
			(xy 30.78955 -340.028725) (xy 30.870191 -340.063279) (xy 30.947263 -340.105193) (xy 31.020096 -340.154104)
			(xy 31.088056 -340.209587) (xy 31.150553 -340.271158) (xy 31.207044 -340.338282) (xy 31.257037 -340.410376)
			(xy 31.300098 -340.486814) (xy 31.335852 -340.56693) (xy 31.363988 -340.650027) (xy 31.384262 -340.735385)
			(xy 31.396497 -340.822259) (xy 31.400588 -340.909896) (xy 31.39856 -340.95336) (xy 34.599874 -340.95336)
			(xy 34.599874 -340.86646) (xy 34.607892 -340.779931) (xy 34.62386 -340.694511) (xy 34.647641 -340.610929)
			(xy 34.679033 -340.529897) (xy 34.717767 -340.452108) (xy 34.763514 -340.378224) (xy 34.815883 -340.308877)
			(xy 34.874427 -340.244657) (xy 34.938647 -340.186113) (xy 35.007994 -340.133744) (xy 35.081878 -340.087997)
			(xy 35.159667 -340.049263) (xy 35.240699 -340.017871) (xy 35.324281 -339.99409) (xy 35.409701 -339.978122)
			(xy 35.49623 -339.970104) (xy 35.58313 -339.970104) (xy 35.669659 -339.978122) (xy 35.755079 -339.99409)
			(xy 35.838661 -340.017871) (xy 35.919693 -340.049263) (xy 35.997482 -340.087997) (xy 36.071366 -340.133744)
			(xy 36.140713 -340.186113) (xy 36.204933 -340.244657) (xy 36.263477 -340.308877) (xy 36.271442 -340.319424)
			(xy 55.289244 -340.319424) (xy 55.293129 -340.265063) (xy 55.304711 -340.211808) (xy 55.323755 -340.160743)
			(xy 55.349872 -340.112909) (xy 55.382532 -340.069278) (xy 55.421068 -340.03074) (xy 55.464698 -339.998079)
			(xy 55.512531 -339.97196) (xy 55.563595 -339.952915) (xy 55.61685 -339.941331) (xy 55.671211 -339.937444)
			(xy 55.725572 -339.941334) (xy 55.778826 -339.952921) (xy 55.829889 -339.971969) (xy 55.877721 -339.998091)
			(xy 55.899812 -340.014052) (xy 55.918824 -340.027648) (xy 55.960707 -340.04838) (xy 56.005675 -340.061106)
			(xy 56.052212 -340.065396) (xy 56.098749 -340.061106) (xy 56.143717 -340.04838) (xy 56.1856 -340.027648)
			(xy 56.204612 -340.014052) (xy 56.226737 -339.998147) (xy 56.27456 -339.972033) (xy 56.325612 -339.952992)
			(xy 56.378854 -339.94141) (xy 56.433203 -339.937523) (xy 56.487551 -339.94141) (xy 56.540794 -339.952993)
			(xy 56.591845 -339.972036) (xy 56.639667 -339.99815) (xy 56.683286 -340.030805) (xy 56.721813 -340.069334)
			(xy 56.754464 -340.112955) (xy 56.780575 -340.160779) (xy 56.799614 -340.211832) (xy 56.811193 -340.265075)
			(xy 56.815077 -340.319424) (xy 57.175937 -340.319424) (xy 57.179822 -340.265061) (xy 57.191405 -340.211804)
			(xy 57.210449 -340.160738) (xy 57.236568 -340.112903) (xy 57.269228 -340.069271) (xy 57.307767 -340.030733)
			(xy 57.351397 -339.998071) (xy 57.399233 -339.971952) (xy 57.450298 -339.952906) (xy 57.503555 -339.941323)
			(xy 57.557918 -339.937437) (xy 57.61228 -339.941328) (xy 57.665536 -339.952916) (xy 57.7166 -339.971966)
			(xy 57.764432 -339.99809) (xy 57.786524 -340.014052) (xy 57.805536 -340.027648) (xy 57.847419 -340.04838)
			(xy 57.892387 -340.061106) (xy 57.938924 -340.065396) (xy 57.985461 -340.061106) (xy 58.030429 -340.04838)
			(xy 58.072312 -340.027648) (xy 58.091324 -340.014052) (xy 58.113449 -339.998148) (xy 58.161271 -339.972036)
			(xy 58.212321 -339.952996) (xy 58.265562 -339.941416) (xy 58.31991 -339.93753) (xy 58.374257 -339.941418)
			(xy 58.427497 -339.953002) (xy 58.478547 -339.972044) (xy 58.526367 -339.998158) (xy 58.569984 -340.030812)
			(xy 58.60851 -340.069341) (xy 58.64116 -340.112961) (xy 58.66727 -340.160784) (xy 58.686308 -340.211835)
			(xy 58.697886 -340.265077) (xy 58.70177 -340.319424) (xy 59.417072 -340.319424) (xy 59.420956 -340.265069)
			(xy 59.432536 -340.21182) (xy 59.451577 -340.160761) (xy 59.47769 -340.112932) (xy 59.510345 -340.069305)
			(xy 59.548876 -340.030771) (xy 59.592499 -339.998112) (xy 59.640325 -339.971993) (xy 59.691382 -339.952947)
			(xy 59.74463 -339.941362) (xy 59.798985 -339.937472) (xy 59.85334 -339.941357) (xy 59.906588 -339.952939)
			(xy 59.957647 -339.971981) (xy 60.005476 -339.998095) (xy 60.027566 -340.014052) (xy 60.046578 -340.027648)
			(xy 60.088461 -340.04838) (xy 60.133429 -340.061106) (xy 60.179966 -340.065396) (xy 60.226503 -340.061106)
			(xy 60.271471 -340.04838) (xy 60.313354 -340.027648) (xy 60.332366 -340.014052) (xy 60.354492 -339.998143)
			(xy 60.402318 -339.972022) (xy 60.453374 -339.952974) (xy 60.506622 -339.941386) (xy 60.560977 -339.937495)
			(xy 60.615332 -339.94138) (xy 60.668581 -339.952961) (xy 60.71964 -339.972003) (xy 60.767468 -339.998118)
			(xy 60.811093 -340.030774) (xy 60.849626 -340.069307) (xy 60.882282 -340.112932) (xy 60.908398 -340.160761)
			(xy 60.927439 -340.21182) (xy 60.93902 -340.265069) (xy 60.942905 -340.319424) (xy 61.320921 -340.319424)
			(xy 61.324807 -340.265057) (xy 61.33639 -340.211797) (xy 61.355437 -340.160728) (xy 61.381557 -340.11289)
			(xy 61.414221 -340.069256) (xy 61.452762 -340.030715) (xy 61.496397 -339.998053) (xy 61.544236 -339.971933)
			(xy 61.595306 -339.952888) (xy 61.648566 -339.941306) (xy 61.702932 -339.937421) (xy 61.757298 -339.941315)
			(xy 61.810557 -339.952906) (xy 61.861623 -339.97196) (xy 61.909458 -339.998088) (xy 61.93155 -340.014052)
			(xy 61.950562 -340.027648) (xy 61.992445 -340.04838) (xy 62.037413 -340.061106) (xy 62.08395 -340.065396)
			(xy 62.130487 -340.061106) (xy 62.175455 -340.04838) (xy 62.217338 -340.027648) (xy 62.23635 -340.014052)
			(xy 62.258477 -339.998142) (xy 62.306303 -339.972018) (xy 62.357361 -339.952968) (xy 62.410611 -339.941378)
			(xy 62.464968 -339.937486) (xy 62.519325 -339.941369) (xy 62.572576 -339.952949) (xy 62.623637 -339.971991)
			(xy 62.671469 -339.998107) (xy 62.715096 -340.030764) (xy 62.753631 -340.069298) (xy 62.786289 -340.112924)
			(xy 62.812405 -340.160755) (xy 62.831448 -340.211815) (xy 62.84303 -340.265067) (xy 62.846914 -340.319424)
			(xy 62.843023 -340.373781) (xy 62.831435 -340.427031) (xy 62.812385 -340.478089) (xy 62.786263 -340.525916)
			(xy 62.753599 -340.569538) (xy 62.715059 -340.608068) (xy 62.671428 -340.640719) (xy 62.623594 -340.666829)
			(xy 62.57253 -340.685864) (xy 62.519278 -340.697438) (xy 62.46492 -340.701314) (xy 62.410563 -340.697415)
			(xy 62.357315 -340.685819) (xy 62.30626 -340.666762) (xy 62.258436 -340.640632) (xy 62.23635 -340.624668)
			(xy 62.217338 -340.611072) (xy 62.175455 -340.59034) (xy 62.130487 -340.577614) (xy 62.08395 -340.573324)
			(xy 62.037413 -340.577614) (xy 61.992445 -340.59034) (xy 61.950562 -340.611072) (xy 61.93155 -340.624668)
			(xy 61.909498 -340.640686) (xy 61.861667 -340.66682) (xy 61.810603 -340.68588) (xy 61.757346 -340.697478)
			(xy 61.702981 -340.701379) (xy 61.648613 -340.697501) (xy 61.595352 -340.685925) (xy 61.54428 -340.666887)
			(xy 61.496437 -340.640773) (xy 61.452799 -340.608116) (xy 61.414252 -340.56958) (xy 61.381583 -340.525951)
			(xy 61.355457 -340.478115) (xy 61.336404 -340.427049) (xy 61.324814 -340.37379) (xy 61.320921 -340.319424)
			(xy 60.942905 -340.319424) (xy 60.939014 -340.373779) (xy 60.927426 -340.427026) (xy 60.908378 -340.478083)
			(xy 60.882257 -340.525908) (xy 60.849595 -340.569529) (xy 60.811057 -340.608057) (xy 60.767428 -340.640708)
			(xy 60.719596 -340.666817) (xy 60.668535 -340.685853) (xy 60.615284 -340.697427) (xy 60.560929 -340.701305)
			(xy 60.506574 -340.697407) (xy 60.453328 -340.685813) (xy 60.402274 -340.666758) (xy 60.354452 -340.640631)
			(xy 60.332366 -340.624668) (xy 60.313354 -340.611072) (xy 60.271471 -340.59034) (xy 60.226503 -340.577614)
			(xy 60.179966 -340.573324) (xy 60.133429 -340.577614) (xy 60.088461 -340.59034) (xy 60.046578 -340.611072)
			(xy 60.027566 -340.624668) (xy 60.005516 -340.640679) (xy 59.957691 -340.6668) (xy 59.906635 -340.685848)
			(xy 59.853387 -340.697436) (xy 59.799033 -340.701328) (xy 59.744678 -340.697445) (xy 59.691428 -340.685866)
			(xy 59.640369 -340.666827) (xy 59.592539 -340.640714) (xy 59.548912 -340.608061) (xy 59.510376 -340.569531)
			(xy 59.477716 -340.525909) (xy 59.451597 -340.478083) (xy 59.43255 -340.427026) (xy 59.420963 -340.373779)
			(xy 59.417072 -340.319424) (xy 58.70177 -340.319424) (xy 58.69788 -340.373771) (xy 58.686294 -340.427011)
			(xy 58.66725 -340.47806) (xy 58.641134 -340.525879) (xy 58.608478 -340.569495) (xy 58.569948 -340.608019)
			(xy 58.526327 -340.640668) (xy 58.478503 -340.666776) (xy 58.427451 -340.685812) (xy 58.374209 -340.697389)
			(xy 58.319862 -340.70127) (xy 58.265515 -340.697378) (xy 58.212275 -340.68579) (xy 58.161227 -340.666744)
			(xy 58.113409 -340.640626) (xy 58.091324 -340.624668) (xy 58.072312 -340.611072) (xy 58.030429 -340.59034)
			(xy 57.985461 -340.577614) (xy 57.938924 -340.573324) (xy 57.892387 -340.577614) (xy 57.847419 -340.59034)
			(xy 57.805536 -340.611072) (xy 57.786524 -340.624668) (xy 57.764473 -340.640684) (xy 57.716643 -340.666814)
			(xy 57.665582 -340.68587) (xy 57.612328 -340.697465) (xy 57.557966 -340.701363) (xy 57.503602 -340.697484)
			(xy 57.450344 -340.685907) (xy 57.399276 -340.666868) (xy 57.351438 -340.640755) (xy 57.307803 -340.608099)
			(xy 57.26926 -340.569565) (xy 57.236594 -340.525938) (xy 57.210469 -340.478105) (xy 57.191418 -340.427042)
			(xy 57.179829 -340.373787) (xy 57.175937 -340.319424) (xy 56.815077 -340.319424) (xy 56.811187 -340.373772)
			(xy 56.799601 -340.427014) (xy 56.780555 -340.478065) (xy 56.754438 -340.525885) (xy 56.721782 -340.569502)
			(xy 56.68325 -340.608027) (xy 56.639627 -340.640676) (xy 56.591802 -340.666784) (xy 56.540748 -340.68582)
			(xy 56.487504 -340.697397) (xy 56.433155 -340.701277) (xy 56.378807 -340.697384) (xy 56.325566 -340.685795)
			(xy 56.274516 -340.666747) (xy 56.226697 -340.640627) (xy 56.204612 -340.624668) (xy 56.1856 -340.611072)
			(xy 56.143717 -340.59034) (xy 56.098749 -340.577614) (xy 56.052212 -340.573324) (xy 56.005675 -340.577614)
			(xy 55.960707 -340.59034) (xy 55.918824 -340.611072) (xy 55.899812 -340.624668) (xy 55.877761 -340.640683)
			(xy 55.829932 -340.666811) (xy 55.778872 -340.685865) (xy 55.725619 -340.697459) (xy 55.671259 -340.701356)
			(xy 55.616897 -340.697476) (xy 55.563641 -340.685899) (xy 55.512575 -340.66686) (xy 55.464738 -340.640747)
			(xy 55.421105 -340.608091) (xy 55.382563 -340.569558) (xy 55.349898 -340.525932) (xy 55.323775 -340.478101)
			(xy 55.304725 -340.427038) (xy 55.293136 -340.373785) (xy 55.289244 -340.319424) (xy 36.271442 -340.319424)
			(xy 36.315846 -340.378224) (xy 36.361593 -340.452108) (xy 36.400327 -340.529897) (xy 36.431719 -340.610929)
			(xy 36.4555 -340.694511) (xy 36.471468 -340.779931) (xy 36.479486 -340.86646) (xy 36.479988 -340.90991)
			(xy 36.479486 -340.95336) (xy 36.471468 -341.039889) (xy 36.4555 -341.125309) (xy 36.431719 -341.208891)
			(xy 36.415787 -341.250016) (xy 72.998846 -341.250016) (xy 73.00285 -341.049918) (xy 73.014857 -340.85014)
			(xy 73.034848 -340.651003) (xy 73.06279 -340.452825) (xy 73.098638 -340.255923) (xy 73.142336 -340.060614)
			(xy 73.193813 -339.867209) (xy 73.252987 -339.676019) (xy 73.319763 -339.487349) (xy 73.394035 -339.301502)
			(xy 73.475682 -339.118775) (xy 73.564575 -338.939462) (xy 73.660571 -338.763848) (xy 73.763516 -338.592216)
			(xy 73.873246 -338.42484) (xy 73.989584 -338.261989) (xy 74.112345 -338.103922) (xy 74.241332 -337.950894)
			(xy 74.376339 -337.803149) (xy 74.517148 -337.660923) (xy 74.663535 -337.524446) (xy 74.815265 -337.393934)
			(xy 74.972096 -337.269598) (xy 75.133775 -337.151636) (xy 75.300045 -337.040237) (xy 75.470638 -336.93558)
			(xy 75.645282 -336.837832) (xy 75.823698 -336.747149) (xy 76.005598 -336.663678) (xy 76.190693 -336.587551)
			(xy 76.378685 -336.518891) (xy 76.569274 -336.457807) (xy 76.762154 -336.404397) (xy 76.957016 -336.358748)
			(xy 77.153549 -336.320931) (xy 77.351438 -336.291007) (xy 77.550365 -336.269025) (xy 77.750013 -336.25502)
			(xy 77.950061 -336.249014) (xy 78.150189 -336.251016) (xy 78.350077 -336.261024) (xy 78.549404 -336.279021)
			(xy 78.747852 -336.304979) (xy 78.945102 -336.338856) (xy 79.140839 -336.380598) (xy 79.334749 -336.430137)
			(xy 79.526522 -336.487395) (xy 79.715851 -336.55228) (xy 79.902431 -336.624688) (xy 80.085966 -336.704504)
			(xy 80.26616 -336.791598) (xy 80.442725 -336.885832) (xy 80.615378 -336.987055) (xy 80.783843 -337.095105)
			(xy 80.947851 -337.209808) (xy 81.107138 -337.330982) (xy 81.261449 -337.458431) (xy 81.410537 -337.591952)
			(xy 81.554164 -337.731332) (xy 81.6921 -337.876346) (xy 81.824123 -338.026763) (xy 81.950022 -338.182341)
			(xy 82.069596 -338.342833) (xy 82.182652 -338.507979) (xy 82.289011 -338.677517) (xy 82.388502 -338.851175)
			(xy 82.480965 -339.028674) (xy 82.566252 -339.20973) (xy 82.644227 -339.394054) (xy 82.714764 -339.58135)
			(xy 82.777752 -339.771318) (xy 82.833089 -339.963654) (xy 82.880686 -340.15805) (xy 82.920467 -340.354195)
			(xy 82.952369 -340.551774) (xy 82.97634 -340.750471) (xy 82.992342 -340.949969) (xy 83.000349 -341.149947)
			(xy 83.00085 -341.250016) (xy 83.000349 -341.350085) (xy 82.992342 -341.550063) (xy 82.97634 -341.749561)
			(xy 82.952369 -341.948258) (xy 82.920467 -342.145837) (xy 82.880686 -342.341982) (xy 82.833089 -342.536378)
			(xy 82.777752 -342.728714) (xy 82.714764 -342.918682) (xy 82.644227 -343.105978) (xy 82.566252 -343.290302)
			(xy 82.480965 -343.471358) (xy 82.388502 -343.648857) (xy 82.289011 -343.822515) (xy 82.182652 -343.992053)
			(xy 82.069596 -344.157199) (xy 81.950022 -344.317691) (xy 81.824123 -344.473269) (xy 81.6921 -344.623686)
			(xy 81.554164 -344.7687) (xy 81.410537 -344.90808) (xy 81.261449 -345.041601) (xy 81.107138 -345.16905)
			(xy 80.947851 -345.290224) (xy 80.783843 -345.404927) (xy 80.615378 -345.512977) (xy 80.442725 -345.6142)
			(xy 80.26616 -345.708434) (xy 80.085966 -345.795528) (xy 79.902431 -345.875344) (xy 79.715851 -345.947752)
			(xy 79.526522 -346.012637) (xy 79.334749 -346.069895) (xy 79.140839 -346.119434) (xy 78.945102 -346.161176)
			(xy 78.747852 -346.195053) (xy 78.549404 -346.221011) (xy 78.350077 -346.239008) (xy 78.150189 -346.249016)
			(xy 77.950061 -346.251018) (xy 77.750013 -346.245012) (xy 77.550365 -346.231007) (xy 77.351438 -346.209025)
			(xy 77.153549 -346.179101) (xy 76.957016 -346.141284) (xy 76.762154 -346.095635) (xy 76.569274 -346.042225)
			(xy 76.378685 -345.981141) (xy 76.190693 -345.912481) (xy 76.005598 -345.836354) (xy 75.823698 -345.752883)
			(xy 75.645282 -345.6622) (xy 75.470638 -345.564452) (xy 75.300045 -345.459795) (xy 75.133775 -345.348396)
			(xy 74.972096 -345.230434) (xy 74.815265 -345.106098) (xy 74.663535 -344.975586) (xy 74.517148 -344.839109)
			(xy 74.376339 -344.696883) (xy 74.241332 -344.549138) (xy 74.112345 -344.39611) (xy 73.989584 -344.238043)
			(xy 73.873246 -344.075192) (xy 73.763516 -343.907816) (xy 73.660571 -343.736184) (xy 73.564575 -343.56057)
			(xy 73.475682 -343.381257) (xy 73.394035 -343.19853) (xy 73.319763 -343.012683) (xy 73.252987 -342.824013)
			(xy 73.193813 -342.632823) (xy 73.142336 -342.439418) (xy 73.098638 -342.244109) (xy 73.06279 -342.047207)
			(xy 73.034848 -341.849029) (xy 73.014857 -341.649892) (xy 73.00285 -341.450114) (xy 72.998846 -341.250016)
			(xy 36.415787 -341.250016) (xy 36.400327 -341.289923) (xy 36.361593 -341.367712) (xy 36.315846 -341.441596)
			(xy 36.263477 -341.510943) (xy 36.204933 -341.575163) (xy 36.140713 -341.633707) (xy 36.071366 -341.686076)
			(xy 35.997482 -341.731823) (xy 35.919693 -341.770557) (xy 35.838661 -341.801949) (xy 35.755079 -341.82573)
			(xy 35.69042 -341.837817) (xy 39.178233 -341.837817) (xy 39.18212 -341.783452) (xy 39.193704 -341.730194)
			(xy 39.21275 -341.679127) (xy 39.238871 -341.631291) (xy 39.271534 -341.587659) (xy 39.310075 -341.549121)
			(xy 39.353708 -341.51646) (xy 39.401546 -341.490342) (xy 39.452614 -341.471298) (xy 39.505873 -341.459717)
			(xy 39.560237 -341.455833) (xy 39.614601 -341.459727) (xy 39.667858 -341.471319) (xy 39.718922 -341.490373)
			(xy 39.766755 -341.5165) (xy 39.788846 -341.532464) (xy 39.807858 -341.54606) (xy 39.849741 -341.566792)
			(xy 39.894709 -341.579518) (xy 39.941246 -341.583808) (xy 39.987783 -341.579518) (xy 40.032751 -341.566792)
			(xy 40.074634 -341.54606) (xy 40.093646 -341.532464) (xy 40.115759 -341.516546) (xy 40.16358 -341.490436)
			(xy 40.21463 -341.471398) (xy 40.267869 -341.459818) (xy 40.322215 -341.455933) (xy 40.37656 -341.459822)
			(xy 40.429799 -341.471406) (xy 40.480847 -341.490448) (xy 40.528666 -341.516562) (xy 40.572281 -341.549215)
			(xy 40.610806 -341.587743) (xy 40.643455 -341.631361) (xy 40.669565 -341.679182) (xy 40.688603 -341.730232)
			(xy 40.700182 -341.783471) (xy 40.704067 -341.837817) (xy 40.700177 -341.892162) (xy 40.688593 -341.945401)
			(xy 40.669551 -341.996449) (xy 40.643437 -342.044267) (xy 40.610784 -342.087883) (xy 40.572256 -342.126407)
			(xy 40.528637 -342.159056) (xy 40.480817 -342.185166) (xy 40.429767 -342.204203) (xy 40.376527 -342.215782)
			(xy 40.322181 -342.219667) (xy 40.267836 -342.215777) (xy 40.214598 -342.204193) (xy 40.163549 -342.18515)
			(xy 40.115731 -342.159036) (xy 40.093646 -342.14308) (xy 40.074634 -342.129484) (xy 40.032751 -342.108752)
			(xy 39.987783 -342.096026) (xy 39.941246 -342.091736) (xy 39.894709 -342.096026) (xy 39.849741 -342.108752)
			(xy 39.807858 -342.129484) (xy 39.788846 -342.14308) (xy 39.766783 -342.159082) (xy 39.718953 -342.185213)
			(xy 39.66789 -342.204271) (xy 39.614635 -342.215868) (xy 39.560271 -342.219766) (xy 39.505906 -342.215888)
			(xy 39.452646 -342.204311) (xy 39.401577 -342.185272) (xy 39.353736 -342.159158) (xy 39.3101 -342.126501)
			(xy 39.271556 -342.087966) (xy 39.238889 -342.044337) (xy 39.212764 -341.996503) (xy 39.193713 -341.945438)
			(xy 39.182124 -341.892181) (xy 39.178233 -341.837817) (xy 35.69042 -341.837817) (xy 35.669659 -341.841698)
			(xy 35.58313 -341.849716) (xy 35.49623 -341.849716) (xy 35.409701 -341.841698) (xy 35.324281 -341.82573)
			(xy 35.240699 -341.801949) (xy 35.159667 -341.770557) (xy 35.081878 -341.731823) (xy 35.007994 -341.686076)
			(xy 34.938647 -341.633707) (xy 34.874427 -341.575163) (xy 34.815883 -341.510943) (xy 34.763514 -341.441596)
			(xy 34.717767 -341.367712) (xy 34.679033 -341.289923) (xy 34.647641 -341.208891) (xy 34.62386 -341.125309)
			(xy 34.607892 -341.039889) (xy 34.599874 -340.95336) (xy 31.39856 -340.95336) (xy 31.396498 -340.997532)
			(xy 31.384263 -341.084407) (xy 31.36399 -341.169764) (xy 31.335855 -341.252863) (xy 31.300101 -341.332979)
			(xy 31.257042 -341.409417) (xy 31.207049 -341.481511) (xy 31.150559 -341.548636) (xy 31.088062 -341.610208)
			(xy 31.020102 -341.665691) (xy 30.94727 -341.714602) (xy 30.870199 -341.756518) (xy 30.789558 -341.791072)
			(xy 30.70605 -341.817965) (xy 30.620399 -341.836963) (xy 30.533352 -341.847901) (xy 30.445664 -341.850683)
			(xy 30.358098 -341.845286) (xy 30.271416 -341.831756) (xy 30.18637 -341.810212) (xy 30.103701 -341.780839)
			(xy 30.063694 -341.762842) (xy 30.043103 -341.754515) (xy 29.999863 -341.744379) (xy 29.955519 -341.741912)
			(xy 29.911421 -341.747188) (xy 29.868911 -341.760046) (xy 29.829282 -341.780095) (xy 29.793739 -341.806725)
			(xy 29.763364 -341.839126) (xy 29.739082 -341.876313) (xy 29.72163 -341.917153) (xy 29.711541 -341.960404)
			(xy 29.709872 -341.982552) (xy 29.709872 -342.377268) (xy 29.711583 -342.399403) (xy 29.721698 -342.442627)
			(xy 29.739164 -342.483439) (xy 29.763451 -342.520598) (xy 29.793821 -342.552975) (xy 29.829351 -342.579588)
			(xy 29.868962 -342.599628) (xy 29.911451 -342.612486) (xy 29.955527 -342.617772) (xy 29.999851 -342.615324)
			(xy 30.043078 -342.605218) (xy 30.063694 -342.596978) (xy 30.103694 -342.578964) (xy 30.186362 -342.549591)
			(xy 30.271408 -342.528045) (xy 30.35809 -342.514515) (xy 30.445656 -342.509117) (xy 30.533343 -342.511898)
			(xy 30.620391 -342.522835) (xy 30.706041 -342.541833) (xy 30.78955 -342.568725) (xy 30.870191 -342.603279)
			(xy 30.947263 -342.645193) (xy 31.020096 -342.694104) (xy 31.088056 -342.749587) (xy 31.150553 -342.811158)
			(xy 31.207044 -342.878282) (xy 31.257037 -342.950376) (xy 31.300098 -343.026814) (xy 31.335852 -343.10693)
			(xy 31.363988 -343.190027) (xy 31.384262 -343.275385) (xy 31.396497 -343.362259) (xy 31.400588 -343.449896)
			(xy 31.39856 -343.49336) (xy 34.599874 -343.49336) (xy 34.599874 -343.40646) (xy 34.607892 -343.319931)
			(xy 34.62386 -343.234511) (xy 34.647641 -343.150929) (xy 34.679033 -343.069897) (xy 34.717767 -342.992108)
			(xy 34.763514 -342.918224) (xy 34.815883 -342.848877) (xy 34.874427 -342.784657) (xy 34.938647 -342.726113)
			(xy 35.007994 -342.673744) (xy 35.081878 -342.627997) (xy 35.159667 -342.589263) (xy 35.240699 -342.557871)
			(xy 35.324281 -342.53409) (xy 35.409701 -342.518122) (xy 35.49623 -342.510104) (xy 35.58313 -342.510104)
			(xy 35.669659 -342.518122) (xy 35.755079 -342.53409) (xy 35.838661 -342.557871) (xy 35.919693 -342.589263)
			(xy 35.997482 -342.627997) (xy 36.071366 -342.673744) (xy 36.140713 -342.726113) (xy 36.204933 -342.784657)
			(xy 36.263477 -342.848877) (xy 36.315846 -342.918224) (xy 36.361593 -342.992108) (xy 36.400327 -343.069897)
			(xy 36.431719 -343.150929) (xy 36.4555 -343.234511) (xy 36.471468 -343.319931) (xy 36.479486 -343.40646)
			(xy 36.479988 -343.44991) (xy 36.479486 -343.49336) (xy 36.471468 -343.579889) (xy 36.4555 -343.665309)
			(xy 36.431719 -343.748891) (xy 36.400327 -343.829923) (xy 36.361593 -343.907712) (xy 36.316021 -343.981313)
			(xy 39.178238 -343.981313) (xy 39.182125 -343.926949) (xy 39.193709 -343.873692) (xy 39.212756 -343.822626)
			(xy 39.238877 -343.77479) (xy 39.27154 -343.73116) (xy 39.310081 -343.692622) (xy 39.353714 -343.659962)
			(xy 39.401551 -343.633845) (xy 39.452619 -343.614802) (xy 39.505877 -343.603221) (xy 39.560241 -343.599338)
			(xy 39.614604 -343.603233) (xy 39.66786 -343.614825) (xy 39.718923 -343.633879) (xy 39.766755 -343.660006)
			(xy 39.788846 -343.67597) (xy 39.807858 -343.689566) (xy 39.849741 -343.710298) (xy 39.894709 -343.723024)
			(xy 39.941246 -343.727314) (xy 39.987783 -343.723024) (xy 40.032751 -343.710298) (xy 40.074634 -343.689566)
			(xy 40.093646 -343.67597) (xy 40.115754 -343.660044) (xy 40.163575 -343.633933) (xy 40.214625 -343.614894)
			(xy 40.267865 -343.603314) (xy 40.322211 -343.599429) (xy 40.376557 -343.603317) (xy 40.429797 -343.6149)
			(xy 40.480846 -343.633943) (xy 40.528665 -343.660056) (xy 40.572282 -343.692709) (xy 40.610807 -343.731237)
			(xy 40.643457 -343.774855) (xy 40.669568 -343.822676) (xy 40.688606 -343.873727) (xy 40.700186 -343.926967)
			(xy 40.704071 -343.981313) (xy 40.700183 -344.035659) (xy 40.688599 -344.088899) (xy 40.669557 -344.139948)
			(xy 40.643443 -344.187767) (xy 40.61079 -344.231383) (xy 40.572262 -344.269908) (xy 40.528643 -344.302558)
			(xy 40.480822 -344.328668) (xy 40.429771 -344.347707) (xy 40.376531 -344.359287) (xy 40.322185 -344.363171)
			(xy 40.267839 -344.359282) (xy 40.2146 -344.347699) (xy 40.163551 -344.328656) (xy 40.115732 -344.302542)
			(xy 40.093646 -344.286586) (xy 40.074634 -344.27299) (xy 40.032751 -344.252258) (xy 39.987783 -344.239532)
			(xy 39.941246 -344.235242) (xy 39.894709 -344.239532) (xy 39.849741 -344.252258) (xy 39.807858 -344.27299)
			(xy 39.788846 -344.286586) (xy 39.766777 -344.30258) (xy 39.718947 -344.32871) (xy 39.667885 -344.347768)
			(xy 39.61463 -344.359364) (xy 39.560267 -344.363262) (xy 39.505903 -344.359383) (xy 39.452644 -344.347806)
			(xy 39.401575 -344.328766) (xy 39.353736 -344.302652) (xy 39.310101 -344.269995) (xy 39.271557 -344.23146)
			(xy 39.238891 -344.187832) (xy 39.212767 -344.139998) (xy 39.193717 -344.088933) (xy 39.182129 -344.035677)
			(xy 39.178238 -343.981313) (xy 36.316021 -343.981313) (xy 36.315846 -343.981596) (xy 36.263477 -344.050943)
			(xy 36.204933 -344.115163) (xy 36.140713 -344.173707) (xy 36.071366 -344.226076) (xy 35.997482 -344.271823)
			(xy 35.919693 -344.310557) (xy 35.838661 -344.341949) (xy 35.755079 -344.36573) (xy 35.669659 -344.381698)
			(xy 35.58313 -344.389716) (xy 35.49623 -344.389716) (xy 35.409701 -344.381698) (xy 35.324281 -344.36573)
			(xy 35.240699 -344.341949) (xy 35.159667 -344.310557) (xy 35.081878 -344.271823) (xy 35.007994 -344.226076)
			(xy 34.938647 -344.173707) (xy 34.874427 -344.115163) (xy 34.815883 -344.050943) (xy 34.763514 -343.981596)
			(xy 34.717767 -343.907712) (xy 34.679033 -343.829923) (xy 34.647641 -343.748891) (xy 34.62386 -343.665309)
			(xy 34.607892 -343.579889) (xy 34.599874 -343.49336) (xy 31.39856 -343.49336) (xy 31.396498 -343.537532)
			(xy 31.384263 -343.624407) (xy 31.36399 -343.709764) (xy 31.335855 -343.792863) (xy 31.300101 -343.872979)
			(xy 31.257042 -343.949417) (xy 31.207049 -344.021511) (xy 31.150559 -344.088636) (xy 31.088062 -344.150208)
			(xy 31.020102 -344.205691) (xy 30.94727 -344.254602) (xy 30.870199 -344.296518) (xy 30.789558 -344.331072)
			(xy 30.70605 -344.357965) (xy 30.620399 -344.376963) (xy 30.533352 -344.387901) (xy 30.445664 -344.390683)
			(xy 30.358098 -344.385286) (xy 30.271416 -344.371756) (xy 30.18637 -344.350212) (xy 30.103701 -344.320839)
			(xy 30.063694 -344.302842) (xy 30.043103 -344.294515) (xy 29.999863 -344.284379) (xy 29.955519 -344.281912)
			(xy 29.911421 -344.287188) (xy 29.868911 -344.300046) (xy 29.829282 -344.320095) (xy 29.793739 -344.346725)
			(xy 29.763364 -344.379126) (xy 29.739082 -344.416313) (xy 29.72163 -344.457153) (xy 29.711541 -344.500404)
			(xy 29.709872 -344.522552) (xy 29.709872 -344.917268) (xy 29.711583 -344.939403) (xy 29.721698 -344.982627)
			(xy 29.739164 -345.023439) (xy 29.763451 -345.060598) (xy 29.793821 -345.092975) (xy 29.829351 -345.119588)
			(xy 29.868962 -345.139628) (xy 29.911451 -345.152486) (xy 29.955527 -345.157772) (xy 29.999851 -345.155324)
			(xy 30.043078 -345.145218) (xy 30.063694 -345.136978) (xy 30.103694 -345.118964) (xy 30.186362 -345.089591)
			(xy 30.271408 -345.068045) (xy 30.35809 -345.054515) (xy 30.445656 -345.049117) (xy 30.533343 -345.051898)
			(xy 30.620391 -345.062835) (xy 30.706041 -345.081833) (xy 30.78955 -345.108725) (xy 30.870191 -345.143279)
			(xy 30.947263 -345.185193) (xy 31.020096 -345.234104) (xy 31.088056 -345.289587) (xy 31.150553 -345.351158)
			(xy 31.207044 -345.418282) (xy 31.257037 -345.490376) (xy 31.300098 -345.566814) (xy 31.335852 -345.64693)
			(xy 31.363988 -345.730027) (xy 31.384262 -345.815385) (xy 31.396497 -345.902259) (xy 31.400588 -345.989896)
			(xy 31.39856 -346.03336) (xy 34.599874 -346.03336) (xy 34.599874 -345.94646) (xy 34.607892 -345.859931)
			(xy 34.62386 -345.774511) (xy 34.647641 -345.690929) (xy 34.679033 -345.609897) (xy 34.717767 -345.532108)
			(xy 34.763514 -345.458224) (xy 34.815883 -345.388877) (xy 34.874427 -345.324657) (xy 34.938647 -345.266113)
			(xy 35.007994 -345.213744) (xy 35.081878 -345.167997) (xy 35.159667 -345.129263) (xy 35.240699 -345.097871)
			(xy 35.324281 -345.07409) (xy 35.409701 -345.058122) (xy 35.49623 -345.050104) (xy 35.58313 -345.050104)
			(xy 35.669659 -345.058122) (xy 35.755079 -345.07409) (xy 35.838661 -345.097871) (xy 35.919693 -345.129263)
			(xy 35.997482 -345.167997) (xy 36.071366 -345.213744) (xy 36.140713 -345.266113) (xy 36.204933 -345.324657)
			(xy 36.263477 -345.388877) (xy 36.315846 -345.458224) (xy 36.361593 -345.532108) (xy 36.400327 -345.609897)
			(xy 36.431719 -345.690929) (xy 36.4555 -345.774511) (xy 36.471468 -345.859931) (xy 36.479486 -345.94646)
			(xy 36.479988 -345.98991) (xy 36.479486 -346.03336) (xy 36.471468 -346.119889) (xy 36.4555 -346.205309)
			(xy 36.431719 -346.288891) (xy 36.400327 -346.369923) (xy 36.361593 -346.447712) (xy 36.315846 -346.521596)
			(xy 36.263477 -346.590943) (xy 36.204933 -346.655163) (xy 36.140713 -346.713707) (xy 36.071366 -346.766076)
			(xy 35.997482 -346.811823) (xy 35.919693 -346.850557) (xy 35.838661 -346.881949) (xy 35.755079 -346.90573)
			(xy 35.669659 -346.921698) (xy 35.58313 -346.929716) (xy 35.49623 -346.929716) (xy 35.409701 -346.921698)
			(xy 35.324281 -346.90573) (xy 35.240699 -346.881949) (xy 35.159667 -346.850557) (xy 35.081878 -346.811823)
			(xy 35.007994 -346.766076) (xy 34.938647 -346.713707) (xy 34.874427 -346.655163) (xy 34.815883 -346.590943)
			(xy 34.763514 -346.521596) (xy 34.717767 -346.447712) (xy 34.679033 -346.369923) (xy 34.647641 -346.288891)
			(xy 34.62386 -346.205309) (xy 34.607892 -346.119889) (xy 34.599874 -346.03336) (xy 31.39856 -346.03336)
			(xy 31.396498 -346.077532) (xy 31.384263 -346.164407) (xy 31.36399 -346.249764) (xy 31.335855 -346.332863)
			(xy 31.300101 -346.412979) (xy 31.257042 -346.489417) (xy 31.207049 -346.561511) (xy 31.150559 -346.628636)
			(xy 31.088062 -346.690208) (xy 31.020102 -346.745691) (xy 30.94727 -346.794602) (xy 30.870199 -346.836518)
			(xy 30.789558 -346.871072) (xy 30.70605 -346.897965) (xy 30.620399 -346.916963) (xy 30.533352 -346.927901)
			(xy 30.445664 -346.930683) (xy 30.358098 -346.925286) (xy 30.271416 -346.911756) (xy 30.18637 -346.890212)
			(xy 30.103701 -346.860839) (xy 30.063694 -346.842842) (xy 30.043103 -346.834515) (xy 29.999863 -346.824379)
			(xy 29.955519 -346.821912) (xy 29.911421 -346.827188) (xy 29.868911 -346.840046) (xy 29.829282 -346.860095)
			(xy 29.793739 -346.886725) (xy 29.763364 -346.919126) (xy 29.739082 -346.956313) (xy 29.72163 -346.997153)
			(xy 29.711541 -347.040404) (xy 29.709872 -347.062552) (xy 29.709872 -347.472508) (xy 29.711434 -347.487519)
			(xy 29.720696 -347.516235) (xy 29.73643 -347.54198) (xy 29.757759 -347.563322) (xy 29.783495 -347.579071)
			(xy 29.812205 -347.588351) (xy 29.82722 -347.589856) (xy 31.399988 -347.589856) (xy 31.399988 -348.57336)
			(xy 34.599874 -348.57336) (xy 34.599874 -348.48646) (xy 34.607892 -348.399931) (xy 34.62386 -348.314511)
			(xy 34.647641 -348.230929) (xy 34.679033 -348.149897) (xy 34.717767 -348.072108) (xy 34.763514 -347.998224)
			(xy 34.815883 -347.928877) (xy 34.874427 -347.864657) (xy 34.938647 -347.806113) (xy 35.007994 -347.753744)
			(xy 35.081878 -347.707997) (xy 35.159667 -347.669263) (xy 35.240699 -347.637871) (xy 35.324281 -347.61409)
			(xy 35.409701 -347.598122) (xy 35.49623 -347.590104) (xy 35.58313 -347.590104) (xy 35.669659 -347.598122)
			(xy 35.755079 -347.61409) (xy 35.838661 -347.637871) (xy 35.919693 -347.669263) (xy 35.997482 -347.707997)
			(xy 36.071366 -347.753744) (xy 36.140713 -347.806113) (xy 36.204933 -347.864657) (xy 36.263477 -347.928877)
			(xy 36.315846 -347.998224) (xy 36.361593 -348.072108) (xy 36.400327 -348.149897) (xy 36.431719 -348.230929)
			(xy 36.4555 -348.314511) (xy 36.471468 -348.399931) (xy 36.479486 -348.48646) (xy 36.479988 -348.52991)
			(xy 36.479486 -348.57336) (xy 36.471468 -348.659889) (xy 36.4555 -348.745309) (xy 36.431719 -348.828891)
			(xy 36.400327 -348.909923) (xy 36.361593 -348.987712) (xy 36.315846 -349.061596) (xy 36.263477 -349.130943)
			(xy 36.204933 -349.195163) (xy 36.140713 -349.253707) (xy 36.071366 -349.306076) (xy 35.997482 -349.351823)
			(xy 35.919693 -349.390557) (xy 35.838661 -349.421949) (xy 35.755079 -349.44573) (xy 35.669659 -349.461698)
			(xy 35.58313 -349.469716) (xy 35.49623 -349.469716) (xy 35.409701 -349.461698) (xy 35.324281 -349.44573)
			(xy 35.240699 -349.421949) (xy 35.159667 -349.390557) (xy 35.081878 -349.351823) (xy 35.007994 -349.306076)
			(xy 34.938647 -349.253707) (xy 34.874427 -349.195163) (xy 34.815883 -349.130943) (xy 34.763514 -349.061596)
			(xy 34.717767 -348.987712) (xy 34.679033 -348.909923) (xy 34.647641 -348.828891) (xy 34.62386 -348.745309)
			(xy 34.607892 -348.659889) (xy 34.599874 -348.57336) (xy 31.399988 -348.57336) (xy 31.399988 -349.469964)
			(xy 30.577028 -349.469964) (xy 30.554554 -349.47167) (xy 30.510688 -349.482008) (xy 30.469332 -349.499918)
			(xy 30.431782 -349.524838) (xy 30.399213 -349.555988) (xy 30.372646 -349.592392) (xy 30.352914 -349.63291)
			(xy 30.340633 -349.676272) (xy 30.33619 -349.721119) (xy 30.339723 -349.766048) (xy 30.351122 -349.80965)
			(xy 30.370029 -349.850559) (xy 30.395853 -349.887494) (xy 30.41142 -349.903796) (xy 30.44698 -349.939356)
			(xy 51.07432 -349.939356) (xy 52.726336 -349.939356) (xy 52.726336 -351.591372) (xy 51.07432 -351.591372)
			(xy 51.07432 -349.939356) (xy 30.44698 -349.939356) (xy 31.313543 -350.805919) (xy 47.574698 -350.805919)
			(xy 47.574698 -350.724809) (xy 47.582648 -350.64409) (xy 47.598471 -350.564539) (xy 47.622016 -350.486923)
			(xy 47.653055 -350.411987) (xy 47.69129 -350.340455) (xy 47.736352 -350.273015) (xy 47.787807 -350.210316)
			(xy 47.84516 -350.152963) (xy 47.907859 -350.101508) (xy 47.975299 -350.056446) (xy 48.046831 -350.018211)
			(xy 48.121767 -349.987172) (xy 48.199383 -349.963627) (xy 48.278934 -349.947804) (xy 48.359653 -349.939854)
			(xy 48.440763 -349.939854) (xy 48.521482 -349.947804) (xy 48.601033 -349.963627) (xy 48.678649 -349.987172)
			(xy 48.753585 -350.018211) (xy 48.825117 -350.056446) (xy 48.892557 -350.101508) (xy 48.955256 -350.152963)
			(xy 49.012609 -350.210316) (xy 49.064064 -350.273015) (xy 49.109126 -350.340455) (xy 49.147361 -350.411987)
			(xy 49.1784 -350.486923) (xy 49.201945 -350.564539) (xy 49.217768 -350.64409) (xy 49.225718 -350.724809)
			(xy 49.226216 -350.765364) (xy 49.225718 -350.805919) (xy 49.217768 -350.886638) (xy 49.201945 -350.966189)
			(xy 49.1784 -351.043805) (xy 49.147361 -351.118741) (xy 49.109126 -351.190273) (xy 49.064064 -351.257713)
			(xy 49.012609 -351.320412) (xy 48.955256 -351.377765) (xy 48.892557 -351.42922) (xy 48.825117 -351.474282)
			(xy 48.753585 -351.512517) (xy 48.678649 -351.543556) (xy 48.601033 -351.567101) (xy 48.521482 -351.582924)
			(xy 48.440763 -351.590874) (xy 48.359653 -351.590874) (xy 48.278934 -351.582924) (xy 48.199383 -351.567101)
			(xy 48.121767 -351.543556) (xy 48.046831 -351.512517) (xy 47.975299 -351.474282) (xy 47.907859 -351.42922)
			(xy 47.84516 -351.377765) (xy 47.787807 -351.320412) (xy 47.736352 -351.257713) (xy 47.69129 -351.190273)
			(xy 47.653055 -351.118741) (xy 47.622016 -351.043805) (xy 47.598471 -350.966189) (xy 47.582648 -350.886638)
			(xy 47.574698 -350.805919) (xy 31.313543 -350.805919) (xy 33.038288 -352.530664) (xy 38.516306 -352.530664)
			(xy 40.000174 -354.014532) (xy 40.000174 -354.748846) (xy 40.000663 -354.771723) (xy 40.008858 -354.816737)
			(xy 40.024976 -354.859558) (xy 40.048495 -354.898805) (xy 40.078657 -354.933209) (xy 40.114489 -354.961661)
			(xy 40.154833 -354.983243) (xy 40.198388 -354.997257) (xy 40.243748 -355.003252) (xy 40.26662 -355.002592)
			(xy 40.297513 -355.001589) (xy 40.359096 -355.006902) (xy 40.419403 -355.020454) (xy 40.477338 -355.041998)
			(xy 40.531847 -355.071142) (xy 40.581939 -355.107356) (xy 40.626701 -355.149981) (xy 40.665321 -355.198242)
			(xy 40.697095 -355.251261) (xy 40.721446 -355.308073) (xy 40.73793 -355.367646) (xy 40.746247 -355.428895)
			(xy 40.746247 -355.490706) (xy 40.737929 -355.551955) (xy 40.721445 -355.611527) (xy 40.697095 -355.66834)
			(xy 40.685689 -355.687372) (xy 41.20818 -355.687372) (xy 41.20818 -355.627436) (xy 41.216003 -355.568014)
			(xy 41.231516 -355.510121) (xy 41.254452 -355.454748) (xy 41.284419 -355.402842) (xy 41.320906 -355.355292)
			(xy 41.363286 -355.312912) (xy 41.410836 -355.276425) (xy 41.462742 -355.246458) (xy 41.518115 -355.223522)
			(xy 41.576008 -355.208009) (xy 41.63543 -355.200186) (xy 41.695366 -355.200186) (xy 41.754788 -355.208009)
			(xy 41.812681 -355.223522) (xy 41.868054 -355.246458) (xy 41.91996 -355.276425) (xy 41.96751 -355.312912)
			(xy 42.00989 -355.355292) (xy 42.046377 -355.402842) (xy 42.047579 -355.404924) (xy 82.254326 -355.404924)
			(xy 82.254326 -355.344988) (xy 82.262149 -355.285566) (xy 82.277662 -355.227673) (xy 82.300598 -355.1723)
			(xy 82.330565 -355.120394) (xy 82.367052 -355.072844) (xy 82.409432 -355.030464) (xy 82.456982 -354.993977)
			(xy 82.508888 -354.96401) (xy 82.564261 -354.941074) (xy 82.622154 -354.925561) (xy 82.681576 -354.917738)
			(xy 82.741512 -354.917738) (xy 82.800934 -354.925561) (xy 82.858827 -354.941074) (xy 82.9142 -354.96401)
			(xy 82.966106 -354.993977) (xy 83.013656 -355.030464) (xy 83.056036 -355.072844) (xy 83.092523 -355.120394)
			(xy 83.12249 -355.1723) (xy 83.145426 -355.227673) (xy 83.160939 -355.285566) (xy 83.168762 -355.344988)
			(xy 83.169252 -355.374956) (xy 83.168762 -355.404924) (xy 83.160939 -355.464346) (xy 83.145426 -355.522239)
			(xy 83.12249 -355.577612) (xy 83.092523 -355.629518) (xy 83.056036 -355.677068) (xy 83.013656 -355.719448)
			(xy 82.966106 -355.755935) (xy 82.9142 -355.785902) (xy 82.858827 -355.808838) (xy 82.800934 -355.824351)
			(xy 82.741512 -355.832174) (xy 82.681576 -355.832174) (xy 82.622154 -355.824351) (xy 82.564261 -355.808838)
			(xy 82.508888 -355.785902) (xy 82.456982 -355.755935) (xy 82.409432 -355.719448) (xy 82.367052 -355.677068)
			(xy 82.330565 -355.629518) (xy 82.300598 -355.577612) (xy 82.277662 -355.522239) (xy 82.262149 -355.464346)
			(xy 82.254326 -355.404924) (xy 42.047579 -355.404924) (xy 42.076344 -355.454748) (xy 42.09928 -355.510121)
			(xy 42.114793 -355.568014) (xy 42.122616 -355.627436) (xy 42.123106 -355.657404) (xy 42.122616 -355.687372)
			(xy 42.114793 -355.746794) (xy 42.09928 -355.804687) (xy 42.076344 -355.86006) (xy 42.046377 -355.911966)
			(xy 42.00989 -355.959516) (xy 42.003142 -355.966264) (xy 42.811936 -355.966264) (xy 42.811936 -355.906328)
			(xy 42.819759 -355.846906) (xy 42.835272 -355.789013) (xy 42.858208 -355.73364) (xy 42.888175 -355.681734)
			(xy 42.924662 -355.634184) (xy 42.967042 -355.591804) (xy 43.014592 -355.555317) (xy 43.066498 -355.52535)
			(xy 43.121871 -355.502414) (xy 43.179764 -355.486901) (xy 43.239186 -355.479078) (xy 43.299122 -355.479078)
			(xy 43.358544 -355.486901) (xy 43.416437 -355.502414) (xy 43.47181 -355.52535) (xy 43.523716 -355.555317)
			(xy 43.571266 -355.591804) (xy 43.613646 -355.634184) (xy 43.650133 -355.681734) (xy 43.6801 -355.73364)
			(xy 43.703036 -355.789013) (xy 43.718549 -355.846906) (xy 43.726372 -355.906328) (xy 43.726862 -355.936296)
			(xy 43.726372 -355.966264) (xy 43.718549 -356.025686) (xy 43.703036 -356.083579) (xy 43.6801 -356.138952)
			(xy 43.650133 -356.190858) (xy 43.628153 -356.219502) (xy 44.267864 -356.219502) (xy 44.267864 -356.159566)
			(xy 44.275687 -356.100144) (xy 44.2912 -356.042251) (xy 44.314136 -355.986878) (xy 44.344103 -355.934972)
			(xy 44.38059 -355.887422) (xy 44.42297 -355.845042) (xy 44.47052 -355.808555) (xy 44.522426 -355.778588)
			(xy 44.577799 -355.755652) (xy 44.635692 -355.740139) (xy 44.695114 -355.732316) (xy 44.75505 -355.732316)
			(xy 44.814472 -355.740139) (xy 44.872365 -355.755652) (xy 44.927738 -355.778588) (xy 44.979644 -355.808555)
			(xy 45.013044 -355.834184) (xy 84.542866 -355.834184) (xy 84.542866 -355.774248) (xy 84.550689 -355.714826)
			(xy 84.566202 -355.656933) (xy 84.589138 -355.60156) (xy 84.619105 -355.549654) (xy 84.655592 -355.502104)
			(xy 84.697972 -355.459724) (xy 84.745522 -355.423237) (xy 84.797428 -355.39327) (xy 84.852801 -355.370334)
			(xy 84.910694 -355.354821) (xy 84.970116 -355.346998) (xy 85.030052 -355.346998) (xy 85.089474 -355.354821)
			(xy 85.147367 -355.370334) (xy 85.20274 -355.39327) (xy 85.254646 -355.423237) (xy 85.302196 -355.459724)
			(xy 85.344576 -355.502104) (xy 85.381063 -355.549654) (xy 85.41103 -355.60156) (xy 85.433966 -355.656933)
			(xy 85.449479 -355.714826) (xy 85.457302 -355.774248) (xy 85.457792 -355.804216) (xy 85.457302 -355.834184)
			(xy 85.449479 -355.893606) (xy 85.433966 -355.951499) (xy 85.41103 -356.006872) (xy 85.383736 -356.054148)
			(xy 86.951802 -356.054148) (xy 86.951802 -355.994212) (xy 86.959625 -355.93479) (xy 86.975138 -355.876897)
			(xy 86.998074 -355.821524) (xy 87.028041 -355.769618) (xy 87.064528 -355.722068) (xy 87.106908 -355.679688)
			(xy 87.154458 -355.643201) (xy 87.206364 -355.613234) (xy 87.261737 -355.590298) (xy 87.31963 -355.574785)
			(xy 87.379052 -355.566962) (xy 87.438988 -355.566962) (xy 87.49841 -355.574785) (xy 87.556303 -355.590298)
			(xy 87.611676 -355.613234) (xy 87.663582 -355.643201) (xy 87.711132 -355.679688) (xy 87.753512 -355.722068)
			(xy 87.789999 -355.769618) (xy 87.819966 -355.821524) (xy 87.842902 -355.876897) (xy 87.858415 -355.93479)
			(xy 87.866238 -355.994212) (xy 87.866728 -356.02418) (xy 87.866238 -356.054148) (xy 87.858415 -356.11357)
			(xy 87.842902 -356.171463) (xy 87.819966 -356.226836) (xy 87.789999 -356.278742) (xy 87.753512 -356.326292)
			(xy 87.711132 -356.368672) (xy 87.663582 -356.405159) (xy 87.611676 -356.435126) (xy 87.566858 -356.45369)
			(xy 88.618042 -356.45369) (xy 88.618042 -356.393754) (xy 88.625865 -356.334332) (xy 88.641378 -356.276439)
			(xy 88.664314 -356.221066) (xy 88.694281 -356.16916) (xy 88.730768 -356.12161) (xy 88.773148 -356.07923)
			(xy 88.820698 -356.042743) (xy 88.872604 -356.012776) (xy 88.927977 -355.98984) (xy 88.98587 -355.974327)
			(xy 89.045292 -355.966504) (xy 89.105228 -355.966504) (xy 89.16465 -355.974327) (xy 89.222543 -355.98984)
			(xy 89.277916 -356.012776) (xy 89.329822 -356.042743) (xy 89.377372 -356.07923) (xy 89.419752 -356.12161)
			(xy 89.456239 -356.16916) (xy 89.486206 -356.221066) (xy 89.509142 -356.276439) (xy 89.524655 -356.334332)
			(xy 89.532478 -356.393754) (xy 89.532968 -356.423722) (xy 89.532478 -356.45369) (xy 89.524655 -356.513112)
			(xy 89.509142 -356.571005) (xy 89.486206 -356.626378) (xy 89.456239 -356.678284) (xy 89.419752 -356.725834)
			(xy 89.377372 -356.768214) (xy 89.329822 -356.804701) (xy 89.277916 -356.834668) (xy 89.222543 -356.857604)
			(xy 89.16465 -356.873117) (xy 89.105228 -356.88094) (xy 89.045292 -356.88094) (xy 88.98587 -356.873117)
			(xy 88.927977 -356.857604) (xy 88.872604 -356.834668) (xy 88.820698 -356.804701) (xy 88.773148 -356.768214)
			(xy 88.730768 -356.725834) (xy 88.694281 -356.678284) (xy 88.664314 -356.626378) (xy 88.641378 -356.571005)
			(xy 88.625865 -356.513112) (xy 88.618042 -356.45369) (xy 87.566858 -356.45369) (xy 87.556303 -356.458062)
			(xy 87.49841 -356.473575) (xy 87.438988 -356.481398) (xy 87.379052 -356.481398) (xy 87.31963 -356.473575)
			(xy 87.261737 -356.458062) (xy 87.206364 -356.435126) (xy 87.154458 -356.405159) (xy 87.106908 -356.368672)
			(xy 87.064528 -356.326292) (xy 87.028041 -356.278742) (xy 86.998074 -356.226836) (xy 86.975138 -356.171463)
			(xy 86.959625 -356.11357) (xy 86.951802 -356.054148) (xy 85.383736 -356.054148) (xy 85.381063 -356.058778)
			(xy 85.344576 -356.106328) (xy 85.302196 -356.148708) (xy 85.254646 -356.185195) (xy 85.20274 -356.215162)
			(xy 85.147367 -356.238098) (xy 85.089474 -356.253611) (xy 85.030052 -356.261434) (xy 84.970116 -356.261434)
			(xy 84.910694 -356.253611) (xy 84.852801 -356.238098) (xy 84.797428 -356.215162) (xy 84.745522 -356.185195)
			(xy 84.697972 -356.148708) (xy 84.655592 -356.106328) (xy 84.619105 -356.058778) (xy 84.589138 -356.006872)
			(xy 84.566202 -355.951499) (xy 84.550689 -355.893606) (xy 84.542866 -355.834184) (xy 45.013044 -355.834184)
			(xy 45.027194 -355.845042) (xy 45.069574 -355.887422) (xy 45.106061 -355.934972) (xy 45.136028 -355.986878)
			(xy 45.158964 -356.042251) (xy 45.174477 -356.100144) (xy 45.1823 -356.159566) (xy 45.18279 -356.189534)
			(xy 45.1823 -356.219502) (xy 45.174477 -356.278924) (xy 45.158964 -356.336817) (xy 45.136028 -356.39219)
			(xy 45.106061 -356.444096) (xy 45.069574 -356.491646) (xy 45.06181 -356.49941) (xy 79.345264 -356.49941)
			(xy 79.345264 -356.439474) (xy 79.353087 -356.380052) (xy 79.3686 -356.322159) (xy 79.391536 -356.266786)
			(xy 79.421503 -356.21488) (xy 79.45799 -356.16733) (xy 79.50037 -356.12495) (xy 79.54792 -356.088463)
			(xy 79.599826 -356.058496) (xy 79.655199 -356.03556) (xy 79.713092 -356.020047) (xy 79.772514 -356.012224)
			(xy 79.83245 -356.012224) (xy 79.891872 -356.020047) (xy 79.949765 -356.03556) (xy 80.005138 -356.058496)
			(xy 80.057044 -356.088463) (xy 80.104594 -356.12495) (xy 80.146974 -356.16733) (xy 80.183461 -356.21488)
			(xy 80.213428 -356.266786) (xy 80.236364 -356.322159) (xy 80.251877 -356.380052) (xy 80.2597 -356.439474)
			(xy 80.26019 -356.469442) (xy 80.2597 -356.49941) (xy 80.251877 -356.558832) (xy 80.236364 -356.616725)
			(xy 80.213428 -356.672098) (xy 80.183461 -356.724004) (xy 80.146974 -356.771554) (xy 80.104594 -356.813934)
			(xy 80.057044 -356.850421) (xy 80.005138 -356.880388) (xy 79.949765 -356.903324) (xy 79.891872 -356.918837)
			(xy 79.83245 -356.92666) (xy 79.772514 -356.92666) (xy 79.713092 -356.918837) (xy 79.655199 -356.903324)
			(xy 79.599826 -356.880388) (xy 79.54792 -356.850421) (xy 79.50037 -356.813934) (xy 79.45799 -356.771554)
			(xy 79.421503 -356.724004) (xy 79.391536 -356.672098) (xy 79.3686 -356.616725) (xy 79.353087 -356.558832)
			(xy 79.345264 -356.49941) (xy 45.06181 -356.49941) (xy 45.027194 -356.534026) (xy 44.979644 -356.570513)
			(xy 44.927738 -356.60048) (xy 44.872365 -356.623416) (xy 44.814472 -356.638929) (xy 44.75505 -356.646752)
			(xy 44.695114 -356.646752) (xy 44.635692 -356.638929) (xy 44.577799 -356.623416) (xy 44.522426 -356.60048)
			(xy 44.47052 -356.570513) (xy 44.42297 -356.534026) (xy 44.38059 -356.491646) (xy 44.344103 -356.444096)
			(xy 44.314136 -356.39219) (xy 44.2912 -356.336817) (xy 44.275687 -356.278924) (xy 44.267864 -356.219502)
			(xy 43.628153 -356.219502) (xy 43.613646 -356.238408) (xy 43.571266 -356.280788) (xy 43.523716 -356.317275)
			(xy 43.47181 -356.347242) (xy 43.416437 -356.370178) (xy 43.358544 -356.385691) (xy 43.299122 -356.393514)
			(xy 43.239186 -356.393514) (xy 43.179764 -356.385691) (xy 43.121871 -356.370178) (xy 43.066498 -356.347242)
			(xy 43.014592 -356.317275) (xy 42.967042 -356.280788) (xy 42.924662 -356.238408) (xy 42.888175 -356.190858)
			(xy 42.858208 -356.138952) (xy 42.835272 -356.083579) (xy 42.819759 -356.025686) (xy 42.811936 -355.966264)
			(xy 42.003142 -355.966264) (xy 41.96751 -356.001896) (xy 41.91996 -356.038383) (xy 41.868054 -356.06835)
			(xy 41.812681 -356.091286) (xy 41.754788 -356.106799) (xy 41.695366 -356.114622) (xy 41.63543 -356.114622)
			(xy 41.576008 -356.106799) (xy 41.518115 -356.091286) (xy 41.462742 -356.06835) (xy 41.410836 -356.038383)
			(xy 41.363286 -356.001896) (xy 41.320906 -355.959516) (xy 41.284419 -355.911966) (xy 41.254452 -355.86006)
			(xy 41.231516 -355.804687) (xy 41.216003 -355.746794) (xy 41.20818 -355.687372) (xy 40.685689 -355.687372)
			(xy 40.66532 -355.721359) (xy 40.626701 -355.76962) (xy 40.581938 -355.812245) (xy 40.531846 -355.848459)
			(xy 40.477337 -355.877603) (xy 40.419402 -355.899147) (xy 40.359095 -355.912698) (xy 40.297513 -355.918011)
			(xy 40.26662 -355.916992) (xy 40.243741 -355.91635) (xy 40.198365 -355.922316) (xy 40.154791 -355.93631)
			(xy 40.114426 -355.95788) (xy 40.078577 -355.986329) (xy 40.0484 -356.020737) (xy 40.024873 -356.059993)
			(xy 40.008754 -356.102827) (xy 40.000566 -356.147855) (xy 40.000174 -356.170738) (xy 40.000174 -359.191814)
			(xy 40.105584 -359.297224) (xy 40.429942 -359.297224) (xy 40.982138 -359.84942) (xy 41.05783 -359.84942)
			(xy 41.06799 -359.847896) (xy 41.140106 -359.836698) (xy 41.285233 -359.821156) (xy 41.430988 -359.813487)
			(xy 41.576945 -359.813712) (xy 41.722676 -359.821832) (xy 41.867754 -359.837822) (xy 42.011755 -359.861636)
			(xy 42.154257 -359.893204) (xy 42.294843 -359.932434) (xy 42.433102 -359.97921) (xy 42.568628 -360.033396)
			(xy 42.701024 -360.094832) (xy 42.829904 -360.163341) (xy 42.95489 -360.238719) (xy 43.075616 -360.320748)
			(xy 43.191728 -360.409187) (xy 43.302887 -360.503776) (xy 43.408766 -360.604239) (xy 43.509057 -360.710282)
			(xy 43.603465 -360.821595) (xy 43.691715 -360.937851) (xy 43.773547 -361.05871) (xy 43.834446 -361.16006)
			(xy 63.647577 -361.16006) (xy 63.651612 -361.084356) (xy 63.663671 -361.009511) (xy 63.683617 -360.93637)
			(xy 63.711224 -360.865765) (xy 63.74618 -360.798494) (xy 63.788088 -360.735319) (xy 63.836474 -360.676957)
			(xy 63.89079 -360.624069) (xy 63.950419 -360.577254) (xy 64.014687 -360.537042) (xy 64.082864 -360.50389)
			(xy 64.15418 -360.478172) (xy 64.227825 -360.46018) (xy 64.302965 -360.450118) (xy 64.378749 -360.448099)
			(xy 64.454319 -360.454148) (xy 64.528817 -360.468195) (xy 64.6014 -360.490081) (xy 64.671246 -360.519558)
			(xy 64.737563 -360.556293) (xy 64.799599 -360.599868) (xy 64.856652 -360.64979) (xy 64.908076 -360.705494)
			(xy 64.953287 -360.766349) (xy 64.991774 -360.831664) (xy 65.0231 -360.9007) (xy 65.04691 -360.972675)
			(xy 65.062935 -361.046773) (xy 65.070994 -361.122154) (xy 65.071498 -361.16006) (xy 66.187577 -361.16006)
			(xy 66.191612 -361.084356) (xy 66.203671 -361.009511) (xy 66.223617 -360.93637) (xy 66.251224 -360.865765)
			(xy 66.28618 -360.798494) (xy 66.328088 -360.735319) (xy 66.376474 -360.676957) (xy 66.43079 -360.624069)
			(xy 66.490419 -360.577254) (xy 66.554687 -360.537042) (xy 66.622864 -360.50389) (xy 66.69418 -360.478172)
			(xy 66.767825 -360.46018) (xy 66.842965 -360.450118) (xy 66.918749 -360.448099) (xy 66.994319 -360.454148)
			(xy 67.068817 -360.468195) (xy 67.1414 -360.490081) (xy 67.211246 -360.519558) (xy 67.277563 -360.556293)
			(xy 67.339599 -360.599868) (xy 67.396652 -360.64979) (xy 67.448076 -360.705494) (xy 67.493287 -360.766349)
			(xy 67.531774 -360.831664) (xy 67.5631 -360.9007) (xy 67.58691 -360.972675) (xy 67.602935 -361.046773)
			(xy 67.610994 -361.122154) (xy 67.611498 -361.16006) (xy 68.727577 -361.16006) (xy 68.731612 -361.084356)
			(xy 68.743671 -361.009511) (xy 68.763617 -360.93637) (xy 68.791224 -360.865765) (xy 68.82618 -360.798494)
			(xy 68.868088 -360.735319) (xy 68.916474 -360.676957) (xy 68.97079 -360.624069) (xy 69.030419 -360.577254)
			(xy 69.094687 -360.537042) (xy 69.162864 -360.50389) (xy 69.23418 -360.478172) (xy 69.307825 -360.46018)
			(xy 69.382965 -360.450118) (xy 69.458749 -360.448099) (xy 69.534319 -360.454148) (xy 69.608817 -360.468195)
			(xy 69.6814 -360.490081) (xy 69.751246 -360.519558) (xy 69.817563 -360.556293) (xy 69.879599 -360.599868)
			(xy 69.936652 -360.64979) (xy 69.988076 -360.705494) (xy 70.033287 -360.766349) (xy 70.071774 -360.831664)
			(xy 70.1031 -360.9007) (xy 70.12691 -360.972675) (xy 70.142935 -361.046773) (xy 70.150994 -361.122154)
			(xy 70.151498 -361.16006) (xy 71.267577 -361.16006) (xy 71.271612 -361.084356) (xy 71.283671 -361.009511)
			(xy 71.303617 -360.93637) (xy 71.331224 -360.865765) (xy 71.36618 -360.798494) (xy 71.408088 -360.735319)
			(xy 71.456474 -360.676957) (xy 71.51079 -360.624069) (xy 71.570419 -360.577254) (xy 71.634687 -360.537042)
			(xy 71.702864 -360.50389) (xy 71.77418 -360.478172) (xy 71.847825 -360.46018) (xy 71.922965 -360.450118)
			(xy 71.998749 -360.448099) (xy 72.074319 -360.454148) (xy 72.148817 -360.468195) (xy 72.2214 -360.490081)
			(xy 72.291246 -360.519558) (xy 72.357563 -360.556293) (xy 72.419599 -360.599868) (xy 72.476652 -360.64979)
			(xy 72.528076 -360.705494) (xy 72.573287 -360.766349) (xy 72.611774 -360.831664) (xy 72.6431 -360.9007)
			(xy 72.66691 -360.972675) (xy 72.682935 -361.046773) (xy 72.690994 -361.122154) (xy 72.691498 -361.16006)
			(xy 73.807577 -361.16006) (xy 73.811612 -361.084356) (xy 73.823671 -361.009511) (xy 73.843617 -360.93637)
			(xy 73.871224 -360.865765) (xy 73.90618 -360.798494) (xy 73.948088 -360.735319) (xy 73.996474 -360.676957)
			(xy 74.05079 -360.624069) (xy 74.110419 -360.577254) (xy 74.174687 -360.537042) (xy 74.242864 -360.50389)
			(xy 74.31418 -360.478172) (xy 74.387825 -360.46018) (xy 74.462965 -360.450118) (xy 74.538749 -360.448099)
			(xy 74.614319 -360.454148) (xy 74.688817 -360.468195) (xy 74.7614 -360.490081) (xy 74.831246 -360.519558)
			(xy 74.897563 -360.556293) (xy 74.959599 -360.599868) (xy 75.016652 -360.64979) (xy 75.068076 -360.705494)
			(xy 75.113287 -360.766349) (xy 75.151774 -360.831664) (xy 75.1831 -360.9007) (xy 75.20691 -360.972675)
			(xy 75.222935 -361.046773) (xy 75.230994 -361.122154) (xy 75.231498 -361.16006) (xy 76.347577 -361.16006)
			(xy 76.351612 -361.084356) (xy 76.363671 -361.009511) (xy 76.383617 -360.93637) (xy 76.411224 -360.865765)
			(xy 76.44618 -360.798494) (xy 76.488088 -360.735319) (xy 76.536474 -360.676957) (xy 76.59079 -360.624069)
			(xy 76.650419 -360.577254) (xy 76.714687 -360.537042) (xy 76.782864 -360.50389) (xy 76.85418 -360.478172)
			(xy 76.927825 -360.46018) (xy 77.002965 -360.450118) (xy 77.078749 -360.448099) (xy 77.154319 -360.454148)
			(xy 77.228817 -360.468195) (xy 77.3014 -360.490081) (xy 77.371246 -360.519558) (xy 77.437563 -360.556293)
			(xy 77.499599 -360.599868) (xy 77.556652 -360.64979) (xy 77.608076 -360.705494) (xy 77.653287 -360.766349)
			(xy 77.691774 -360.831664) (xy 77.7231 -360.9007) (xy 77.74691 -360.972675) (xy 77.762935 -361.046773)
			(xy 77.770994 -361.122154) (xy 77.771498 -361.16006) (xy 78.887577 -361.16006) (xy 78.891612 -361.084356)
			(xy 78.903671 -361.009511) (xy 78.923617 -360.93637) (xy 78.951224 -360.865765) (xy 78.98618 -360.798494)
			(xy 79.028088 -360.735319) (xy 79.076474 -360.676957) (xy 79.13079 -360.624069) (xy 79.190419 -360.577254)
			(xy 79.254687 -360.537042) (xy 79.322864 -360.50389) (xy 79.39418 -360.478172) (xy 79.467825 -360.46018)
			(xy 79.542965 -360.450118) (xy 79.618749 -360.448099) (xy 79.694319 -360.454148) (xy 79.768817 -360.468195)
			(xy 79.8414 -360.490081) (xy 79.911246 -360.519558) (xy 79.977563 -360.556293) (xy 80.039599 -360.599868)
			(xy 80.096652 -360.64979) (xy 80.148076 -360.705494) (xy 80.193287 -360.766349) (xy 80.231774 -360.831664)
			(xy 80.2631 -360.9007) (xy 80.28691 -360.972675) (xy 80.302935 -361.046773) (xy 80.310994 -361.122154)
			(xy 80.311498 -361.16006) (xy 81.427577 -361.16006) (xy 81.431612 -361.084356) (xy 81.443671 -361.009511)
			(xy 81.463617 -360.93637) (xy 81.491224 -360.865765) (xy 81.52618 -360.798494) (xy 81.568088 -360.735319)
			(xy 81.616474 -360.676957) (xy 81.67079 -360.624069) (xy 81.730419 -360.577254) (xy 81.794687 -360.537042)
			(xy 81.862864 -360.50389) (xy 81.93418 -360.478172) (xy 82.007825 -360.46018) (xy 82.082965 -360.450118)
			(xy 82.158749 -360.448099) (xy 82.234319 -360.454148) (xy 82.308817 -360.468195) (xy 82.3814 -360.490081)
			(xy 82.451246 -360.519558) (xy 82.517563 -360.556293) (xy 82.579599 -360.599868) (xy 82.585544 -360.60507)
			(xy 86.197697 -360.60507) (xy 86.201732 -360.529366) (xy 86.213791 -360.454521) (xy 86.233737 -360.38138)
			(xy 86.261344 -360.310775) (xy 86.2963 -360.243504) (xy 86.338208 -360.180329) (xy 86.386594 -360.121967)
			(xy 86.44091 -360.069079) (xy 86.500539 -360.022264) (xy 86.564807 -359.982052) (xy 86.632984 -359.9489)
			(xy 86.7043 -359.923182) (xy 86.777945 -359.90519) (xy 86.853085 -359.895128) (xy 86.928869 -359.893109)
			(xy 87.004439 -359.899158) (xy 87.078937 -359.913205) (xy 87.15152 -359.935091) (xy 87.221366 -359.964568)
			(xy 87.287683 -360.001303) (xy 87.349719 -360.044878) (xy 87.406772 -360.0948) (xy 87.458196 -360.150504)
			(xy 87.503407 -360.211359) (xy 87.541894 -360.276674) (xy 87.57322 -360.34571) (xy 87.59703 -360.417685)
			(xy 87.613055 -360.491783) (xy 87.621114 -360.567164) (xy 87.621618 -360.60507) (xy 87.621114 -360.642976)
			(xy 87.613055 -360.718357) (xy 87.59703 -360.792455) (xy 87.57322 -360.86443) (xy 87.541894 -360.933466)
			(xy 87.503407 -360.998781) (xy 87.458196 -361.059636) (xy 87.406772 -361.11534) (xy 87.349719 -361.165262)
			(xy 87.287683 -361.208837) (xy 87.221366 -361.245572) (xy 87.15152 -361.275049) (xy 87.078937 -361.296935)
			(xy 87.004439 -361.310982) (xy 86.928869 -361.317031) (xy 86.853085 -361.315012) (xy 86.777945 -361.30495)
			(xy 86.7043 -361.286958) (xy 86.632984 -361.26124) (xy 86.564807 -361.228088) (xy 86.500539 -361.187876)
			(xy 86.44091 -361.141061) (xy 86.386594 -361.088173) (xy 86.338208 -361.029811) (xy 86.2963 -360.966636)
			(xy 86.261344 -360.899365) (xy 86.233737 -360.82876) (xy 86.213791 -360.755619) (xy 86.201732 -360.680774)
			(xy 86.197697 -360.60507) (xy 82.585544 -360.60507) (xy 82.636652 -360.64979) (xy 82.688076 -360.705494)
			(xy 82.733287 -360.766349) (xy 82.771774 -360.831664) (xy 82.8031 -360.9007) (xy 82.82691 -360.972675)
			(xy 82.842935 -361.046773) (xy 82.850994 -361.122154) (xy 82.851498 -361.16006) (xy 82.850994 -361.197966)
			(xy 82.842935 -361.273347) (xy 82.82691 -361.347445) (xy 82.8031 -361.41942) (xy 82.771774 -361.488456)
			(xy 82.733287 -361.553771) (xy 82.688076 -361.614626) (xy 82.636652 -361.67033) (xy 82.579599 -361.720252)
			(xy 82.517563 -361.763827) (xy 82.451246 -361.800562) (xy 82.3814 -361.830039) (xy 82.308817 -361.851925)
			(xy 82.234319 -361.865972) (xy 82.158749 -361.872021) (xy 82.082965 -361.870002) (xy 82.007825 -361.85994)
			(xy 81.93418 -361.841948) (xy 81.862864 -361.81623) (xy 81.794687 -361.783078) (xy 81.730419 -361.742866)
			(xy 81.67079 -361.696051) (xy 81.616474 -361.643163) (xy 81.568088 -361.584801) (xy 81.52618 -361.521626)
			(xy 81.491224 -361.454355) (xy 81.463617 -361.38375) (xy 81.443671 -361.310609) (xy 81.431612 -361.235764)
			(xy 81.427577 -361.16006) (xy 80.311498 -361.16006) (xy 80.310994 -361.197966) (xy 80.302935 -361.273347)
			(xy 80.28691 -361.347445) (xy 80.2631 -361.41942) (xy 80.231774 -361.488456) (xy 80.193287 -361.553771)
			(xy 80.148076 -361.614626) (xy 80.096652 -361.67033) (xy 80.039599 -361.720252) (xy 79.977563 -361.763827)
			(xy 79.911246 -361.800562) (xy 79.8414 -361.830039) (xy 79.768817 -361.851925) (xy 79.694319 -361.865972)
			(xy 79.618749 -361.872021) (xy 79.542965 -361.870002) (xy 79.467825 -361.85994) (xy 79.39418 -361.841948)
			(xy 79.322864 -361.81623) (xy 79.254687 -361.783078) (xy 79.190419 -361.742866) (xy 79.13079 -361.696051)
			(xy 79.076474 -361.643163) (xy 79.028088 -361.584801) (xy 78.98618 -361.521626) (xy 78.951224 -361.454355)
			(xy 78.923617 -361.38375) (xy 78.903671 -361.310609) (xy 78.891612 -361.235764) (xy 78.887577 -361.16006)
			(xy 77.771498 -361.16006) (xy 77.770994 -361.197966) (xy 77.762935 -361.273347) (xy 77.74691 -361.347445)
			(xy 77.7231 -361.41942) (xy 77.691774 -361.488456) (xy 77.653287 -361.553771) (xy 77.608076 -361.614626)
			(xy 77.556652 -361.67033) (xy 77.499599 -361.720252) (xy 77.437563 -361.763827) (xy 77.371246 -361.800562)
			(xy 77.3014 -361.830039) (xy 77.228817 -361.851925) (xy 77.154319 -361.865972) (xy 77.078749 -361.872021)
			(xy 77.002965 -361.870002) (xy 76.927825 -361.85994) (xy 76.85418 -361.841948) (xy 76.782864 -361.81623)
			(xy 76.714687 -361.783078) (xy 76.650419 -361.742866) (xy 76.59079 -361.696051) (xy 76.536474 -361.643163)
			(xy 76.488088 -361.584801) (xy 76.44618 -361.521626) (xy 76.411224 -361.454355) (xy 76.383617 -361.38375)
			(xy 76.363671 -361.310609) (xy 76.351612 -361.235764) (xy 76.347577 -361.16006) (xy 75.231498 -361.16006)
			(xy 75.230994 -361.197966) (xy 75.222935 -361.273347) (xy 75.20691 -361.347445) (xy 75.1831 -361.41942)
			(xy 75.151774 -361.488456) (xy 75.113287 -361.553771) (xy 75.068076 -361.614626) (xy 75.016652 -361.67033)
			(xy 74.959599 -361.720252) (xy 74.897563 -361.763827) (xy 74.831246 -361.800562) (xy 74.7614 -361.830039)
			(xy 74.688817 -361.851925) (xy 74.614319 -361.865972) (xy 74.538749 -361.872021) (xy 74.462965 -361.870002)
			(xy 74.387825 -361.85994) (xy 74.31418 -361.841948) (xy 74.242864 -361.81623) (xy 74.174687 -361.783078)
			(xy 74.110419 -361.742866) (xy 74.05079 -361.696051) (xy 73.996474 -361.643163) (xy 73.948088 -361.584801)
			(xy 73.90618 -361.521626) (xy 73.871224 -361.454355) (xy 73.843617 -361.38375) (xy 73.823671 -361.310609)
			(xy 73.811612 -361.235764) (xy 73.807577 -361.16006) (xy 72.691498 -361.16006) (xy 72.690994 -361.197966)
			(xy 72.682935 -361.273347) (xy 72.66691 -361.347445) (xy 72.6431 -361.41942) (xy 72.611774 -361.488456)
			(xy 72.573287 -361.553771) (xy 72.528076 -361.614626) (xy 72.476652 -361.67033) (xy 72.419599 -361.720252)
			(xy 72.357563 -361.763827) (xy 72.291246 -361.800562) (xy 72.2214 -361.830039) (xy 72.148817 -361.851925)
			(xy 72.074319 -361.865972) (xy 71.998749 -361.872021) (xy 71.922965 -361.870002) (xy 71.847825 -361.85994)
			(xy 71.77418 -361.841948) (xy 71.702864 -361.81623) (xy 71.634687 -361.783078) (xy 71.570419 -361.742866)
			(xy 71.51079 -361.696051) (xy 71.456474 -361.643163) (xy 71.408088 -361.584801) (xy 71.36618 -361.521626)
			(xy 71.331224 -361.454355) (xy 71.303617 -361.38375) (xy 71.283671 -361.310609) (xy 71.271612 -361.235764)
			(xy 71.267577 -361.16006) (xy 70.151498 -361.16006) (xy 70.150994 -361.197966) (xy 70.142935 -361.273347)
			(xy 70.12691 -361.347445) (xy 70.1031 -361.41942) (xy 70.071774 -361.488456) (xy 70.033287 -361.553771)
			(xy 69.988076 -361.614626) (xy 69.936652 -361.67033) (xy 69.879599 -361.720252) (xy 69.817563 -361.763827)
			(xy 69.751246 -361.800562) (xy 69.6814 -361.830039) (xy 69.608817 -361.851925) (xy 69.534319 -361.865972)
			(xy 69.458749 -361.872021) (xy 69.382965 -361.870002) (xy 69.307825 -361.85994) (xy 69.23418 -361.841948)
			(xy 69.162864 -361.81623) (xy 69.094687 -361.783078) (xy 69.030419 -361.742866) (xy 68.97079 -361.696051)
			(xy 68.916474 -361.643163) (xy 68.868088 -361.584801) (xy 68.82618 -361.521626) (xy 68.791224 -361.454355)
			(xy 68.763617 -361.38375) (xy 68.743671 -361.310609) (xy 68.731612 -361.235764) (xy 68.727577 -361.16006)
			(xy 67.611498 -361.16006) (xy 67.610994 -361.197966) (xy 67.602935 -361.273347) (xy 67.58691 -361.347445)
			(xy 67.5631 -361.41942) (xy 67.531774 -361.488456) (xy 67.493287 -361.553771) (xy 67.448076 -361.614626)
			(xy 67.396652 -361.67033) (xy 67.339599 -361.720252) (xy 67.277563 -361.763827) (xy 67.211246 -361.800562)
			(xy 67.1414 -361.830039) (xy 67.068817 -361.851925) (xy 66.994319 -361.865972) (xy 66.918749 -361.872021)
			(xy 66.842965 -361.870002) (xy 66.767825 -361.85994) (xy 66.69418 -361.841948) (xy 66.622864 -361.81623)
			(xy 66.554687 -361.783078) (xy 66.490419 -361.742866) (xy 66.43079 -361.696051) (xy 66.376474 -361.643163)
			(xy 66.328088 -361.584801) (xy 66.28618 -361.521626) (xy 66.251224 -361.454355) (xy 66.223617 -361.38375)
			(xy 66.203671 -361.310609) (xy 66.191612 -361.235764) (xy 66.187577 -361.16006) (xy 65.071498 -361.16006)
			(xy 65.070994 -361.197966) (xy 65.062935 -361.273347) (xy 65.04691 -361.347445) (xy 65.0231 -361.41942)
			(xy 64.991774 -361.488456) (xy 64.953287 -361.553771) (xy 64.908076 -361.614626) (xy 64.856652 -361.67033)
			(xy 64.799599 -361.720252) (xy 64.737563 -361.763827) (xy 64.671246 -361.800562) (xy 64.6014 -361.830039)
			(xy 64.528817 -361.851925) (xy 64.454319 -361.865972) (xy 64.378749 -361.872021) (xy 64.302965 -361.870002)
			(xy 64.227825 -361.85994) (xy 64.15418 -361.841948) (xy 64.082864 -361.81623) (xy 64.014687 -361.783078)
			(xy 63.950419 -361.742866) (xy 63.89079 -361.696051) (xy 63.836474 -361.643163) (xy 63.788088 -361.584801)
			(xy 63.74618 -361.521626) (xy 63.711224 -361.454355) (xy 63.683617 -361.38375) (xy 63.663671 -361.310609)
			(xy 63.651612 -361.235764) (xy 63.647577 -361.16006) (xy 43.834446 -361.16006) (xy 43.848722 -361.183818)
			(xy 43.91702 -361.31281) (xy 43.978241 -361.445306) (xy 44.032207 -361.58092) (xy 44.078757 -361.719255)
			(xy 44.117758 -361.859905) (xy 44.121092 -361.87507) (xy 84.927697 -361.87507) (xy 84.931732 -361.799366)
			(xy 84.943791 -361.724521) (xy 84.963737 -361.65138) (xy 84.991344 -361.580775) (xy 85.0263 -361.513504)
			(xy 85.068208 -361.450329) (xy 85.116594 -361.391967) (xy 85.17091 -361.339079) (xy 85.230539 -361.292264)
			(xy 85.294807 -361.252052) (xy 85.362984 -361.2189) (xy 85.4343 -361.193182) (xy 85.507945 -361.17519)
			(xy 85.583085 -361.165128) (xy 85.658869 -361.163109) (xy 85.734439 -361.169158) (xy 85.808937 -361.183205)
			(xy 85.88152 -361.205091) (xy 85.951366 -361.234568) (xy 86.017683 -361.271303) (xy 86.079719 -361.314878)
			(xy 86.136772 -361.3648) (xy 86.188196 -361.420504) (xy 86.233407 -361.481359) (xy 86.271894 -361.546674)
			(xy 86.30322 -361.61571) (xy 86.32703 -361.687685) (xy 86.343055 -361.761783) (xy 86.351114 -361.837164)
			(xy 86.351618 -361.87507) (xy 86.351114 -361.912976) (xy 86.343055 -361.988357) (xy 86.32703 -362.062455)
			(xy 86.30322 -362.13443) (xy 86.271894 -362.203466) (xy 86.233407 -362.268781) (xy 86.188196 -362.329636)
			(xy 86.136772 -362.38534) (xy 86.079719 -362.435262) (xy 86.017683 -362.478837) (xy 85.951366 -362.515572)
			(xy 85.88152 -362.545049) (xy 85.808937 -362.566935) (xy 85.734439 -362.580982) (xy 85.658869 -362.587031)
			(xy 85.583085 -362.585012) (xy 85.507945 -362.57495) (xy 85.4343 -362.556958) (xy 85.362984 -362.53124)
			(xy 85.294807 -362.498088) (xy 85.230539 -362.457876) (xy 85.17091 -362.411061) (xy 85.116594 -362.358173)
			(xy 85.068208 -362.299811) (xy 85.0263 -362.236636) (xy 84.991344 -362.169365) (xy 84.963737 -362.09876)
			(xy 84.943791 -362.025619) (xy 84.931732 -361.950774) (xy 84.927697 -361.87507) (xy 44.121092 -361.87507)
			(xy 44.149094 -362.002458) (xy 44.172673 -362.146498) (xy 44.188427 -362.291602) (xy 44.19631 -362.437346)
			(xy 44.196762 -362.510324) (xy 44.196448 -362.563596) (xy 44.19213 -362.670054) (xy 44.188126 -362.723176)
			(xy 44.181835 -362.796254) (xy 44.162307 -362.941642) (xy 44.134905 -363.085753) (xy 44.120245 -363.14507)
			(xy 86.197697 -363.14507) (xy 86.201732 -363.069366) (xy 86.213791 -362.994521) (xy 86.233737 -362.92138)
			(xy 86.261344 -362.850775) (xy 86.2963 -362.783504) (xy 86.338208 -362.720329) (xy 86.386594 -362.661967)
			(xy 86.44091 -362.609079) (xy 86.500539 -362.562264) (xy 86.564807 -362.522052) (xy 86.632984 -362.4889)
			(xy 86.7043 -362.463182) (xy 86.777945 -362.44519) (xy 86.853085 -362.435128) (xy 86.928869 -362.433109)
			(xy 87.004439 -362.439158) (xy 87.078937 -362.453205) (xy 87.15152 -362.475091) (xy 87.221366 -362.504568)
			(xy 87.287683 -362.541303) (xy 87.349719 -362.584878) (xy 87.406772 -362.6348) (xy 87.458196 -362.690504)
			(xy 87.503407 -362.751359) (xy 87.541894 -362.816674) (xy 87.57322 -362.88571) (xy 87.59703 -362.957685)
			(xy 87.613055 -363.031783) (xy 87.621114 -363.107164) (xy 87.621618 -363.14507) (xy 87.621114 -363.182976)
			(xy 87.613055 -363.258357) (xy 87.59703 -363.332455) (xy 87.57322 -363.40443) (xy 87.541894 -363.473466)
			(xy 87.503407 -363.538781) (xy 87.458196 -363.599636) (xy 87.406772 -363.65534) (xy 87.349719 -363.705262)
			(xy 87.287683 -363.748837) (xy 87.221366 -363.785572) (xy 87.15152 -363.815049) (xy 87.078937 -363.836935)
			(xy 87.004439 -363.850982) (xy 86.928869 -363.857031) (xy 86.853085 -363.855012) (xy 86.777945 -363.84495)
			(xy 86.7043 -363.826958) (xy 86.632984 -363.80124) (xy 86.564807 -363.768088) (xy 86.500539 -363.727876)
			(xy 86.44091 -363.681061) (xy 86.386594 -363.628173) (xy 86.338208 -363.569811) (xy 86.2963 -363.506636)
			(xy 86.261344 -363.439365) (xy 86.233737 -363.36876) (xy 86.213791 -363.295619) (xy 86.201732 -363.220774)
			(xy 86.197697 -363.14507) (xy 44.120245 -363.14507) (xy 44.09971 -363.228161) (xy 44.056827 -363.368447)
			(xy 44.006382 -363.506193) (xy 43.948524 -363.640995) (xy 43.883424 -363.772452) (xy 43.833925 -363.86008)
			(xy 63.647577 -363.86008) (xy 63.651612 -363.784376) (xy 63.663671 -363.709531) (xy 63.683617 -363.63639)
			(xy 63.711224 -363.565785) (xy 63.74618 -363.498514) (xy 63.788088 -363.435339) (xy 63.836474 -363.376977)
			(xy 63.89079 -363.324089) (xy 63.950419 -363.277274) (xy 64.014687 -363.237062) (xy 64.082864 -363.20391)
			(xy 64.15418 -363.178192) (xy 64.227825 -363.1602) (xy 64.302965 -363.150138) (xy 64.378749 -363.148119)
			(xy 64.454319 -363.154168) (xy 64.528817 -363.168215) (xy 64.6014 -363.190101) (xy 64.671246 -363.219578)
			(xy 64.737563 -363.256313) (xy 64.799599 -363.299888) (xy 64.856652 -363.34981) (xy 64.908076 -363.405514)
			(xy 64.953287 -363.466369) (xy 64.991774 -363.531684) (xy 65.0231 -363.60072) (xy 65.04691 -363.672695)
			(xy 65.062935 -363.746793) (xy 65.070994 -363.822174) (xy 65.071498 -363.86008) (xy 66.187577 -363.86008)
			(xy 66.191612 -363.784376) (xy 66.203671 -363.709531) (xy 66.223617 -363.63639) (xy 66.251224 -363.565785)
			(xy 66.28618 -363.498514) (xy 66.328088 -363.435339) (xy 66.376474 -363.376977) (xy 66.43079 -363.324089)
			(xy 66.490419 -363.277274) (xy 66.554687 -363.237062) (xy 66.622864 -363.20391) (xy 66.69418 -363.178192)
			(xy 66.767825 -363.1602) (xy 66.842965 -363.150138) (xy 66.918749 -363.148119) (xy 66.994319 -363.154168)
			(xy 67.068817 -363.168215) (xy 67.1414 -363.190101) (xy 67.211246 -363.219578) (xy 67.277563 -363.256313)
			(xy 67.339599 -363.299888) (xy 67.396652 -363.34981) (xy 67.448076 -363.405514) (xy 67.493287 -363.466369)
			(xy 67.531774 -363.531684) (xy 67.5631 -363.60072) (xy 67.58691 -363.672695) (xy 67.602935 -363.746793)
			(xy 67.610994 -363.822174) (xy 67.611498 -363.86008) (xy 68.727577 -363.86008) (xy 68.731612 -363.784376)
			(xy 68.743671 -363.709531) (xy 68.763617 -363.63639) (xy 68.791224 -363.565785) (xy 68.82618 -363.498514)
			(xy 68.868088 -363.435339) (xy 68.916474 -363.376977) (xy 68.97079 -363.324089) (xy 69.030419 -363.277274)
			(xy 69.094687 -363.237062) (xy 69.162864 -363.20391) (xy 69.23418 -363.178192) (xy 69.307825 -363.1602)
			(xy 69.382965 -363.150138) (xy 69.458749 -363.148119) (xy 69.534319 -363.154168) (xy 69.608817 -363.168215)
			(xy 69.6814 -363.190101) (xy 69.751246 -363.219578) (xy 69.817563 -363.256313) (xy 69.879599 -363.299888)
			(xy 69.936652 -363.34981) (xy 69.988076 -363.405514) (xy 70.033287 -363.466369) (xy 70.071774 -363.531684)
			(xy 70.1031 -363.60072) (xy 70.12691 -363.672695) (xy 70.142935 -363.746793) (xy 70.150994 -363.822174)
			(xy 70.151498 -363.86008) (xy 71.267577 -363.86008) (xy 71.271612 -363.784376) (xy 71.283671 -363.709531)
			(xy 71.303617 -363.63639) (xy 71.331224 -363.565785) (xy 71.36618 -363.498514) (xy 71.408088 -363.435339)
			(xy 71.456474 -363.376977) (xy 71.51079 -363.324089) (xy 71.570419 -363.277274) (xy 71.634687 -363.237062)
			(xy 71.702864 -363.20391) (xy 71.77418 -363.178192) (xy 71.847825 -363.1602) (xy 71.922965 -363.150138)
			(xy 71.998749 -363.148119) (xy 72.074319 -363.154168) (xy 72.148817 -363.168215) (xy 72.2214 -363.190101)
			(xy 72.291246 -363.219578) (xy 72.357563 -363.256313) (xy 72.419599 -363.299888) (xy 72.476652 -363.34981)
			(xy 72.528076 -363.405514) (xy 72.573287 -363.466369) (xy 72.611774 -363.531684) (xy 72.6431 -363.60072)
			(xy 72.66691 -363.672695) (xy 72.682935 -363.746793) (xy 72.690994 -363.822174) (xy 72.691498 -363.86008)
			(xy 73.807577 -363.86008) (xy 73.811612 -363.784376) (xy 73.823671 -363.709531) (xy 73.843617 -363.63639)
			(xy 73.871224 -363.565785) (xy 73.90618 -363.498514) (xy 73.948088 -363.435339) (xy 73.996474 -363.376977)
			(xy 74.05079 -363.324089) (xy 74.110419 -363.277274) (xy 74.174687 -363.237062) (xy 74.242864 -363.20391)
			(xy 74.31418 -363.178192) (xy 74.387825 -363.1602) (xy 74.462965 -363.150138) (xy 74.538749 -363.148119)
			(xy 74.614319 -363.154168) (xy 74.688817 -363.168215) (xy 74.7614 -363.190101) (xy 74.831246 -363.219578)
			(xy 74.897563 -363.256313) (xy 74.959599 -363.299888) (xy 75.016652 -363.34981) (xy 75.068076 -363.405514)
			(xy 75.113287 -363.466369) (xy 75.151774 -363.531684) (xy 75.1831 -363.60072) (xy 75.20691 -363.672695)
			(xy 75.222935 -363.746793) (xy 75.230994 -363.822174) (xy 75.231498 -363.86008) (xy 76.347577 -363.86008)
			(xy 76.351612 -363.784376) (xy 76.363671 -363.709531) (xy 76.383617 -363.63639) (xy 76.411224 -363.565785)
			(xy 76.44618 -363.498514) (xy 76.488088 -363.435339) (xy 76.536474 -363.376977) (xy 76.59079 -363.324089)
			(xy 76.650419 -363.277274) (xy 76.714687 -363.237062) (xy 76.782864 -363.20391) (xy 76.85418 -363.178192)
			(xy 76.927825 -363.1602) (xy 77.002965 -363.150138) (xy 77.078749 -363.148119) (xy 77.154319 -363.154168)
			(xy 77.228817 -363.168215) (xy 77.3014 -363.190101) (xy 77.371246 -363.219578) (xy 77.437563 -363.256313)
			(xy 77.499599 -363.299888) (xy 77.556652 -363.34981) (xy 77.608076 -363.405514) (xy 77.653287 -363.466369)
			(xy 77.691774 -363.531684) (xy 77.7231 -363.60072) (xy 77.74691 -363.672695) (xy 77.762935 -363.746793)
			(xy 77.770994 -363.822174) (xy 77.771498 -363.86008) (xy 78.887577 -363.86008) (xy 78.891612 -363.784376)
			(xy 78.903671 -363.709531) (xy 78.923617 -363.63639) (xy 78.951224 -363.565785) (xy 78.98618 -363.498514)
			(xy 79.028088 -363.435339) (xy 79.076474 -363.376977) (xy 79.13079 -363.324089) (xy 79.190419 -363.277274)
			(xy 79.254687 -363.237062) (xy 79.322864 -363.20391) (xy 79.39418 -363.178192) (xy 79.467825 -363.1602)
			(xy 79.542965 -363.150138) (xy 79.618749 -363.148119) (xy 79.694319 -363.154168) (xy 79.768817 -363.168215)
			(xy 79.8414 -363.190101) (xy 79.911246 -363.219578) (xy 79.977563 -363.256313) (xy 80.039599 -363.299888)
			(xy 80.096652 -363.34981) (xy 80.148076 -363.405514) (xy 80.193287 -363.466369) (xy 80.231774 -363.531684)
			(xy 80.2631 -363.60072) (xy 80.28691 -363.672695) (xy 80.302935 -363.746793) (xy 80.310994 -363.822174)
			(xy 80.311498 -363.86008) (xy 81.427577 -363.86008) (xy 81.431612 -363.784376) (xy 81.443671 -363.709531)
			(xy 81.463617 -363.63639) (xy 81.491224 -363.565785) (xy 81.52618 -363.498514) (xy 81.568088 -363.435339)
			(xy 81.616474 -363.376977) (xy 81.67079 -363.324089) (xy 81.730419 -363.277274) (xy 81.794687 -363.237062)
			(xy 81.862864 -363.20391) (xy 81.93418 -363.178192) (xy 82.007825 -363.1602) (xy 82.082965 -363.150138)
			(xy 82.158749 -363.148119) (xy 82.234319 -363.154168) (xy 82.308817 -363.168215) (xy 82.3814 -363.190101)
			(xy 82.451246 -363.219578) (xy 82.517563 -363.256313) (xy 82.579599 -363.299888) (xy 82.636652 -363.34981)
			(xy 82.688076 -363.405514) (xy 82.733287 -363.466369) (xy 82.771774 -363.531684) (xy 82.8031 -363.60072)
			(xy 82.82691 -363.672695) (xy 82.842935 -363.746793) (xy 82.850994 -363.822174) (xy 82.851498 -363.86008)
			(xy 82.850994 -363.897986) (xy 82.842935 -363.973367) (xy 82.82691 -364.047465) (xy 82.8031 -364.11944)
			(xy 82.771774 -364.188476) (xy 82.733287 -364.253791) (xy 82.688076 -364.314646) (xy 82.636652 -364.37035)
			(xy 82.585544 -364.41507) (xy 84.927697 -364.41507) (xy 84.931732 -364.339366) (xy 84.943791 -364.264521)
			(xy 84.963737 -364.19138) (xy 84.991344 -364.120775) (xy 85.0263 -364.053504) (xy 85.068208 -363.990329)
			(xy 85.116594 -363.931967) (xy 85.17091 -363.879079) (xy 85.230539 -363.832264) (xy 85.294807 -363.792052)
			(xy 85.362984 -363.7589) (xy 85.4343 -363.733182) (xy 85.507945 -363.71519) (xy 85.583085 -363.705128)
			(xy 85.658869 -363.703109) (xy 85.734439 -363.709158) (xy 85.808937 -363.723205) (xy 85.88152 -363.745091)
			(xy 85.951366 -363.774568) (xy 86.017683 -363.811303) (xy 86.079719 -363.854878) (xy 86.136772 -363.9048)
			(xy 86.188196 -363.960504) (xy 86.233407 -364.021359) (xy 86.271894 -364.086674) (xy 86.30322 -364.15571)
			(xy 86.32703 -364.227685) (xy 86.343055 -364.301783) (xy 86.351114 -364.377164) (xy 86.351618 -364.41507)
			(xy 87.467697 -364.41507) (xy 87.471732 -364.339366) (xy 87.483791 -364.264521) (xy 87.503737 -364.19138)
			(xy 87.531344 -364.120775) (xy 87.5663 -364.053504) (xy 87.608208 -363.990329) (xy 87.656594 -363.931967)
			(xy 87.71091 -363.879079) (xy 87.770539 -363.832264) (xy 87.834807 -363.792052) (xy 87.902984 -363.7589)
			(xy 87.9743 -363.733182) (xy 88.047945 -363.71519) (xy 88.123085 -363.705128) (xy 88.198869 -363.703109)
			(xy 88.274439 -363.709158) (xy 88.348937 -363.723205) (xy 88.42152 -363.745091) (xy 88.491366 -363.774568)
			(xy 88.557683 -363.811303) (xy 88.619719 -363.854878) (xy 88.676772 -363.9048) (xy 88.728196 -363.960504)
			(xy 88.773407 -364.021359) (xy 88.811894 -364.086674) (xy 88.84322 -364.15571) (xy 88.86703 -364.227685)
			(xy 88.883055 -364.301783) (xy 88.891114 -364.377164) (xy 88.891618 -364.41507) (xy 90.007697 -364.41507)
			(xy 90.011732 -364.339366) (xy 90.023791 -364.264521) (xy 90.043737 -364.19138) (xy 90.071344 -364.120775)
			(xy 90.1063 -364.053504) (xy 90.148208 -363.990329) (xy 90.196594 -363.931967) (xy 90.25091 -363.879079)
			(xy 90.310539 -363.832264) (xy 90.374807 -363.792052) (xy 90.442984 -363.7589) (xy 90.5143 -363.733182)
			(xy 90.587945 -363.71519) (xy 90.663085 -363.705128) (xy 90.738869 -363.703109) (xy 90.814439 -363.709158)
			(xy 90.888937 -363.723205) (xy 90.96152 -363.745091) (xy 91.031366 -363.774568) (xy 91.097683 -363.811303)
			(xy 91.159719 -363.854878) (xy 91.165664 -363.86008) (xy 93.154506 -363.86008) (xy 93.158522 -363.74381)
			(xy 93.170549 -363.628095) (xy 93.190531 -363.513485) (xy 93.218373 -363.400526) (xy 93.253942 -363.289758)
			(xy 93.297068 -363.181707) (xy 93.347545 -363.076889) (xy 93.405134 -362.975804) (xy 93.46956 -362.878932)
			(xy 93.540515 -362.786736) (xy 93.617662 -362.699655) (xy 93.700633 -362.618104) (xy 93.789033 -362.542472)
			(xy 93.88244 -362.473118) (xy 93.980409 -362.410375) (xy 94.082473 -362.354539) (xy 94.188147 -362.305878)
			(xy 94.296926 -362.264624) (xy 94.408291 -362.230973) (xy 94.521714 -362.205085) (xy 94.636651 -362.187084)
			(xy 94.752557 -362.177055) (xy 94.868879 -362.175047) (xy 94.985062 -362.181069) (xy 95.100553 -362.195092)
			(xy 95.214801 -362.21705) (xy 95.327262 -362.246837) (xy 95.4374 -362.284312) (xy 95.54469 -362.329297)
			(xy 95.648621 -362.381576) (xy 95.748697 -362.440901) (xy 95.844443 -362.506989) (xy 95.9354 -362.579525)
			(xy 96.021136 -362.658164) (xy 96.101243 -362.74253) (xy 96.175339 -362.832222) (xy 96.243069 -362.926812)
			(xy 96.304113 -363.02585) (xy 96.358178 -363.128863) (xy 96.405008 -363.23536) (xy 96.444379 -363.344835)
			(xy 96.476103 -363.456765) (xy 96.500029 -363.570617) (xy 96.516043 -363.685849) (xy 96.52407 -363.801911)
			(xy 96.524572 -363.86008) (xy 96.52407 -363.918249) (xy 96.516043 -364.034311) (xy 96.500029 -364.149543)
			(xy 96.476103 -364.263395) (xy 96.444379 -364.375325) (xy 96.405008 -364.4848) (xy 96.358178 -364.591297)
			(xy 96.304113 -364.69431) (xy 96.243069 -364.793348) (xy 96.175339 -364.887938) (xy 96.101243 -364.97763)
			(xy 96.021136 -365.061996) (xy 95.9354 -365.140635) (xy 95.844443 -365.213171) (xy 95.748697 -365.279259)
			(xy 95.648621 -365.338584) (xy 95.54469 -365.390863) (xy 95.4374 -365.435848) (xy 95.327262 -365.473323)
			(xy 95.214801 -365.50311) (xy 95.100553 -365.525068) (xy 94.985062 -365.539091) (xy 94.868879 -365.545113)
			(xy 94.752557 -365.543105) (xy 94.636651 -365.533076) (xy 94.521714 -365.515075) (xy 94.408291 -365.489187)
			(xy 94.296926 -365.455536) (xy 94.188147 -365.414282) (xy 94.082473 -365.365621) (xy 93.980409 -365.309785)
			(xy 93.88244 -365.247042) (xy 93.789033 -365.177688) (xy 93.700633 -365.102056) (xy 93.617662 -365.020505)
			(xy 93.540515 -364.933424) (xy 93.46956 -364.841228) (xy 93.405134 -364.744356) (xy 93.347545 -364.643271)
			(xy 93.297068 -364.538453) (xy 93.253942 -364.430402) (xy 93.218373 -364.319634) (xy 93.190531 -364.206675)
			(xy 93.170549 -364.092065) (xy 93.158522 -363.97635) (xy 93.154506 -363.86008) (xy 91.165664 -363.86008)
			(xy 91.216772 -363.9048) (xy 91.268196 -363.960504) (xy 91.313407 -364.021359) (xy 91.351894 -364.086674)
			(xy 91.38322 -364.15571) (xy 91.40703 -364.227685) (xy 91.423055 -364.301783) (xy 91.431114 -364.377164)
			(xy 91.431618 -364.41507) (xy 91.431114 -364.452976) (xy 91.423055 -364.528357) (xy 91.40703 -364.602455)
			(xy 91.38322 -364.67443) (xy 91.351894 -364.743466) (xy 91.313407 -364.808781) (xy 91.268196 -364.869636)
			(xy 91.216772 -364.92534) (xy 91.159719 -364.975262) (xy 91.097683 -365.018837) (xy 91.031366 -365.055572)
			(xy 90.96152 -365.085049) (xy 90.888937 -365.106935) (xy 90.814439 -365.120982) (xy 90.738869 -365.127031)
			(xy 90.663085 -365.125012) (xy 90.587945 -365.11495) (xy 90.5143 -365.096958) (xy 90.442984 -365.07124)
			(xy 90.374807 -365.038088) (xy 90.310539 -364.997876) (xy 90.25091 -364.951061) (xy 90.196594 -364.898173)
			(xy 90.148208 -364.839811) (xy 90.1063 -364.776636) (xy 90.071344 -364.709365) (xy 90.043737 -364.63876)
			(xy 90.023791 -364.565619) (xy 90.011732 -364.490774) (xy 90.007697 -364.41507) (xy 88.891618 -364.41507)
			(xy 88.891114 -364.452976) (xy 88.883055 -364.528357) (xy 88.86703 -364.602455) (xy 88.84322 -364.67443)
			(xy 88.811894 -364.743466) (xy 88.773407 -364.808781) (xy 88.728196 -364.869636) (xy 88.676772 -364.92534)
			(xy 88.619719 -364.975262) (xy 88.557683 -365.018837) (xy 88.491366 -365.055572) (xy 88.42152 -365.085049)
			(xy 88.348937 -365.106935) (xy 88.274439 -365.120982) (xy 88.198869 -365.127031) (xy 88.123085 -365.125012)
			(xy 88.047945 -365.11495) (xy 87.9743 -365.096958) (xy 87.902984 -365.07124) (xy 87.834807 -365.038088)
			(xy 87.770539 -364.997876) (xy 87.71091 -364.951061) (xy 87.656594 -364.898173) (xy 87.608208 -364.839811)
			(xy 87.5663 -364.776636) (xy 87.531344 -364.709365) (xy 87.503737 -364.63876) (xy 87.483791 -364.565619)
			(xy 87.471732 -364.490774) (xy 87.467697 -364.41507) (xy 86.351618 -364.41507) (xy 86.351114 -364.452976)
			(xy 86.343055 -364.528357) (xy 86.32703 -364.602455) (xy 86.30322 -364.67443) (xy 86.271894 -364.743466)
			(xy 86.233407 -364.808781) (xy 86.188196 -364.869636) (xy 86.136772 -364.92534) (xy 86.079719 -364.975262)
			(xy 86.017683 -365.018837) (xy 85.951366 -365.055572) (xy 85.88152 -365.085049) (xy 85.808937 -365.106935)
			(xy 85.734439 -365.120982) (xy 85.658869 -365.127031) (xy 85.583085 -365.125012) (xy 85.507945 -365.11495)
			(xy 85.4343 -365.096958) (xy 85.362984 -365.07124) (xy 85.294807 -365.038088) (xy 85.230539 -364.997876)
			(xy 85.17091 -364.951061) (xy 85.116594 -364.898173) (xy 85.068208 -364.839811) (xy 85.0263 -364.776636)
			(xy 84.991344 -364.709365) (xy 84.963737 -364.63876) (xy 84.943791 -364.565619) (xy 84.931732 -364.490774)
			(xy 84.927697 -364.41507) (xy 82.585544 -364.41507) (xy 82.579599 -364.420272) (xy 82.517563 -364.463847)
			(xy 82.451246 -364.500582) (xy 82.3814 -364.530059) (xy 82.308817 -364.551945) (xy 82.234319 -364.565992)
			(xy 82.158749 -364.572041) (xy 82.082965 -364.570022) (xy 82.007825 -364.55996) (xy 81.93418 -364.541968)
			(xy 81.862864 -364.51625) (xy 81.794687 -364.483098) (xy 81.730419 -364.442886) (xy 81.67079 -364.396071)
			(xy 81.616474 -364.343183) (xy 81.568088 -364.284821) (xy 81.52618 -364.221646) (xy 81.491224 -364.154375)
			(xy 81.463617 -364.08377) (xy 81.443671 -364.010629) (xy 81.431612 -363.935784) (xy 81.427577 -363.86008)
			(xy 80.311498 -363.86008) (xy 80.310994 -363.897986) (xy 80.302935 -363.973367) (xy 80.28691 -364.047465)
			(xy 80.2631 -364.11944) (xy 80.231774 -364.188476) (xy 80.193287 -364.253791) (xy 80.148076 -364.314646)
			(xy 80.096652 -364.37035) (xy 80.039599 -364.420272) (xy 79.977563 -364.463847) (xy 79.911246 -364.500582)
			(xy 79.8414 -364.530059) (xy 79.768817 -364.551945) (xy 79.694319 -364.565992) (xy 79.618749 -364.572041)
			(xy 79.542965 -364.570022) (xy 79.467825 -364.55996) (xy 79.39418 -364.541968) (xy 79.322864 -364.51625)
			(xy 79.254687 -364.483098) (xy 79.190419 -364.442886) (xy 79.13079 -364.396071) (xy 79.076474 -364.343183)
			(xy 79.028088 -364.284821) (xy 78.98618 -364.221646) (xy 78.951224 -364.154375) (xy 78.923617 -364.08377)
			(xy 78.903671 -364.010629) (xy 78.891612 -363.935784) (xy 78.887577 -363.86008) (xy 77.771498 -363.86008)
			(xy 77.770994 -363.897986) (xy 77.762935 -363.973367) (xy 77.74691 -364.047465) (xy 77.7231 -364.11944)
			(xy 77.691774 -364.188476) (xy 77.653287 -364.253791) (xy 77.608076 -364.314646) (xy 77.556652 -364.37035)
			(xy 77.499599 -364.420272) (xy 77.437563 -364.463847) (xy 77.371246 -364.500582) (xy 77.3014 -364.530059)
			(xy 77.228817 -364.551945) (xy 77.154319 -364.565992) (xy 77.078749 -364.572041) (xy 77.002965 -364.570022)
			(xy 76.927825 -364.55996) (xy 76.85418 -364.541968) (xy 76.782864 -364.51625) (xy 76.714687 -364.483098)
			(xy 76.650419 -364.442886) (xy 76.59079 -364.396071) (xy 76.536474 -364.343183) (xy 76.488088 -364.284821)
			(xy 76.44618 -364.221646) (xy 76.411224 -364.154375) (xy 76.383617 -364.08377) (xy 76.363671 -364.010629)
			(xy 76.351612 -363.935784) (xy 76.347577 -363.86008) (xy 75.231498 -363.86008) (xy 75.230994 -363.897986)
			(xy 75.222935 -363.973367) (xy 75.20691 -364.047465) (xy 75.1831 -364.11944) (xy 75.151774 -364.188476)
			(xy 75.113287 -364.253791) (xy 75.068076 -364.314646) (xy 75.016652 -364.37035) (xy 74.959599 -364.420272)
			(xy 74.897563 -364.463847) (xy 74.831246 -364.500582) (xy 74.7614 -364.530059) (xy 74.688817 -364.551945)
			(xy 74.614319 -364.565992) (xy 74.538749 -364.572041) (xy 74.462965 -364.570022) (xy 74.387825 -364.55996)
			(xy 74.31418 -364.541968) (xy 74.242864 -364.51625) (xy 74.174687 -364.483098) (xy 74.110419 -364.442886)
			(xy 74.05079 -364.396071) (xy 73.996474 -364.343183) (xy 73.948088 -364.284821) (xy 73.90618 -364.221646)
			(xy 73.871224 -364.154375) (xy 73.843617 -364.08377) (xy 73.823671 -364.010629) (xy 73.811612 -363.935784)
			(xy 73.807577 -363.86008) (xy 72.691498 -363.86008) (xy 72.690994 -363.897986) (xy 72.682935 -363.973367)
			(xy 72.66691 -364.047465) (xy 72.6431 -364.11944) (xy 72.611774 -364.188476) (xy 72.573287 -364.253791)
			(xy 72.528076 -364.314646) (xy 72.476652 -364.37035) (xy 72.419599 -364.420272) (xy 72.357563 -364.463847)
			(xy 72.291246 -364.500582) (xy 72.2214 -364.530059) (xy 72.148817 -364.551945) (xy 72.074319 -364.565992)
			(xy 71.998749 -364.572041) (xy 71.922965 -364.570022) (xy 71.847825 -364.55996) (xy 71.77418 -364.541968)
			(xy 71.702864 -364.51625) (xy 71.634687 -364.483098) (xy 71.570419 -364.442886) (xy 71.51079 -364.396071)
			(xy 71.456474 -364.343183) (xy 71.408088 -364.284821) (xy 71.36618 -364.221646) (xy 71.331224 -364.154375)
			(xy 71.303617 -364.08377) (xy 71.283671 -364.010629) (xy 71.271612 -363.935784) (xy 71.267577 -363.86008)
			(xy 70.151498 -363.86008) (xy 70.150994 -363.897986) (xy 70.142935 -363.973367) (xy 70.12691 -364.047465)
			(xy 70.1031 -364.11944) (xy 70.071774 -364.188476) (xy 70.033287 -364.253791) (xy 69.988076 -364.314646)
			(xy 69.936652 -364.37035) (xy 69.879599 -364.420272) (xy 69.817563 -364.463847) (xy 69.751246 -364.500582)
			(xy 69.6814 -364.530059) (xy 69.608817 -364.551945) (xy 69.534319 -364.565992) (xy 69.458749 -364.572041)
			(xy 69.382965 -364.570022) (xy 69.307825 -364.55996) (xy 69.23418 -364.541968) (xy 69.162864 -364.51625)
			(xy 69.094687 -364.483098) (xy 69.030419 -364.442886) (xy 68.97079 -364.396071) (xy 68.916474 -364.343183)
			(xy 68.868088 -364.284821) (xy 68.82618 -364.221646) (xy 68.791224 -364.154375) (xy 68.763617 -364.08377)
			(xy 68.743671 -364.010629) (xy 68.731612 -363.935784) (xy 68.727577 -363.86008) (xy 67.611498 -363.86008)
			(xy 67.610994 -363.897986) (xy 67.602935 -363.973367) (xy 67.58691 -364.047465) (xy 67.5631 -364.11944)
			(xy 67.531774 -364.188476) (xy 67.493287 -364.253791) (xy 67.448076 -364.314646) (xy 67.396652 -364.37035)
			(xy 67.339599 -364.420272) (xy 67.277563 -364.463847) (xy 67.211246 -364.500582) (xy 67.1414 -364.530059)
			(xy 67.068817 -364.551945) (xy 66.994319 -364.565992) (xy 66.918749 -364.572041) (xy 66.842965 -364.570022)
			(xy 66.767825 -364.55996) (xy 66.69418 -364.541968) (xy 66.622864 -364.51625) (xy 66.554687 -364.483098)
			(xy 66.490419 -364.442886) (xy 66.43079 -364.396071) (xy 66.376474 -364.343183) (xy 66.328088 -364.284821)
			(xy 66.28618 -364.221646) (xy 66.251224 -364.154375) (xy 66.223617 -364.08377) (xy 66.203671 -364.010629)
			(xy 66.191612 -363.935784) (xy 66.187577 -363.86008) (xy 65.071498 -363.86008) (xy 65.070994 -363.897986)
			(xy 65.062935 -363.973367) (xy 65.04691 -364.047465) (xy 65.0231 -364.11944) (xy 64.991774 -364.188476)
			(xy 64.953287 -364.253791) (xy 64.908076 -364.314646) (xy 64.856652 -364.37035) (xy 64.799599 -364.420272)
			(xy 64.737563 -364.463847) (xy 64.671246 -364.500582) (xy 64.6014 -364.530059) (xy 64.528817 -364.551945)
			(xy 64.454319 -364.565992) (xy 64.378749 -364.572041) (xy 64.302965 -364.570022) (xy 64.227825 -364.55996)
			(xy 64.15418 -364.541968) (xy 64.082864 -364.51625) (xy 64.014687 -364.483098) (xy 63.950419 -364.442886)
			(xy 63.89079 -364.396071) (xy 63.836474 -364.343183) (xy 63.788088 -364.284821) (xy 63.74618 -364.221646)
			(xy 63.711224 -364.154375) (xy 63.683617 -364.08377) (xy 63.663671 -364.010629) (xy 63.651612 -363.935784)
			(xy 63.647577 -363.86008) (xy 43.833925 -363.86008) (xy 43.811275 -363.900176) (xy 43.732291 -364.02379)
			(xy 43.646704 -364.142927) (xy 43.554768 -364.257237) (xy 43.456755 -364.36638) (xy 43.352954 -364.470035)
			(xy 43.243672 -364.567894) (xy 43.129233 -364.659668) (xy 43.009974 -364.745087) (xy 42.886249 -364.823897)
			(xy 42.758423 -364.895865) (xy 42.626874 -364.960779) (xy 42.491992 -365.018446) (xy 42.354174 -365.068697)
			(xy 42.213828 -365.111382) (xy 42.07137 -365.146375) (xy 41.92722 -365.173574) (xy 41.781805 -365.192897)
			(xy 41.635555 -365.204287) (xy 41.488902 -365.207712) (xy 41.342279 -365.203159) (xy 41.269158 -365.19739)
			(xy 41.24582 -365.195936) (xy 41.199295 -365.200555) (xy 41.154398 -365.213604) (xy 41.112646 -365.234645)
			(xy 41.075446 -365.262966) (xy 41.044052 -365.297613) (xy 41.019525 -365.337417) (xy 41.00269 -365.381036)
			(xy 40.994117 -365.426997) (xy 40.993568 -365.450374) (xy 40.993568 -367.13414) (xy 41.065704 -367.248186)
			(xy 41.0972 -367.264188) (xy 41.145456 -367.289024) (xy 41.238561 -367.344813) (xy 41.32731 -367.407301)
			(xy 41.41122 -367.476148) (xy 41.489837 -367.550983) (xy 41.562736 -367.631399) (xy 41.629521 -367.716961)
			(xy 41.689829 -367.807204) (xy 41.743334 -367.90164) (xy 41.789747 -367.999756) (xy 41.828815 -368.101022)
			(xy 41.860326 -368.204887) (xy 41.88411 -368.310789) (xy 41.900038 -368.418154) (xy 41.908024 -368.5264)
			(xy 41.908024 -368.63494) (xy 41.900038 -368.743186) (xy 41.88411 -368.850551) (xy 41.860326 -368.956453)
			(xy 41.828815 -369.060318) (xy 41.789747 -369.161584) (xy 41.743334 -369.2597) (xy 41.689829 -369.354136)
			(xy 41.629521 -369.444379) (xy 41.562736 -369.529941) (xy 41.489837 -369.610357) (xy 41.41122 -369.685192)
			(xy 41.32731 -369.754039) (xy 41.238561 -369.816527) (xy 41.145456 -369.872316) (xy 41.0972 -369.897152)
			(xy 41.065704 -369.913154) (xy 40.993568 -370.0272) (xy 40.993568 -370.607111) (xy 74.013351 -370.607111)
			(xy 74.017238 -370.55275) (xy 74.028822 -370.499495) (xy 74.047868 -370.448431) (xy 74.073987 -370.400598)
			(xy 74.106649 -370.356969) (xy 74.145187 -370.318433) (xy 74.188818 -370.285774) (xy 74.236653 -370.259658)
			(xy 74.287718 -370.240615) (xy 74.340973 -370.229034) (xy 74.395334 -370.225151) (xy 74.449695 -370.229044)
			(xy 74.502948 -370.240635) (xy 74.55401 -370.259686) (xy 74.60184 -370.285812) (xy 74.62393 -370.301774)
			(xy 74.642942 -370.31537) (xy 74.684825 -370.336102) (xy 74.729793 -370.348828) (xy 74.77633 -370.353118)
			(xy 74.822867 -370.348828) (xy 74.867835 -370.336102) (xy 74.909718 -370.31537) (xy 74.92873 -370.301774)
			(xy 74.950834 -370.285841) (xy 74.998657 -370.259727) (xy 75.049709 -370.240685) (xy 75.102951 -370.229103)
			(xy 75.1573 -370.225216) (xy 75.211649 -370.229103) (xy 75.264891 -370.240685) (xy 75.315943 -370.259727)
			(xy 75.363765 -370.285841) (xy 75.407385 -370.318494) (xy 75.445913 -370.357023) (xy 75.478565 -370.400644)
			(xy 75.504677 -370.448467) (xy 75.523718 -370.499519) (xy 75.535298 -370.552762) (xy 75.539184 -370.607111)
			(xy 76.088891 -370.607111) (xy 76.092776 -370.552759) (xy 76.104358 -370.499513) (xy 76.123399 -370.448457)
			(xy 76.149513 -370.400631) (xy 76.182167 -370.357008) (xy 76.220698 -370.318477) (xy 76.264319 -370.285821)
			(xy 76.312144 -370.259705) (xy 76.363199 -370.240662) (xy 76.416445 -370.229078) (xy 76.470797 -370.225191)
			(xy 76.525149 -370.229078) (xy 76.578395 -370.24066) (xy 76.62945 -370.259703) (xy 76.677275 -370.285817)
			(xy 76.699364 -370.301774) (xy 76.718376 -370.31537) (xy 76.760259 -370.336102) (xy 76.805227 -370.348828)
			(xy 76.851764 -370.353118) (xy 76.898301 -370.348828) (xy 76.943269 -370.336102) (xy 76.985152 -370.31537)
			(xy 77.004164 -370.301774) (xy 77.02627 -370.285835) (xy 77.074097 -370.259711) (xy 77.125155 -370.24066)
			(xy 77.178405 -370.22907) (xy 77.232762 -370.225176) (xy 77.28712 -370.229059) (xy 77.340373 -370.240639)
			(xy 77.391435 -370.25968) (xy 77.439267 -370.285794) (xy 77.482895 -370.318451) (xy 77.521431 -370.356985)
			(xy 77.554091 -370.400611) (xy 77.580209 -370.448441) (xy 77.599254 -370.499502) (xy 77.610837 -370.552753)
			(xy 77.614724 -370.607111) (xy 77.614677 -370.607774) (xy 78.313094 -370.607774) (xy 78.316985 -370.553418)
			(xy 78.328574 -370.50017) (xy 78.347623 -370.449113) (xy 78.373744 -370.401288) (xy 78.406407 -370.357667)
			(xy 78.444946 -370.319139) (xy 78.488576 -370.286488) (xy 78.536409 -370.260379) (xy 78.587471 -370.241344)
			(xy 78.640722 -370.22977) (xy 78.695078 -370.225894) (xy 78.749433 -370.229793) (xy 78.80268 -370.241388)
			(xy 78.853734 -370.260444) (xy 78.901556 -370.286572) (xy 78.923642 -370.302536) (xy 78.942654 -370.316132)
			(xy 78.984537 -370.336864) (xy 79.029505 -370.34959) (xy 79.076042 -370.35388) (xy 79.122579 -370.34959)
			(xy 79.167547 -370.336864) (xy 79.20943 -370.316132) (xy 79.228442 -370.302536) (xy 79.250488 -370.28652)
			(xy 79.298313 -370.260401) (xy 79.349369 -370.241353) (xy 79.402616 -370.229765) (xy 79.456969 -370.225873)
			(xy 79.511324 -370.229757) (xy 79.564573 -370.241336) (xy 79.615631 -370.260375) (xy 79.663461 -370.286487)
			(xy 79.707087 -370.31914) (xy 79.745622 -370.35767) (xy 79.778282 -370.401291) (xy 79.804401 -370.449117)
			(xy 79.823448 -370.500173) (xy 79.835035 -370.55342) (xy 79.838927 -370.607774) (xy 79.835043 -370.662128)
			(xy 79.823463 -370.715377) (xy 79.804423 -370.766435) (xy 79.778311 -370.814264) (xy 79.745657 -370.85789)
			(xy 79.707127 -370.896425) (xy 79.663505 -370.929084) (xy 79.615679 -370.955203) (xy 79.564623 -370.974249)
			(xy 79.511376 -370.985836) (xy 79.457022 -370.989727) (xy 79.402668 -370.985842) (xy 79.349419 -370.974262)
			(xy 79.298361 -370.955221) (xy 79.250532 -370.929108) (xy 79.228442 -370.913152) (xy 79.20943 -370.899556)
			(xy 79.167547 -370.878824) (xy 79.122579 -370.866098) (xy 79.076042 -370.861808) (xy 79.029505 -370.866098)
			(xy 78.984537 -370.878824) (xy 78.942654 -370.899556) (xy 78.923642 -370.913152) (xy 78.901512 -370.929056)
			(xy 78.853686 -370.955178) (xy 78.802629 -370.974227) (xy 78.749381 -370.985815) (xy 78.695026 -370.989706)
			(xy 78.64067 -370.985822) (xy 78.58742 -370.974241) (xy 78.536361 -370.955199) (xy 78.488531 -370.929084)
			(xy 78.444906 -370.896427) (xy 78.406373 -370.857893) (xy 78.373716 -370.814268) (xy 78.347601 -370.766439)
			(xy 78.328559 -370.715379) (xy 78.316978 -370.662129) (xy 78.313094 -370.607774) (xy 77.614677 -370.607774)
			(xy 77.610834 -370.661468) (xy 77.599248 -370.714719) (xy 77.5802 -370.765779) (xy 77.554079 -370.813607)
			(xy 77.521417 -370.857232) (xy 77.482879 -370.895763) (xy 77.439248 -370.928417) (xy 77.391415 -370.954529)
			(xy 77.340352 -370.973567) (xy 77.287099 -370.985144) (xy 77.232741 -370.989024) (xy 77.178384 -370.985127)
			(xy 77.125134 -370.973534) (xy 77.074077 -370.95448) (xy 77.026252 -370.928353) (xy 77.004164 -370.91239)
			(xy 76.985152 -370.898794) (xy 76.943269 -370.878062) (xy 76.898301 -370.865336) (xy 76.851764 -370.861046)
			(xy 76.805227 -370.865336) (xy 76.760259 -370.878062) (xy 76.718376 -370.898794) (xy 76.699364 -370.91239)
			(xy 76.677294 -370.928371) (xy 76.629469 -370.954488) (xy 76.578415 -370.973534) (xy 76.52517 -370.985119)
			(xy 76.470818 -370.989009) (xy 76.416466 -370.985125) (xy 76.36322 -370.973544) (xy 76.312164 -370.954504)
			(xy 76.264337 -370.928391) (xy 76.220714 -370.895738) (xy 76.182181 -370.857208) (xy 76.149525 -370.813587)
			(xy 76.123408 -370.765763) (xy 76.104364 -370.714708) (xy 76.09278 -370.661463) (xy 76.088891 -370.607111)
			(xy 75.539184 -370.607111) (xy 75.535295 -370.661459) (xy 75.523712 -370.714701) (xy 75.504668 -370.765753)
			(xy 75.478553 -370.813575) (xy 75.445898 -370.857193) (xy 75.407368 -370.89572) (xy 75.363747 -370.928371)
			(xy 75.315923 -370.954482) (xy 75.26487 -370.973521) (xy 75.211627 -370.9851) (xy 75.157278 -370.988984)
			(xy 75.10293 -370.985094) (xy 75.049688 -370.973508) (xy 74.998637 -370.954464) (xy 74.950816 -370.928347)
			(xy 74.92873 -370.91239) (xy 74.909718 -370.898794) (xy 74.867835 -370.878062) (xy 74.822867 -370.865336)
			(xy 74.77633 -370.861046) (xy 74.729793 -370.865336) (xy 74.684825 -370.878062) (xy 74.642942 -370.898794)
			(xy 74.62393 -370.91239) (xy 74.601858 -370.928377) (xy 74.554029 -370.954505) (xy 74.502969 -370.973559)
			(xy 74.449716 -370.985153) (xy 74.395356 -370.989049) (xy 74.340994 -370.985169) (xy 74.287738 -370.973591)
			(xy 74.236672 -370.954551) (xy 74.188836 -370.928437) (xy 74.145203 -370.895781) (xy 74.106663 -370.857247)
			(xy 74.073999 -370.81362) (xy 74.047877 -370.765788) (xy 74.028828 -370.714726) (xy 74.017241 -370.661472)
			(xy 74.013351 -370.607111) (xy 40.993568 -370.607111) (xy 40.993568 -372.363672) (xy 74.013402 -372.363672)
			(xy 74.017294 -372.309319) (xy 74.028882 -372.256073) (xy 74.04793 -372.205018) (xy 74.074051 -372.157194)
			(xy 74.106712 -372.113574) (xy 74.14525 -372.075047) (xy 74.188878 -372.042397) (xy 74.236709 -372.016289)
			(xy 74.287769 -371.997254) (xy 74.341018 -371.98568) (xy 74.395373 -371.981802) (xy 74.449726 -371.9857)
			(xy 74.502971 -371.997295) (xy 74.554023 -372.016349) (xy 74.601844 -372.042475) (xy 74.62393 -372.058438)
			(xy 74.642942 -372.072034) (xy 74.684825 -372.092766) (xy 74.729793 -372.105492) (xy 74.77633 -372.109782)
			(xy 74.822867 -372.105492) (xy 74.867835 -372.092766) (xy 74.909718 -372.072034) (xy 74.92873 -372.058438)
			(xy 74.950774 -372.042419) (xy 74.9986 -372.016297) (xy 75.049657 -371.997247) (xy 75.102906 -371.985658)
			(xy 75.157261 -371.981765) (xy 75.211618 -371.985647) (xy 75.264869 -371.997225) (xy 75.315929 -372.016265)
			(xy 75.363761 -372.042377) (xy 75.407389 -372.075031) (xy 75.445926 -372.113561) (xy 75.478587 -372.157184)
			(xy 75.504708 -372.20501) (xy 75.523756 -372.256068) (xy 75.535344 -372.309317) (xy 75.539235 -372.363672)
			(xy 76.088942 -372.363672) (xy 76.092833 -372.309328) (xy 76.104418 -372.25609) (xy 76.123462 -372.205043)
			(xy 76.149577 -372.157226) (xy 76.182231 -372.113613) (xy 76.22076 -372.07509) (xy 76.264379 -372.042443)
			(xy 76.312201 -372.016336) (xy 76.363251 -371.9973) (xy 76.41649 -371.985724) (xy 76.470835 -371.981842)
			(xy 76.52518 -371.985734) (xy 76.578417 -371.99732) (xy 76.629463 -372.016365) (xy 76.67728 -372.042481)
			(xy 76.699364 -372.058438) (xy 76.718376 -372.072034) (xy 76.760259 -372.092766) (xy 76.805227 -372.105492)
			(xy 76.851764 -372.109782) (xy 76.898301 -372.105492) (xy 76.943269 -372.092766) (xy 76.985152 -372.072034)
			(xy 77.004164 -372.058438) (xy 77.02621 -372.042413) (xy 77.074041 -372.016281) (xy 77.125104 -371.997222)
			(xy 77.17836 -371.985625) (xy 77.232724 -371.981725) (xy 77.28709 -371.985603) (xy 77.34035 -371.997179)
			(xy 77.391421 -372.016217) (xy 77.439262 -372.042331) (xy 77.4829 -372.074987) (xy 77.521445 -372.113522)
			(xy 77.554113 -372.157151) (xy 77.58024 -372.204985) (xy 77.599292 -372.25605) (xy 77.610882 -372.309308)
			(xy 77.614775 -372.363672) (xy 77.614716 -372.364495) (xy 78.313065 -372.364495) (xy 78.316954 -372.310136)
			(xy 78.32854 -372.256883) (xy 78.347587 -372.205821) (xy 78.373708 -372.15799) (xy 78.406371 -372.114364)
			(xy 78.444911 -372.075831) (xy 78.488542 -372.043175) (xy 78.536377 -372.017062) (xy 78.587442 -371.998022)
			(xy 78.640696 -371.986445) (xy 78.695057 -371.982565) (xy 78.749416 -371.986461) (xy 78.802667 -371.998054)
			(xy 78.853726 -372.017109) (xy 78.901553 -372.043236) (xy 78.923642 -372.0592) (xy 78.942654 -372.072796)
			(xy 78.984537 -372.093528) (xy 79.029505 -372.106254) (xy 79.076042 -372.110544) (xy 79.122579 -372.106254)
			(xy 79.167547 -372.093528) (xy 79.20943 -372.072796) (xy 79.228442 -372.0592) (xy 79.250522 -372.043233)
			(xy 79.298345 -372.017118) (xy 79.349398 -371.998075) (xy 79.402641 -371.986491) (xy 79.456991 -371.982602)
			(xy 79.511341 -371.986488) (xy 79.564585 -371.998069) (xy 79.615639 -372.01711) (xy 79.663463 -372.043223)
			(xy 79.707085 -372.075876) (xy 79.745615 -372.114405) (xy 79.778269 -372.158025) (xy 79.804384 -372.205849)
			(xy 79.823427 -372.256902) (xy 79.83501 -372.310145) (xy 79.838898 -372.364495) (xy 79.835011 -372.418845)
			(xy 79.823429 -372.472089) (xy 79.804388 -372.523143) (xy 79.778275 -372.570967) (xy 79.745621 -372.614588)
			(xy 79.707092 -372.653117) (xy 79.663471 -372.685772) (xy 79.615648 -372.711886) (xy 79.564594 -372.730928)
			(xy 79.511351 -372.74251) (xy 79.457001 -372.746398) (xy 79.402651 -372.742511) (xy 79.349407 -372.730928)
			(xy 79.298354 -372.711886) (xy 79.25053 -372.685772) (xy 79.228442 -372.669816) (xy 79.20943 -372.65622)
			(xy 79.167547 -372.635488) (xy 79.122579 -372.622762) (xy 79.076042 -372.618472) (xy 79.029505 -372.622762)
			(xy 78.984537 -372.635488) (xy 78.942654 -372.65622) (xy 78.923642 -372.669816) (xy 78.901545 -372.685769)
			(xy 78.853717 -372.711895) (xy 78.802658 -372.730948) (xy 78.749406 -372.74254) (xy 78.695047 -372.746435)
			(xy 78.640687 -372.742554) (xy 78.587433 -372.730975) (xy 78.536368 -372.711934) (xy 78.488534 -372.68582)
			(xy 78.444903 -372.653163) (xy 78.406365 -372.614629) (xy 78.373703 -372.571002) (xy 78.347583 -372.52317)
			(xy 78.328537 -372.472108) (xy 78.316952 -372.418855) (xy 78.313065 -372.364495) (xy 77.614716 -372.364495)
			(xy 77.61089 -372.418038) (xy 77.599308 -372.471297) (xy 77.580263 -372.522365) (xy 77.554143 -372.570203)
			(xy 77.521481 -372.613836) (xy 77.482941 -372.652377) (xy 77.439308 -372.68504) (xy 77.391471 -372.71116)
			(xy 77.340403 -372.730206) (xy 77.287144 -372.741789) (xy 77.232779 -372.745675) (xy 77.178414 -372.741783)
			(xy 77.125157 -372.730194) (xy 77.074091 -372.711142) (xy 77.026256 -372.685017) (xy 77.004164 -372.669054)
			(xy 76.985152 -372.655458) (xy 76.943269 -372.634726) (xy 76.898301 -372.622) (xy 76.851764 -372.61771)
			(xy 76.805227 -372.622) (xy 76.760259 -372.634726) (xy 76.718376 -372.655458) (xy 76.699364 -372.669054)
			(xy 76.677234 -372.684949) (xy 76.629413 -372.711058) (xy 76.578364 -372.730095) (xy 76.525125 -372.741674)
			(xy 76.47078 -372.745558) (xy 76.416435 -372.741668) (xy 76.363198 -372.730084) (xy 76.31215 -372.711041)
			(xy 76.264333 -372.684927) (xy 76.220718 -372.652274) (xy 76.182195 -372.613746) (xy 76.149547 -372.570127)
			(xy 76.123439 -372.522306) (xy 76.104402 -372.471257) (xy 76.092825 -372.418017) (xy 76.088942 -372.363672)
			(xy 75.539235 -372.363672) (xy 75.535352 -372.418029) (xy 75.523772 -372.471279) (xy 75.504731 -372.522339)
			(xy 75.478617 -372.57017) (xy 75.445962 -372.613797) (xy 75.407431 -372.652333) (xy 75.363807 -372.684993)
			(xy 75.31598 -372.711112) (xy 75.264921 -372.730159) (xy 75.211673 -372.741745) (xy 75.157317 -372.745635)
			(xy 75.10296 -372.74175) (xy 75.04971 -372.730168) (xy 74.998651 -372.711126) (xy 74.950821 -372.685011)
			(xy 74.92873 -372.669054) (xy 74.909718 -372.655458) (xy 74.867835 -372.634726) (xy 74.822867 -372.622)
			(xy 74.77633 -372.61771) (xy 74.729793 -372.622) (xy 74.684825 -372.634726) (xy 74.642942 -372.655458)
			(xy 74.62393 -372.669054) (xy 74.601798 -372.684954) (xy 74.553973 -372.711074) (xy 74.502918 -372.730121)
			(xy 74.449671 -372.741707) (xy 74.395317 -372.745598) (xy 74.340964 -372.741712) (xy 74.287716 -372.730131)
			(xy 74.236659 -372.711089) (xy 74.188831 -372.684973) (xy 74.145208 -372.652317) (xy 74.106676 -372.613784)
			(xy 74.074021 -372.57016) (xy 74.047907 -372.522332) (xy 74.028866 -372.471274) (xy 74.017286 -372.418026)
			(xy 74.013402 -372.363672) (xy 40.993568 -372.363672) (xy 40.993568 -373.61114) (xy 50.797968 -373.61114)
			(xy 52.449476 -373.61114) (xy 52.449476 -374.13029) (xy 74.013378 -374.13029) (xy 74.017268 -374.075933)
			(xy 74.028854 -374.022683) (xy 74.047901 -373.971624) (xy 74.074021 -373.923796) (xy 74.106683 -373.880172)
			(xy 74.14522 -373.84164) (xy 74.18885 -373.808986) (xy 74.236683 -373.782874) (xy 74.287745 -373.763836)
			(xy 74.340997 -373.752259) (xy 74.395355 -373.748378) (xy 74.449711 -373.752274) (xy 74.50296 -373.763867)
			(xy 74.554017 -373.78292) (xy 74.601842 -373.809045) (xy 74.62393 -373.825008) (xy 74.642942 -373.838604)
			(xy 74.684825 -373.859336) (xy 74.729793 -373.872062) (xy 74.77633 -373.876352) (xy 74.822867 -373.872062)
			(xy 74.867835 -373.859336) (xy 74.909718 -373.838604) (xy 74.92873 -373.825008) (xy 74.950802 -373.809029)
			(xy 74.998627 -373.782911) (xy 75.049681 -373.763865) (xy 75.102927 -373.752279) (xy 75.157279 -373.748389)
			(xy 75.211632 -373.752273) (xy 75.264879 -373.763854) (xy 75.315936 -373.782894) (xy 75.363763 -373.809007)
			(xy 75.407387 -373.84166) (xy 75.44592 -373.88019) (xy 75.478577 -373.923812) (xy 75.504694 -373.971637)
			(xy 75.523738 -374.022692) (xy 75.535323 -374.075938) (xy 75.539211 -374.13029) (xy 76.088918 -374.13029)
			(xy 76.092806 -374.075942) (xy 76.10439 -374.022701) (xy 76.123433 -373.97165) (xy 76.149547 -373.923829)
			(xy 76.182201 -373.880211) (xy 76.220731 -373.841684) (xy 76.264351 -373.809033) (xy 76.312174 -373.782922)
			(xy 76.363227 -373.763882) (xy 76.416469 -373.752303) (xy 76.470817 -373.748418) (xy 76.525165 -373.752307)
			(xy 76.578406 -373.763892) (xy 76.629457 -373.782936) (xy 76.677278 -373.809051) (xy 76.699364 -373.825008)
			(xy 76.718376 -373.838604) (xy 76.760259 -373.859336) (xy 76.805227 -373.872062) (xy 76.851764 -373.876352)
			(xy 76.898301 -373.872062) (xy 76.943269 -373.859336) (xy 76.985152 -373.838604) (xy 77.004164 -373.825008)
			(xy 77.026238 -373.809023) (xy 77.074067 -373.782895) (xy 77.125128 -373.76384) (xy 77.178381 -373.752246)
			(xy 77.232742 -373.748349) (xy 77.287104 -373.752229) (xy 77.340361 -373.763807) (xy 77.391427 -373.782847)
			(xy 77.439264 -373.808961) (xy 77.482897 -373.841617) (xy 77.521439 -373.880151) (xy 77.554103 -373.923779)
			(xy 77.580225 -373.971611) (xy 77.599274 -374.022674) (xy 77.610861 -374.075929) (xy 77.614751 -374.13029)
			(xy 77.614692 -374.131113) (xy 78.313041 -374.131113) (xy 78.316927 -374.07675) (xy 78.328512 -374.023493)
			(xy 78.347558 -373.972427) (xy 78.373678 -373.924592) (xy 78.406341 -373.880962) (xy 78.444881 -373.842425)
			(xy 78.488514 -373.809765) (xy 78.536351 -373.783647) (xy 78.587418 -373.764604) (xy 78.640675 -373.753024)
			(xy 78.695039 -373.749141) (xy 78.749401 -373.753035) (xy 78.802657 -373.764626) (xy 78.85372 -373.78368)
			(xy 78.901551 -373.809807) (xy 78.923642 -373.82577) (xy 78.942654 -373.839366) (xy 78.984537 -373.860098)
			(xy 79.029505 -373.872824) (xy 79.076042 -373.877114) (xy 79.122579 -373.872824) (xy 79.167547 -373.860098)
			(xy 79.20943 -373.839366) (xy 79.228442 -373.82577) (xy 79.25055 -373.809843) (xy 79.298371 -373.783732)
			(xy 79.349422 -373.764692) (xy 79.402662 -373.753112) (xy 79.457009 -373.749226) (xy 79.511356 -373.753115)
			(xy 79.564596 -373.764698) (xy 79.615645 -373.78374) (xy 79.663465 -373.809853) (xy 79.707082 -373.842506)
			(xy 79.745608 -373.881034) (xy 79.778259 -373.924653) (xy 79.80437 -373.972475) (xy 79.823409 -374.023526)
			(xy 79.834989 -374.076766) (xy 79.838874 -374.131113) (xy 79.834985 -374.18546) (xy 79.823401 -374.2387)
			(xy 79.804359 -374.289749) (xy 79.778245 -374.337569) (xy 79.745591 -374.381186) (xy 79.707062 -374.419711)
			(xy 79.663443 -374.452361) (xy 79.615621 -374.478471) (xy 79.56457 -374.49751) (xy 79.511329 -374.509089)
			(xy 79.456983 -374.512974) (xy 79.402636 -374.509084) (xy 79.349396 -374.4975) (xy 79.298347 -374.478457)
			(xy 79.250528 -374.452342) (xy 79.228442 -374.436386) (xy 79.20943 -374.42279) (xy 79.167547 -374.402058)
			(xy 79.122579 -374.389332) (xy 79.076042 -374.385042) (xy 79.029505 -374.389332) (xy 78.984537 -374.402058)
			(xy 78.942654 -374.42279) (xy 78.923642 -374.436386) (xy 78.901573 -374.452379) (xy 78.853744 -374.478509)
			(xy 78.802682 -374.497566) (xy 78.749428 -374.509162) (xy 78.695065 -374.513059) (xy 78.640701 -374.50918)
			(xy 78.587443 -374.497603) (xy 78.536375 -374.478564) (xy 78.488536 -374.45245) (xy 78.444901 -374.419793)
			(xy 78.406359 -374.381258) (xy 78.373693 -374.33763) (xy 78.347569 -374.289797) (xy 78.328519 -374.238732)
			(xy 78.316931 -374.185476) (xy 78.313041 -374.131113) (xy 77.614692 -374.131113) (xy 77.610864 -374.184652)
			(xy 77.599279 -374.237907) (xy 77.580233 -374.288971) (xy 77.554113 -374.336805) (xy 77.521451 -374.380434)
			(xy 77.482912 -374.41897) (xy 77.43928 -374.451629) (xy 77.391445 -374.477745) (xy 77.340379 -374.496788)
			(xy 77.287123 -374.508368) (xy 77.232761 -374.512251) (xy 77.1784 -374.508357) (xy 77.125146 -374.496766)
			(xy 77.074084 -374.477713) (xy 77.026254 -374.451587) (xy 77.004164 -374.435624) (xy 76.985152 -374.422028)
			(xy 76.943269 -374.401296) (xy 76.898301 -374.38857) (xy 76.851764 -374.38428) (xy 76.805227 -374.38857)
			(xy 76.760259 -374.401296) (xy 76.718376 -374.422028) (xy 76.699364 -374.435624) (xy 76.677262 -374.451559)
			(xy 76.62944 -374.477672) (xy 76.578388 -374.496713) (xy 76.525146 -374.508295) (xy 76.470798 -374.512182)
			(xy 76.41645 -374.508295) (xy 76.363208 -374.496712) (xy 76.312157 -374.477671) (xy 76.264335 -374.451557)
			(xy 76.220716 -374.418904) (xy 76.182189 -374.380375) (xy 76.149537 -374.336755) (xy 76.123425 -374.288933)
			(xy 76.104384 -374.237881) (xy 76.092804 -374.184639) (xy 76.088918 -374.13029) (xy 75.539211 -374.13029)
			(xy 75.535325 -374.184643) (xy 75.523743 -374.23789) (xy 75.504702 -374.288946) (xy 75.478587 -374.336772)
			(xy 75.445932 -374.380395) (xy 75.407401 -374.418927) (xy 75.363779 -374.451583) (xy 75.315953 -374.477698)
			(xy 75.264897 -374.496741) (xy 75.211651 -374.508324) (xy 75.157299 -374.512211) (xy 75.102946 -374.508324)
			(xy 75.0497 -374.49674) (xy 74.998644 -374.477697) (xy 74.950819 -374.451581) (xy 74.92873 -374.435624)
			(xy 74.909718 -374.422028) (xy 74.867835 -374.401296) (xy 74.822867 -374.38857) (xy 74.77633 -374.38428)
			(xy 74.729793 -374.38857) (xy 74.684825 -374.401296) (xy 74.642942 -374.422028) (xy 74.62393 -374.435624)
			(xy 74.601826 -374.451565) (xy 74.553999 -374.477688) (xy 74.502942 -374.496739) (xy 74.449692 -374.508329)
			(xy 74.395336 -374.512222) (xy 74.340978 -374.508339) (xy 74.287726 -374.496759) (xy 74.236665 -374.477718)
			(xy 74.188834 -374.451603) (xy 74.145206 -374.418947) (xy 74.10667 -374.380414) (xy 74.074011 -374.336788)
			(xy 74.047893 -374.288958) (xy 74.028848 -374.237898) (xy 74.017265 -374.184648) (xy 74.013378 -374.13029)
			(xy 52.449476 -374.13029) (xy 52.449476 -375.263156) (xy 50.797968 -375.263156) (xy 50.797968 -373.61114)
			(xy 40.993568 -373.61114) (xy 40.993568 -373.825008) (xy 40.99415 -373.842647) (xy 41.003811 -373.876579)
			(xy 41.022369 -373.906583) (xy 41.048414 -373.930381) (xy 41.063926 -373.9388) (xy 41.111809 -373.963226)
			(xy 41.204061 -374.01842) (xy 41.291798 -374.08054) (xy 41.374503 -374.149218) (xy 41.451685 -374.224048)
			(xy 41.52289 -374.304588) (xy 41.587695 -374.390361) (xy 41.643694 -374.477703) (xy 47.298092 -374.477703)
			(xy 47.298092 -374.396593) (xy 47.306042 -374.315874) (xy 47.321865 -374.236323) (xy 47.34541 -374.158707)
			(xy 47.376449 -374.083771) (xy 47.414684 -374.012239) (xy 47.459746 -373.944799) (xy 47.511201 -373.8821)
			(xy 47.568554 -373.824747) (xy 47.631253 -373.773292) (xy 47.698693 -373.72823) (xy 47.770225 -373.689995)
			(xy 47.845161 -373.658956) (xy 47.922777 -373.635411) (xy 48.002328 -373.619588) (xy 48.083047 -373.611638)
			(xy 48.164157 -373.611638) (xy 48.244876 -373.619588) (xy 48.324427 -373.635411) (xy 48.402043 -373.658956)
			(xy 48.476979 -373.689995) (xy 48.548511 -373.72823) (xy 48.615951 -373.773292) (xy 48.67865 -373.824747)
			(xy 48.736003 -373.8821) (xy 48.787458 -373.944799) (xy 48.83252 -374.012239) (xy 48.870755 -374.083771)
			(xy 48.901794 -374.158707) (xy 48.925339 -374.236323) (xy 48.941162 -374.315874) (xy 48.949112 -374.396593)
			(xy 48.94961 -374.437148) (xy 48.949112 -374.477703) (xy 48.941162 -374.558422) (xy 48.925339 -374.637973)
			(xy 48.901794 -374.715589) (xy 48.870755 -374.790525) (xy 48.83252 -374.862057) (xy 48.787458 -374.929497)
			(xy 48.736003 -374.992196) (xy 48.67865 -375.049549) (xy 48.615951 -375.101004) (xy 48.548511 -375.146066)
			(xy 48.476979 -375.184301) (xy 48.402043 -375.21534) (xy 48.324427 -375.238885) (xy 48.244876 -375.254708)
			(xy 48.164157 -375.262658) (xy 48.083047 -375.262658) (xy 48.002328 -375.254708) (xy 47.922777 -375.238885)
			(xy 47.845161 -375.21534) (xy 47.770225 -375.184301) (xy 47.698693 -375.146066) (xy 47.631253 -375.101004)
			(xy 47.568554 -375.049549) (xy 47.511201 -374.992196) (xy 47.459746 -374.929497) (xy 47.414684 -374.862057)
			(xy 47.376449 -374.790525) (xy 47.34541 -374.715589) (xy 47.321865 -374.637973) (xy 47.306042 -374.558422)
			(xy 47.298092 -374.477703) (xy 41.643694 -374.477703) (xy 41.645718 -374.48086) (xy 41.696615 -374.57555)
			(xy 41.740086 -374.67387) (xy 41.775874 -374.775241) (xy 41.803766 -374.879062) (xy 41.823597 -374.984719)
			(xy 41.835252 -375.091587) (xy 41.83866 -375.199036) (xy 41.833802 -375.306428) (xy 41.820706 -375.413129)
			(xy 41.79945 -375.518509) (xy 41.770159 -375.621944) (xy 41.733006 -375.722822) (xy 41.711118 -375.771918)
			(xy 41.704546 -375.787579) (xy 41.69906 -375.821084) (xy 41.70259 -375.854851) (xy 41.714886 -375.886497)
			(xy 41.72458 -375.900442) (xy 41.756738 -375.944728) (xy 41.756956 -375.945072) (xy 73.967714 -375.945072)
			(xy 73.971606 -375.890722) (xy 73.983193 -375.837478) (xy 74.00224 -375.786425) (xy 74.028359 -375.738603)
			(xy 74.061018 -375.694986) (xy 74.099553 -375.65646) (xy 74.143178 -375.623811) (xy 74.191006 -375.597703)
			(xy 74.242063 -375.578668) (xy 74.29531 -375.567093) (xy 74.349661 -375.563214) (xy 74.404012 -375.567111)
			(xy 74.457254 -375.578702) (xy 74.508305 -375.597754) (xy 74.556125 -375.623877) (xy 74.57821 -375.639838)
			(xy 74.597222 -375.653434) (xy 74.639105 -375.674166) (xy 74.684073 -375.686892) (xy 74.73061 -375.691182)
			(xy 74.777147 -375.686892) (xy 74.822115 -375.674166) (xy 74.863998 -375.653434) (xy 74.88301 -375.639838)
			(xy 74.905055 -375.623817) (xy 74.952882 -375.597692) (xy 75.003941 -375.578639) (xy 75.057192 -375.567048)
			(xy 75.11155 -375.563153) (xy 75.165909 -375.567034) (xy 75.219163 -375.578611) (xy 75.270227 -375.59765)
			(xy 75.318061 -375.623763) (xy 75.361692 -375.656417) (xy 75.400232 -375.694949) (xy 75.432895 -375.738574)
			(xy 75.459018 -375.786403) (xy 75.478067 -375.837463) (xy 75.489655 -375.890714) (xy 75.493547 -375.945072)
			(xy 76.043094 -375.945072) (xy 76.046986 -375.890717) (xy 76.058574 -375.837469) (xy 76.077623 -375.786412)
			(xy 76.103746 -375.738587) (xy 76.136409 -375.694966) (xy 76.174947 -375.656438) (xy 76.218578 -375.623787)
			(xy 76.266411 -375.597679) (xy 76.317473 -375.578644) (xy 76.370724 -375.56707) (xy 76.425081 -375.563194)
			(xy 76.479436 -375.567093) (xy 76.532682 -375.578689) (xy 76.583736 -375.597746) (xy 76.631558 -375.623874)
			(xy 76.653644 -375.639838) (xy 76.672656 -375.653434) (xy 76.714539 -375.674166) (xy 76.759507 -375.686892)
			(xy 76.806044 -375.691182) (xy 76.852581 -375.686892) (xy 76.897549 -375.674166) (xy 76.939432 -375.653434)
			(xy 76.958444 -375.639838) (xy 76.980488 -375.62382) (xy 77.028313 -375.5977) (xy 77.079369 -375.578653)
			(xy 77.132616 -375.567065) (xy 77.186969 -375.563173) (xy 77.241324 -375.567056) (xy 77.294572 -375.578635)
			(xy 77.345631 -375.597675) (xy 77.39346 -375.623787) (xy 77.437087 -375.65644) (xy 77.475622 -375.694969)
			(xy 77.508282 -375.738591) (xy 77.534401 -375.786416) (xy 77.553448 -375.837472) (xy 77.565036 -375.890719)
			(xy 77.568927 -375.945072) (xy 77.568868 -375.945895) (xy 78.222016 -375.945895) (xy 78.225904 -375.891547)
			(xy 78.237487 -375.838306) (xy 78.256529 -375.787255) (xy 78.282642 -375.739433) (xy 78.315296 -375.695815)
			(xy 78.353824 -375.657287) (xy 78.397444 -375.624635) (xy 78.445266 -375.598523) (xy 78.496318 -375.579483)
			(xy 78.54956 -375.567902) (xy 78.603908 -375.564016) (xy 78.658256 -375.567904) (xy 78.711497 -375.579488)
			(xy 78.762548 -375.59853) (xy 78.810369 -375.624644) (xy 78.832456 -375.6406) (xy 78.851468 -375.654196)
			(xy 78.893351 -375.674928) (xy 78.938319 -375.687654) (xy 78.984856 -375.691944) (xy 79.031393 -375.687654)
			(xy 79.076361 -375.674928) (xy 79.118244 -375.654196) (xy 79.137256 -375.6406) (xy 79.159338 -375.624626)
			(xy 79.207167 -375.598497) (xy 79.258228 -375.579441) (xy 79.311481 -375.567847) (xy 79.365842 -375.563951)
			(xy 79.420205 -375.567831) (xy 79.473461 -375.579409) (xy 79.524528 -375.598449) (xy 79.545908 -375.61012)
			(xy 86.39887 -375.61012) (xy 86.402874 -375.410022) (xy 86.414881 -375.210244) (xy 86.434872 -375.011107)
			(xy 86.462814 -374.812929) (xy 86.498662 -374.616027) (xy 86.54236 -374.420718) (xy 86.593837 -374.227313)
			(xy 86.653011 -374.036123) (xy 86.719787 -373.847453) (xy 86.794059 -373.661606) (xy 86.875706 -373.478879)
			(xy 86.964599 -373.299566) (xy 87.060595 -373.123952) (xy 87.16354 -372.95232) (xy 87.27327 -372.784944)
			(xy 87.389608 -372.622093) (xy 87.512369 -372.464026) (xy 87.641356 -372.310998) (xy 87.776363 -372.163253)
			(xy 87.917172 -372.021027) (xy 88.063559 -371.88455) (xy 88.215289 -371.754038) (xy 88.37212 -371.629702)
			(xy 88.533799 -371.51174) (xy 88.700069 -371.400341) (xy 88.870662 -371.295684) (xy 89.045306 -371.197936)
			(xy 89.223722 -371.107253) (xy 89.405622 -371.023782) (xy 89.590717 -370.947655) (xy 89.778709 -370.878995)
			(xy 89.969298 -370.817911) (xy 90.162178 -370.764501) (xy 90.35704 -370.718852) (xy 90.553573 -370.681035)
			(xy 90.751462 -370.651111) (xy 90.950389 -370.629129) (xy 91.150037 -370.615124) (xy 91.350085 -370.609118)
			(xy 91.550213 -370.61112) (xy 91.750101 -370.621128) (xy 91.949428 -370.639125) (xy 92.147876 -370.665083)
			(xy 92.345126 -370.69896) (xy 92.540863 -370.740702) (xy 92.734773 -370.790241) (xy 92.926546 -370.847499)
			(xy 93.115875 -370.912384) (xy 93.302455 -370.984792) (xy 93.48599 -371.064608) (xy 93.666184 -371.151702)
			(xy 93.842749 -371.245936) (xy 94.015402 -371.347159) (xy 94.183867 -371.455209) (xy 94.347875 -371.569912)
			(xy 94.507162 -371.691086) (xy 94.661473 -371.818535) (xy 94.810561 -371.952056) (xy 94.954188 -372.091436)
			(xy 95.092124 -372.23645) (xy 95.224147 -372.386867) (xy 95.350046 -372.542445) (xy 95.46962 -372.702937)
			(xy 95.582676 -372.868083) (xy 95.689035 -373.037621) (xy 95.788526 -373.211279) (xy 95.880989 -373.388778)
			(xy 95.966276 -373.569834) (xy 96.044251 -373.754158) (xy 96.114788 -373.941454) (xy 96.177776 -374.131422)
			(xy 96.233113 -374.323758) (xy 96.28071 -374.518154) (xy 96.320491 -374.714299) (xy 96.352393 -374.911878)
			(xy 96.376364 -375.110575) (xy 96.392366 -375.310073) (xy 96.400373 -375.510051) (xy 96.400874 -375.61012)
			(xy 96.400373 -375.710189) (xy 96.392366 -375.910167) (xy 96.376364 -376.109665) (xy 96.352393 -376.308362)
			(xy 96.320491 -376.505941) (xy 96.28071 -376.702086) (xy 96.233113 -376.896482) (xy 96.177776 -377.088818)
			(xy 96.114788 -377.278786) (xy 96.044251 -377.466082) (xy 95.966276 -377.650406) (xy 95.880989 -377.831462)
			(xy 95.788526 -378.008961) (xy 95.689035 -378.182619) (xy 95.582676 -378.352157) (xy 95.46962 -378.517303)
			(xy 95.350046 -378.677795) (xy 95.224147 -378.833373) (xy 95.092124 -378.98379) (xy 94.954188 -379.128804)
			(xy 94.810561 -379.268184) (xy 94.661473 -379.401705) (xy 94.507162 -379.529154) (xy 94.347875 -379.650328)
			(xy 94.183867 -379.765031) (xy 94.015402 -379.873081) (xy 93.842749 -379.974304) (xy 93.666184 -380.068538)
			(xy 93.48599 -380.155632) (xy 93.302455 -380.235448) (xy 93.115875 -380.307856) (xy 92.926546 -380.372741)
			(xy 92.734773 -380.429999) (xy 92.540863 -380.479538) (xy 92.345126 -380.52128) (xy 92.147876 -380.555157)
			(xy 91.949428 -380.581115) (xy 91.750101 -380.599112) (xy 91.550213 -380.60912) (xy 91.350085 -380.611122)
			(xy 91.150037 -380.605116) (xy 90.950389 -380.591111) (xy 90.751462 -380.569129) (xy 90.553573 -380.539205)
			(xy 90.35704 -380.501388) (xy 90.162178 -380.455739) (xy 89.969298 -380.402329) (xy 89.778709 -380.341245)
			(xy 89.590717 -380.272585) (xy 89.405622 -380.196458) (xy 89.223722 -380.112987) (xy 89.045306 -380.022304)
			(xy 88.870662 -379.924556) (xy 88.700069 -379.819899) (xy 88.533799 -379.7085) (xy 88.37212 -379.590538)
			(xy 88.215289 -379.466202) (xy 88.063559 -379.33569) (xy 87.917172 -379.199213) (xy 87.776363 -379.056987)
			(xy 87.641356 -378.909242) (xy 87.512369 -378.756214) (xy 87.389608 -378.598147) (xy 87.27327 -378.435296)
			(xy 87.16354 -378.26792) (xy 87.060595 -378.096288) (xy 86.964599 -377.920674) (xy 86.875706 -377.741361)
			(xy 86.794059 -377.558634) (xy 86.719787 -377.372787) (xy 86.653011 -377.184117) (xy 86.593837 -376.992927)
			(xy 86.54236 -376.799522) (xy 86.498662 -376.604213) (xy 86.462814 -376.407311) (xy 86.434872 -376.209133)
			(xy 86.414881 -376.009996) (xy 86.402874 -375.810218) (xy 86.39887 -375.61012) (xy 79.545908 -375.61012)
			(xy 79.572365 -375.624563) (xy 79.615998 -375.65722) (xy 79.654539 -375.695755) (xy 79.687203 -375.739382)
			(xy 79.713325 -375.787215) (xy 79.732374 -375.838279) (xy 79.74396 -375.891533) (xy 79.747849 -375.945895)
			(xy 79.743962 -376.000257) (xy 79.732376 -376.053512) (xy 79.713329 -376.104576) (xy 79.687208 -376.15241)
			(xy 79.654545 -376.196038) (xy 79.616005 -376.234574) (xy 79.572373 -376.267232) (xy 79.524537 -376.293347)
			(xy 79.47347 -376.312389) (xy 79.420214 -376.323968) (xy 79.365852 -376.327849) (xy 79.31149 -376.323954)
			(xy 79.258237 -376.312361) (xy 79.207175 -376.293307) (xy 79.159346 -376.26718) (xy 79.137256 -376.251216)
			(xy 79.118244 -376.23762) (xy 79.076361 -376.216888) (xy 79.031393 -376.204162) (xy 78.984856 -376.199872)
			(xy 78.938319 -376.204162) (xy 78.893351 -376.216888) (xy 78.851468 -376.23762) (xy 78.832456 -376.251216)
			(xy 78.810361 -376.267161) (xy 78.762539 -376.293274) (xy 78.711488 -376.312315) (xy 78.658246 -376.323897)
			(xy 78.603898 -376.327784) (xy 78.54955 -376.323896) (xy 78.496309 -376.312314) (xy 78.445257 -376.293273)
			(xy 78.397436 -376.267159) (xy 78.353817 -376.234506) (xy 78.315289 -376.195978) (xy 78.282637 -376.152359)
			(xy 78.256525 -376.104537) (xy 78.237484 -376.053485) (xy 78.225903 -376.000243) (xy 78.222016 -375.945895)
			(xy 77.568868 -375.945895) (xy 77.565043 -375.999427) (xy 77.553464 -376.052675) (xy 77.534424 -376.103734)
			(xy 77.508312 -376.151563) (xy 77.475658 -376.195189) (xy 77.437129 -376.233724) (xy 77.393507 -376.266384)
			(xy 77.345681 -376.292502) (xy 77.294625 -376.311549) (xy 77.241378 -376.323136) (xy 77.187025 -376.327027)
			(xy 77.13267 -376.323143) (xy 77.079422 -376.311563) (xy 77.028363 -376.292523) (xy 76.980534 -376.26641)
			(xy 76.958444 -376.250454) (xy 76.939432 -376.236858) (xy 76.897549 -376.216126) (xy 76.852581 -376.2034)
			(xy 76.806044 -376.19911) (xy 76.759507 -376.2034) (xy 76.714539 -376.216126) (xy 76.672656 -376.236858)
			(xy 76.653644 -376.250454) (xy 76.631512 -376.266356) (xy 76.583686 -376.292477) (xy 76.532629 -376.311526)
			(xy 76.479381 -376.323115) (xy 76.425025 -376.327006) (xy 76.37067 -376.323122) (xy 76.31742 -376.311541)
			(xy 76.26636 -376.292499) (xy 76.218531 -376.266383) (xy 76.174906 -376.233726) (xy 76.136372 -376.195193)
			(xy 76.103716 -376.151567) (xy 76.077601 -376.103738) (xy 76.058559 -376.052678) (xy 76.046978 -375.999428)
			(xy 76.043094 -375.945072) (xy 75.493547 -375.945072) (xy 75.489663 -375.999431) (xy 75.478082 -376.052684)
			(xy 75.45904 -376.103747) (xy 75.432925 -376.15158) (xy 75.400268 -376.195209) (xy 75.361734 -376.233746)
			(xy 75.318108 -376.266407) (xy 75.270277 -376.292527) (xy 75.219216 -376.311573) (xy 75.165964 -376.323159)
			(xy 75.111605 -376.327047) (xy 75.057246 -376.32316) (xy 75.003994 -376.311576) (xy 74.952933 -376.292531)
			(xy 74.905101 -376.266413) (xy 74.88301 -376.250454) (xy 74.863998 -376.236858) (xy 74.822115 -376.216126)
			(xy 74.777147 -376.2034) (xy 74.73061 -376.19911) (xy 74.684073 -376.2034) (xy 74.639105 -376.216126)
			(xy 74.597222 -376.236858) (xy 74.57821 -376.250454) (xy 74.556078 -376.266353) (xy 74.508255 -376.292469)
			(xy 74.457201 -376.311513) (xy 74.403957 -376.323097) (xy 74.349606 -376.326986) (xy 74.295255 -376.323099)
			(xy 74.24201 -376.311517) (xy 74.190956 -376.292474) (xy 74.143132 -376.266359) (xy 74.099511 -376.233704)
			(xy 74.060982 -376.195173) (xy 74.028329 -376.15155) (xy 74.002217 -376.103724) (xy 73.983177 -376.052669)
			(xy 73.971598 -375.999424) (xy 73.967714 -375.945072) (xy 41.756956 -375.945072) (xy 41.815264 -376.037223)
			(xy 41.866887 -376.13374) (xy 41.911332 -376.233766) (xy 41.948362 -376.336768) (xy 41.977781 -376.442196)
			(xy 41.99943 -376.54949) (xy 42.013196 -376.658076) (xy 42.019003 -376.767378) (xy 42.016823 -376.876812)
			(xy 42.006665 -376.985795) (xy 41.988585 -377.093748) (xy 41.962678 -377.200093) (xy 41.929083 -377.304266)
			(xy 41.887979 -377.405711) (xy 41.839584 -377.503887) (xy 41.784157 -377.598271) (xy 41.721993 -377.688361)
			(xy 41.711197 -377.701794) (xy 73.967685 -377.701794) (xy 73.971574 -377.647439) (xy 73.983159 -377.594191)
			(xy 74.002205 -377.543133) (xy 74.028323 -377.495306) (xy 74.060982 -377.451683) (xy 74.099518 -377.413152)
			(xy 74.143145 -377.380498) (xy 74.190975 -377.354386) (xy 74.242034 -377.335346) (xy 74.295284 -377.323768)
			(xy 74.34964 -377.319885) (xy 74.403994 -377.323779) (xy 74.457242 -377.335369) (xy 74.508298 -377.354419)
			(xy 74.556122 -377.380541) (xy 74.57821 -377.396502) (xy 74.597222 -377.410098) (xy 74.639105 -377.43083)
			(xy 74.684073 -377.443556) (xy 74.73061 -377.447846) (xy 74.777147 -377.443556) (xy 74.822115 -377.43083)
			(xy 74.863998 -377.410098) (xy 74.88301 -377.396502) (xy 74.905089 -377.380529) (xy 74.952914 -377.354409)
			(xy 75.00397 -377.335361) (xy 75.057217 -377.323773) (xy 75.111572 -377.319881) (xy 75.165927 -377.323765)
			(xy 75.219176 -377.335345) (xy 75.270234 -377.354385) (xy 75.318064 -377.380499) (xy 75.36169 -377.413153)
			(xy 75.400224 -377.451684) (xy 75.432883 -377.495307) (xy 75.459 -377.543134) (xy 75.478045 -377.594191)
			(xy 75.48963 -377.647439) (xy 75.493519 -377.701794) (xy 76.043065 -377.701794) (xy 76.046954 -377.647434)
			(xy 76.058541 -377.594181) (xy 76.077588 -377.54312) (xy 76.10371 -377.495289) (xy 76.136373 -377.451663)
			(xy 76.174912 -377.41313) (xy 76.218544 -377.380474) (xy 76.266379 -377.354361) (xy 76.317444 -377.335322)
			(xy 76.370699 -377.323745) (xy 76.425059 -377.319865) (xy 76.479418 -377.323762) (xy 76.532669 -377.335356)
			(xy 76.583728 -377.35441) (xy 76.631556 -377.380538) (xy 76.653644 -377.396502) (xy 76.672656 -377.410098)
			(xy 76.714539 -377.43083) (xy 76.759507 -377.443556) (xy 76.806044 -377.447846) (xy 76.852581 -377.443556)
			(xy 76.897549 -377.43083) (xy 76.939432 -377.410098) (xy 76.958444 -377.396502) (xy 76.980522 -377.380532)
			(xy 77.028345 -377.354417) (xy 77.079398 -377.335374) (xy 77.132641 -377.32379) (xy 77.186991 -377.319902)
			(xy 77.241341 -377.323788) (xy 77.294585 -377.335369) (xy 77.345639 -377.35441) (xy 77.393463 -377.380523)
			(xy 77.437084 -377.413176) (xy 77.475615 -377.451704) (xy 77.508269 -377.495324) (xy 77.534384 -377.543148)
			(xy 77.553427 -377.594201) (xy 77.56501 -377.647444) (xy 77.568898 -377.701794) (xy 77.568839 -377.702617)
			(xy 78.221987 -377.702617) (xy 78.225872 -377.648265) (xy 78.237453 -377.595018) (xy 78.256493 -377.543962)
			(xy 78.282606 -377.496136) (xy 78.31526 -377.452512) (xy 78.353789 -377.41398) (xy 78.39741 -377.381323)
			(xy 78.445234 -377.355206) (xy 78.496289 -377.336162) (xy 78.549534 -377.324577) (xy 78.603886 -377.320687)
			(xy 78.658238 -377.324573) (xy 78.711484 -377.336154) (xy 78.76254 -377.355195) (xy 78.810367 -377.381308)
			(xy 78.832456 -377.397264) (xy 78.851468 -377.41086) (xy 78.893351 -377.431592) (xy 78.938319 -377.444318)
			(xy 78.984856 -377.448608) (xy 79.031393 -377.444318) (xy 79.076361 -377.431592) (xy 79.118244 -377.41086)
			(xy 79.137256 -377.397264) (xy 79.159371 -377.381338) (xy 79.207198 -377.355214) (xy 79.258257 -377.336163)
			(xy 79.311506 -377.324573) (xy 79.365864 -377.32068) (xy 79.420222 -377.324562) (xy 79.473474 -377.336142)
			(xy 79.524536 -377.355184) (xy 79.572368 -377.381299) (xy 79.615996 -377.413956) (xy 79.654531 -377.45249)
			(xy 79.687191 -377.496116) (xy 79.713308 -377.543947) (xy 79.732352 -377.595007) (xy 79.743935 -377.648259)
			(xy 79.74782 -377.702617) (xy 79.74393 -377.756974) (xy 79.732343 -377.810225) (xy 79.713294 -377.861284)
			(xy 79.687172 -377.909112) (xy 79.654509 -377.952736) (xy 79.61597 -377.991266) (xy 79.572339 -378.023919)
			(xy 79.524505 -378.05003) (xy 79.473442 -378.069067) (xy 79.420189 -378.080642) (xy 79.36583 -378.08452)
			(xy 79.311473 -378.080622) (xy 79.258224 -378.069028) (xy 79.207168 -378.049972) (xy 79.159343 -378.023844)
			(xy 79.137256 -378.00788) (xy 79.118244 -377.994284) (xy 79.076361 -377.973552) (xy 79.031393 -377.960826)
			(xy 78.984856 -377.956536) (xy 78.938319 -377.960826) (xy 78.893351 -377.973552) (xy 78.851468 -377.994284)
			(xy 78.832456 -378.00788) (xy 78.810395 -378.023874) (xy 78.762571 -378.049991) (xy 78.711517 -378.069037)
			(xy 78.658272 -378.080622) (xy 78.60392 -378.084513) (xy 78.549568 -378.080628) (xy 78.496321 -378.069048)
			(xy 78.445265 -378.050008) (xy 78.397438 -378.023895) (xy 78.353814 -377.991242) (xy 78.315282 -377.952713)
			(xy 78.282624 -377.909093) (xy 78.256507 -377.861268) (xy 78.237462 -377.810214) (xy 78.225877 -377.756969)
			(xy 78.221987 -377.702617) (xy 77.568839 -377.702617) (xy 77.565012 -377.756144) (xy 77.55343 -377.809388)
			(xy 77.534389 -377.860442) (xy 77.508276 -377.908266) (xy 77.475622 -377.951887) (xy 77.437093 -377.990417)
			(xy 77.393473 -378.023071) (xy 77.34565 -378.049185) (xy 77.294597 -378.068228) (xy 77.241353 -378.079811)
			(xy 77.187003 -378.083698) (xy 77.132653 -378.079811) (xy 77.079409 -378.068229) (xy 77.028356 -378.049188)
			(xy 76.980532 -378.023074) (xy 76.958444 -378.007118) (xy 76.939432 -377.993522) (xy 76.897549 -377.97279)
			(xy 76.852581 -377.960064) (xy 76.806044 -377.955774) (xy 76.759507 -377.960064) (xy 76.714539 -377.97279)
			(xy 76.672656 -377.993522) (xy 76.653644 -378.007118) (xy 76.631545 -378.023068) (xy 76.583717 -378.049195)
			(xy 76.532658 -378.068248) (xy 76.479406 -378.07984) (xy 76.425047 -378.083735) (xy 76.370687 -378.079853)
			(xy 76.317432 -378.068274) (xy 76.266368 -378.049234) (xy 76.218534 -378.023119) (xy 76.174903 -377.990462)
			(xy 76.136365 -377.951928) (xy 76.103703 -377.908301) (xy 76.077583 -377.860469) (xy 76.058537 -377.809407)
			(xy 76.046952 -377.756154) (xy 76.043065 -377.701794) (xy 75.493519 -377.701794) (xy 75.489632 -377.756149)
			(xy 75.478049 -377.809397) (xy 75.459005 -377.860455) (xy 75.432889 -377.908283) (xy 75.400232 -377.951907)
			(xy 75.361699 -377.990439) (xy 75.318074 -378.023095) (xy 75.270245 -378.04921) (xy 75.219187 -378.068252)
			(xy 75.165938 -378.079833) (xy 75.111584 -378.083719) (xy 75.057229 -378.079829) (xy 75.003982 -378.068242)
			(xy 74.952925 -378.049196) (xy 74.905099 -378.023077) (xy 74.88301 -378.007118) (xy 74.863998 -377.993522)
			(xy 74.822115 -377.97279) (xy 74.777147 -377.960064) (xy 74.73061 -377.955774) (xy 74.684073 -377.960064)
			(xy 74.639105 -377.97279) (xy 74.597222 -377.993522) (xy 74.57821 -378.007118) (xy 74.556112 -378.023065)
			(xy 74.508287 -378.049186) (xy 74.45723 -378.068235) (xy 74.403983 -378.079823) (xy 74.349628 -378.083715)
			(xy 74.295272 -378.079831) (xy 74.242023 -378.06825) (xy 74.190964 -378.049209) (xy 74.143134 -378.023095)
			(xy 74.099509 -377.99044) (xy 74.060974 -377.951908) (xy 74.028316 -377.908284) (xy 74.0022 -377.860456)
			(xy 73.983156 -377.809398) (xy 73.971572 -377.756149) (xy 73.967685 -377.701794) (xy 41.711197 -377.701794)
			(xy 41.653423 -377.773676) (xy 41.578812 -377.853762) (xy 41.498558 -377.928192) (xy 41.413088 -377.99657)
			(xy 41.322859 -378.058531) (xy 41.22835 -378.113745) (xy 41.130065 -378.161918) (xy 41.028528 -378.202794)
			(xy 40.92428 -378.236154) (xy 40.817876 -378.261821) (xy 40.709883 -378.279658) (xy 40.600877 -378.289569)
			(xy 40.491438 -378.291503) (xy 40.38215 -378.285449) (xy 40.273595 -378.271439) (xy 40.16635 -378.249548)
			(xy 40.060989 -378.219892) (xy 39.958071 -378.18263) (xy 39.858145 -378.137959) (xy 39.761744 -378.086119)
			(xy 39.669382 -378.027384) (xy 39.58155 -377.962069) (xy 39.498716 -377.890521) (xy 39.459662 -377.852178)
			(xy 38.565328 -376.957844) (xy 37.115242 -376.957844) (xy 36.403534 -377.669552) (xy 30.240986 -377.669552)
			(xy 30.226694 -377.671086) (xy 30.199288 -377.679735) (xy 30.174499 -377.694276) (xy 30.16377 -377.703842)
			(xy 29.830776 -378.036836) (xy 29.175202 -378.692664) (xy 29.153199 -378.714003) (xy 29.104727 -378.751522)
			(xy 29.051897 -378.782604) (xy 28.995558 -378.80675) (xy 28.936617 -378.823573) (xy 28.87602 -378.8328)
			(xy 28.814742 -378.834284) (xy 28.75377 -378.828002) (xy 28.694083 -378.814053) (xy 28.636641 -378.792663)
			(xy 28.582368 -378.764174) (xy 28.556966 -378.74702) (xy 28.542472 -378.737579) (xy 28.509864 -378.726079)
			(xy 28.475367 -378.723751) (xy 28.44151 -378.730766) (xy 28.410778 -378.746611) (xy 28.397708 -378.757942)
			(xy 28.394152 -378.761498) (xy 28.381719 -378.773735) (xy 28.363493 -378.803465) (xy 28.354019 -378.837026)
			(xy 28.353512 -378.854462) (xy 28.353512 -379.468412) (xy 73.967661 -379.468412) (xy 73.971548 -379.414053)
			(xy 73.983131 -379.360801) (xy 74.002175 -379.30974) (xy 74.028293 -379.261908) (xy 74.060952 -379.218281)
			(xy 74.099488 -379.179746) (xy 74.143116 -379.147088) (xy 74.190948 -379.120971) (xy 74.24201 -379.101928)
			(xy 74.295263 -379.090346) (xy 74.349622 -379.086461) (xy 74.40398 -379.090353) (xy 74.457231 -379.101941)
			(xy 74.508291 -379.120989) (xy 74.55612 -379.147111) (xy 74.57821 -379.163072) (xy 74.597222 -379.176668)
			(xy 74.639105 -379.1974) (xy 74.684073 -379.210126) (xy 74.73061 -379.214416) (xy 74.777147 -379.210126)
			(xy 74.822115 -379.1974) (xy 74.863998 -379.176668) (xy 74.88301 -379.163072) (xy 74.905117 -379.14714)
			(xy 74.95294 -379.121023) (xy 75.003994 -379.101979) (xy 75.057238 -379.090394) (xy 75.11159 -379.086505)
			(xy 75.165941 -379.090391) (xy 75.219186 -379.101973) (xy 75.270241 -379.121015) (xy 75.318066 -379.147129)
			(xy 75.361688 -379.179783) (xy 75.400218 -379.218314) (xy 75.432872 -379.261935) (xy 75.458986 -379.309761)
			(xy 75.478027 -379.360815) (xy 75.489609 -379.414061) (xy 75.493495 -379.468412) (xy 76.043041 -379.468412)
			(xy 76.046928 -379.414049) (xy 76.058512 -379.360792) (xy 76.077559 -379.309726) (xy 76.10368 -379.261891)
			(xy 76.136343 -379.218261) (xy 76.174883 -379.179724) (xy 76.218516 -379.147064) (xy 76.266353 -379.120947)
			(xy 76.31742 -379.101904) (xy 76.370677 -379.090324) (xy 76.425041 -379.086441) (xy 76.479404 -379.090335)
			(xy 76.532659 -379.101927) (xy 76.583722 -379.120981) (xy 76.631553 -379.147108) (xy 76.653644 -379.163072)
			(xy 76.672656 -379.176668) (xy 76.714539 -379.1974) (xy 76.759507 -379.210126) (xy 76.806044 -379.214416)
			(xy 76.852581 -379.210126) (xy 76.897549 -379.1974) (xy 76.939432 -379.176668) (xy 76.958444 -379.163072)
			(xy 76.98055 -379.147143) (xy 77.028371 -379.121032) (xy 77.079422 -379.101992) (xy 77.132662 -379.090412)
			(xy 77.187009 -379.086526) (xy 77.241356 -379.090414) (xy 77.294596 -379.101997) (xy 77.345645 -379.121039)
			(xy 77.393465 -379.147152) (xy 77.437082 -379.179806) (xy 77.475608 -379.218334) (xy 77.508259 -379.261952)
			(xy 77.53437 -379.309774) (xy 77.553409 -379.360825) (xy 77.564989 -379.414065) (xy 77.568874 -379.468412)
			(xy 77.568827 -379.469075) (xy 78.222043 -379.469075) (xy 78.225934 -379.414731) (xy 78.237519 -379.361494)
			(xy 78.256562 -379.310447) (xy 78.282676 -379.262631) (xy 78.315329 -379.219017) (xy 78.353857 -379.180495)
			(xy 78.397476 -379.147847) (xy 78.445296 -379.12174) (xy 78.496345 -379.102704) (xy 78.549584 -379.091126)
			(xy 78.603928 -379.087243) (xy 78.658272 -379.091134) (xy 78.711509 -379.102719) (xy 78.762555 -379.121763)
			(xy 78.810372 -379.147878) (xy 78.832456 -379.163834) (xy 78.851468 -379.17743) (xy 78.893351 -379.198162)
			(xy 78.938319 -379.210888) (xy 78.984856 -379.215178) (xy 79.031393 -379.210888) (xy 79.076361 -379.198162)
			(xy 79.118244 -379.17743) (xy 79.137256 -379.163834) (xy 79.159306 -379.147814) (xy 79.207137 -379.12168)
			(xy 79.2582 -379.102621) (xy 79.311457 -379.091023) (xy 79.365822 -379.087123) (xy 79.420188 -379.091001)
			(xy 79.473449 -379.102577) (xy 79.524521 -379.121615) (xy 79.572362 -379.147729) (xy 79.616 -379.180386)
			(xy 79.654546 -379.218921) (xy 79.687215 -379.26255) (xy 79.713342 -379.310385) (xy 79.732394 -379.361451)
			(xy 79.743984 -379.414709) (xy 79.747877 -379.469075) (xy 79.743991 -379.523441) (xy 79.732408 -379.5767)
			(xy 79.713363 -379.627769) (xy 79.687242 -379.675607) (xy 79.654579 -379.719241) (xy 79.616039 -379.757781)
			(xy 79.572405 -379.790444) (xy 79.524567 -379.816564) (xy 79.473498 -379.835609) (xy 79.420238 -379.847192)
			(xy 79.365872 -379.851077) (xy 79.311507 -379.847184) (xy 79.258249 -379.835593) (xy 79.207183 -379.81654)
			(xy 79.159348 -379.790414) (xy 79.137256 -379.77445) (xy 79.118244 -379.760854) (xy 79.076361 -379.740122)
			(xy 79.031393 -379.727396) (xy 78.984856 -379.723106) (xy 78.938319 -379.727396) (xy 78.893351 -379.740122)
			(xy 78.851468 -379.760854) (xy 78.832456 -379.77445) (xy 78.810329 -379.79035) (xy 78.762509 -379.816458)
			(xy 78.711461 -379.835495) (xy 78.658222 -379.847073) (xy 78.603878 -379.850957) (xy 78.549534 -379.847067)
			(xy 78.496297 -379.835482) (xy 78.44525 -379.816439) (xy 78.397433 -379.790326) (xy 78.353819 -379.757672)
			(xy 78.315296 -379.719145) (xy 78.282649 -379.675527) (xy 78.256541 -379.627707) (xy 78.237504 -379.576658)
			(xy 78.225927 -379.523419) (xy 78.222043 -379.469075) (xy 77.568827 -379.469075) (xy 77.564985 -379.522759)
			(xy 77.553402 -379.575998) (xy 77.53436 -379.627048) (xy 77.508246 -379.674868) (xy 77.475592 -379.718484)
			(xy 77.437064 -379.75701) (xy 77.393445 -379.78966) (xy 77.345623 -379.815771) (xy 77.294572 -379.83481)
			(xy 77.241332 -379.846389) (xy 77.186985 -379.850274) (xy 77.132639 -379.846385) (xy 77.079399 -379.834801)
			(xy 77.028349 -379.815758) (xy 76.98053 -379.789644) (xy 76.958444 -379.773688) (xy 76.939432 -379.760092)
			(xy 76.897549 -379.73936) (xy 76.852581 -379.726634) (xy 76.806044 -379.722344) (xy 76.759507 -379.726634)
			(xy 76.714539 -379.73936) (xy 76.672656 -379.760092) (xy 76.653644 -379.773688) (xy 76.631574 -379.789679)
			(xy 76.583744 -379.815809) (xy 76.532682 -379.834866) (xy 76.479428 -379.846461) (xy 76.425065 -379.850359)
			(xy 76.370701 -379.84648) (xy 76.317443 -379.834902) (xy 76.266375 -379.815863) (xy 76.218536 -379.789749)
			(xy 76.174901 -379.757092) (xy 76.136358 -379.718557) (xy 76.103693 -379.674929) (xy 76.077569 -379.627096)
			(xy 76.058519 -379.576031) (xy 76.046931 -379.522775) (xy 76.043041 -379.468412) (xy 75.493495 -379.468412)
			(xy 75.489605 -379.522763) (xy 75.478021 -379.576008) (xy 75.458976 -379.627061) (xy 75.432859 -379.674885)
			(xy 75.400202 -379.718504) (xy 75.361669 -379.757032) (xy 75.318046 -379.789684) (xy 75.270219 -379.815795)
			(xy 75.219163 -379.834834) (xy 75.165917 -379.846412) (xy 75.111566 -379.850295) (xy 75.057215 -379.846402)
			(xy 75.003971 -379.834814) (xy 74.952918 -379.815767) (xy 74.905096 -379.789647) (xy 74.88301 -379.773688)
			(xy 74.863998 -379.760092) (xy 74.822115 -379.73936) (xy 74.777147 -379.726634) (xy 74.73061 -379.722344)
			(xy 74.684073 -379.726634) (xy 74.639105 -379.73936) (xy 74.597222 -379.760092) (xy 74.57821 -379.773688)
			(xy 74.55614 -379.789676) (xy 74.508313 -379.815801) (xy 74.457254 -379.834853) (xy 74.404004 -379.846444)
			(xy 74.349646 -379.850339) (xy 74.295287 -379.846457) (xy 74.242033 -379.834878) (xy 74.19097 -379.815839)
			(xy 74.143137 -379.789725) (xy 74.099506 -379.75707) (xy 74.060968 -379.718537) (xy 74.028306 -379.674912)
			(xy 74.002185 -379.627082) (xy 73.983138 -379.576022) (xy 73.971551 -379.52277) (xy 73.967661 -379.468412)
			(xy 28.353512 -379.468412) (xy 28.353512 -384.55625) (xy 76.183218 -384.55625) (xy 76.183218 -384.496314)
			(xy 76.191041 -384.436892) (xy 76.206554 -384.378999) (xy 76.22949 -384.323626) (xy 76.259457 -384.27172)
			(xy 76.295944 -384.22417) (xy 76.338324 -384.18179) (xy 76.385874 -384.145303) (xy 76.43778 -384.115336)
			(xy 76.493153 -384.0924) (xy 76.551046 -384.076887) (xy 76.610468 -384.069064) (xy 76.670404 -384.069064)
			(xy 76.729826 -384.076887) (xy 76.787719 -384.0924) (xy 76.843092 -384.115336) (xy 76.894998 -384.145303)
			(xy 76.942548 -384.18179) (xy 76.984928 -384.22417) (xy 77.021415 -384.27172) (xy 77.051382 -384.323626)
			(xy 77.074318 -384.378999) (xy 77.089831 -384.436892) (xy 77.097654 -384.496314) (xy 77.098144 -384.526282)
			(xy 77.097654 -384.55625) (xy 77.089831 -384.615672) (xy 77.074318 -384.673565) (xy 77.051382 -384.728938)
			(xy 77.021415 -384.780844) (xy 76.984928 -384.828394) (xy 76.942548 -384.870774) (xy 76.894998 -384.907261)
			(xy 76.843092 -384.937228) (xy 76.787719 -384.960164) (xy 76.729826 -384.975677) (xy 76.670404 -384.9835)
			(xy 76.610468 -384.9835) (xy 76.551046 -384.975677) (xy 76.493153 -384.960164) (xy 76.43778 -384.937228)
			(xy 76.385874 -384.907261) (xy 76.338324 -384.870774) (xy 76.295944 -384.828394) (xy 76.259457 -384.780844)
			(xy 76.22949 -384.728938) (xy 76.206554 -384.673565) (xy 76.191041 -384.615672) (xy 76.183218 -384.55625)
			(xy 28.353512 -384.55625) (xy 28.353512 -387.227822) (xy 76.3186 -387.227822) (xy 76.3186 -387.167886)
			(xy 76.326423 -387.108464) (xy 76.341936 -387.050571) (xy 76.364872 -386.995198) (xy 76.394839 -386.943292)
			(xy 76.431326 -386.895742) (xy 76.473706 -386.853362) (xy 76.521256 -386.816875) (xy 76.573162 -386.786908)
			(xy 76.628535 -386.763972) (xy 76.686428 -386.748459) (xy 76.74585 -386.740636) (xy 76.805786 -386.740636)
			(xy 76.865208 -386.748459) (xy 76.923101 -386.763972) (xy 76.978474 -386.786908) (xy 77.03038 -386.816875)
			(xy 77.07793 -386.853362) (xy 77.12031 -386.895742) (xy 77.156797 -386.943292) (xy 77.186764 -386.995198)
			(xy 77.2097 -387.050571) (xy 77.225213 -387.108464) (xy 77.233036 -387.167886) (xy 77.233526 -387.197854)
			(xy 77.233036 -387.227822) (xy 77.225213 -387.287244) (xy 77.2097 -387.345137) (xy 77.186764 -387.40051)
			(xy 77.156797 -387.452416) (xy 77.12031 -387.499966) (xy 77.07793 -387.542346) (xy 77.03038 -387.578833)
			(xy 76.978474 -387.6088) (xy 76.923101 -387.631736) (xy 76.865208 -387.647249) (xy 76.805786 -387.655072)
			(xy 76.74585 -387.655072) (xy 76.686428 -387.647249) (xy 76.628535 -387.631736) (xy 76.573162 -387.6088)
			(xy 76.521256 -387.578833) (xy 76.473706 -387.542346) (xy 76.431326 -387.499966) (xy 76.394839 -387.452416)
			(xy 76.364872 -387.40051) (xy 76.341936 -387.345137) (xy 76.326423 -387.287244) (xy 76.3186 -387.227822)
			(xy 28.353512 -387.227822) (xy 28.353512 -389.671296) (xy 65.896585 -389.671296) (xy 65.900473 -389.616941)
			(xy 65.912058 -389.563693) (xy 65.931103 -389.512636) (xy 65.957221 -389.464808) (xy 65.989879 -389.421185)
			(xy 66.028414 -389.382654) (xy 66.072041 -389.35) (xy 66.119871 -389.323887) (xy 66.17093 -389.304847)
			(xy 66.22418 -389.293267) (xy 66.278535 -389.289385) (xy 66.33289 -389.293277) (xy 66.386137 -389.304866)
			(xy 66.437193 -389.323916) (xy 66.485018 -389.350038) (xy 66.507106 -389.365998) (xy 66.526118 -389.379594)
			(xy 66.568001 -389.400326) (xy 66.612969 -389.413052) (xy 66.659506 -389.417342) (xy 66.706043 -389.413052)
			(xy 66.751011 -389.400326) (xy 66.792894 -389.379594) (xy 66.811906 -389.365998) (xy 66.833988 -389.35003)
			(xy 66.881814 -389.32391) (xy 66.93287 -389.304862) (xy 66.986117 -389.293274) (xy 67.040472 -389.289382)
			(xy 67.094827 -389.293266) (xy 67.148076 -389.304846) (xy 67.199135 -389.323886) (xy 67.246964 -389.35)
			(xy 67.29059 -389.382655) (xy 67.329124 -389.421186) (xy 67.361783 -389.464809) (xy 67.3879 -389.512636)
			(xy 67.406945 -389.563694) (xy 67.41853 -389.616942) (xy 67.422418 -389.671296) (xy 67.825667 -389.671296)
			(xy 67.829555 -389.616937) (xy 67.841141 -389.563685) (xy 67.860188 -389.512624) (xy 67.886309 -389.464793)
			(xy 67.918971 -389.421167) (xy 67.95751 -389.382634) (xy 68.00114 -389.349979) (xy 68.048975 -389.323865)
			(xy 68.100039 -389.304825) (xy 68.153292 -389.293247) (xy 68.207652 -389.289367) (xy 68.262011 -389.293262)
			(xy 68.315262 -389.304855) (xy 68.36632 -389.323908) (xy 68.414147 -389.350035) (xy 68.436236 -389.365998)
			(xy 68.455248 -389.379594) (xy 68.497131 -389.400326) (xy 68.542099 -389.413052) (xy 68.588636 -389.417342)
			(xy 68.635173 -389.413052) (xy 68.680141 -389.400326) (xy 68.722024 -389.379594) (xy 68.741036 -389.365998)
			(xy 68.76318 -389.350021) (xy 68.811092 -389.323831) (xy 68.86225 -389.304744) (xy 68.915608 -389.293149)
			(xy 68.970074 -389.289283) (xy 69.024534 -389.293227) (xy 69.077875 -389.304898) (xy 69.129006 -389.324059)
			(xy 69.176881 -389.350317) (xy 69.220521 -389.383136) (xy 69.259033 -389.421844) (xy 69.275706 -389.443468)
			(xy 69.289495 -389.461221) (xy 69.322262 -389.491988) (xy 69.359932 -389.51651) (xy 69.401328 -389.534023)
			(xy 69.445159 -389.54398) (xy 69.490058 -389.546071) (xy 69.534625 -389.54023) (xy 69.57747 -389.52664)
			(xy 69.617255 -389.505724) (xy 69.65274 -389.478135) (xy 69.668136 -389.461756) (xy 69.687455 -389.441144)
			(xy 69.731039 -389.405207) (xy 69.779446 -389.37609) (xy 69.831618 -389.354431) (xy 69.886414 -389.340702)
			(xy 69.942635 -389.335204) (xy 69.999052 -389.338058) (xy 70.054432 -389.3492) (xy 70.107562 -389.368388)
			(xy 70.157283 -389.395201) (xy 70.1802 -389.411718) (xy 70.199212 -389.425314) (xy 70.241095 -389.446046)
			(xy 70.286063 -389.458772) (xy 70.3326 -389.463062) (xy 70.379137 -389.458772) (xy 70.424105 -389.446046)
			(xy 70.465988 -389.425314) (xy 70.485 -389.411718) (xy 70.507064 -389.395723) (xy 70.554891 -389.369599)
			(xy 70.605949 -389.350548) (xy 70.659199 -389.338957) (xy 70.713556 -389.335063) (xy 70.767915 -389.338944)
			(xy 70.821167 -389.350523) (xy 70.87223 -389.369563) (xy 70.920063 -389.395676) (xy 70.963692 -389.428331)
			(xy 71.00223 -389.466863) (xy 71.034892 -389.510487) (xy 71.061013 -389.558316) (xy 71.08006 -389.609376)
			(xy 71.091647 -389.662627) (xy 71.095537 -389.716984) (xy 71.498786 -389.716984) (xy 71.502676 -389.662629)
			(xy 71.514263 -389.60938) (xy 71.533311 -389.558322) (xy 71.559431 -389.510495) (xy 71.592093 -389.466872)
			(xy 71.63063 -389.428343) (xy 71.674259 -389.39569) (xy 71.722091 -389.369579) (xy 71.773153 -389.350542)
			(xy 71.826404 -389.338966) (xy 71.880761 -389.335086) (xy 71.935116 -389.338983) (xy 71.988364 -389.350576)
			(xy 72.039419 -389.369629) (xy 72.087243 -389.395755) (xy 72.10933 -389.411718) (xy 72.128342 -389.425314)
			(xy 72.170225 -389.446046) (xy 72.215193 -389.458772) (xy 72.26173 -389.463062) (xy 72.308267 -389.458772)
			(xy 72.353235 -389.446046) (xy 72.395118 -389.425314) (xy 72.41413 -389.411718) (xy 72.436193 -389.395726)
			(xy 72.484018 -389.369606) (xy 72.535073 -389.350559) (xy 72.58832 -389.338972) (xy 72.642673 -389.335081)
			(xy 72.697027 -389.338964) (xy 72.750276 -389.350544) (xy 72.801334 -389.369584) (xy 72.849162 -389.395697)
			(xy 72.892788 -389.42835) (xy 72.931322 -389.46688) (xy 72.96398 -389.510502) (xy 72.990098 -389.558328)
			(xy 73.009144 -389.609384) (xy 73.02073 -389.662631) (xy 73.024619 -389.716984) (xy 73.020734 -389.771338)
			(xy 73.009153 -389.824586) (xy 72.990111 -389.875644) (xy 72.963997 -389.923471) (xy 72.931342 -389.967096)
			(xy 72.892811 -390.005629) (xy 72.849188 -390.038286) (xy 72.801362 -390.064403) (xy 72.750305 -390.083447)
			(xy 72.697058 -390.095031) (xy 72.642705 -390.098919) (xy 72.588351 -390.095032) (xy 72.535103 -390.08345)
			(xy 72.484046 -390.064407) (xy 72.436219 -390.038291) (xy 72.41413 -390.022334) (xy 72.395118 -390.008738)
			(xy 72.353235 -389.988006) (xy 72.308267 -389.97528) (xy 72.26173 -389.97099) (xy 72.215193 -389.97528)
			(xy 72.170225 -389.988006) (xy 72.128342 -390.008738) (xy 72.10933 -390.022334) (xy 72.087217 -390.038261)
			(xy 72.039391 -390.064384) (xy 71.988334 -390.083433) (xy 71.935085 -390.095022) (xy 71.88073 -390.098914)
			(xy 71.826373 -390.09503) (xy 71.773123 -390.08345) (xy 71.722063 -390.064408) (xy 71.674233 -390.038293)
			(xy 71.630607 -390.005637) (xy 71.592072 -389.967104) (xy 71.559414 -389.923479) (xy 71.533298 -389.87565)
			(xy 71.514254 -389.82459) (xy 71.502672 -389.771341) (xy 71.498786 -389.716984) (xy 71.095537 -389.716984)
			(xy 71.091652 -389.771342) (xy 71.080069 -389.824594) (xy 71.061026 -389.875655) (xy 71.034909 -389.923486)
			(xy 71.002251 -389.967114) (xy 70.963716 -390.005649) (xy 70.920089 -390.038307) (xy 70.872258 -390.064424)
			(xy 70.821197 -390.083468) (xy 70.767946 -390.095051) (xy 70.713588 -390.098937) (xy 70.65923 -390.095048)
			(xy 70.605979 -390.083461) (xy 70.554919 -390.064414) (xy 70.50709 -390.038294) (xy 70.485 -390.022334)
			(xy 70.465988 -390.008738) (xy 70.424105 -389.988006) (xy 70.379137 -389.97528) (xy 70.3326 -389.97099)
			(xy 70.286063 -389.97528) (xy 70.241095 -389.988006) (xy 70.199212 -390.008738) (xy 70.1802 -390.022334)
			(xy 70.158114 -390.038396) (xy 70.110193 -390.064588) (xy 70.059025 -390.083675) (xy 70.005657 -390.095267)
			(xy 69.951182 -390.099127) (xy 69.896713 -390.095176) (xy 69.843365 -390.083495) (xy 69.792229 -390.064323)
			(xy 69.744351 -390.038051) (xy 69.700711 -390.005218) (xy 69.662201 -389.966495) (xy 69.64553 -389.944864)
			(xy 69.631699 -389.927145) (xy 69.598939 -389.896375) (xy 69.561277 -389.871849) (xy 69.519887 -389.854332)
			(xy 69.47606 -389.844371) (xy 69.431165 -389.842277) (xy 69.386601 -389.848114) (xy 69.34376 -389.8617)
			(xy 69.303978 -389.882613) (xy 69.268495 -389.910199) (xy 69.2531 -389.926576) (xy 69.233843 -389.947247)
			(xy 69.190248 -389.983181) (xy 69.141831 -390.012293) (xy 69.08965 -390.033947) (xy 69.034847 -390.04767)
			(xy 68.978619 -390.053161) (xy 68.922196 -390.0503) (xy 68.866812 -390.03915) (xy 68.813677 -390.019955)
			(xy 68.763954 -389.993135) (xy 68.741036 -389.976614) (xy 68.722024 -389.963018) (xy 68.680141 -389.942286)
			(xy 68.635173 -389.92956) (xy 68.588636 -389.92527) (xy 68.542099 -389.92956) (xy 68.497131 -389.942286)
			(xy 68.455248 -389.963018) (xy 68.436236 -389.976614) (xy 68.414141 -389.992569) (xy 68.366314 -390.018695)
			(xy 68.315255 -390.037747) (xy 68.262004 -390.049339) (xy 68.207645 -390.053233) (xy 68.153285 -390.049352)
			(xy 68.100032 -390.037772) (xy 68.048968 -390.018732) (xy 68.001134 -389.992617) (xy 67.957504 -389.959961)
			(xy 67.918966 -389.921427) (xy 67.886305 -389.877801) (xy 67.860185 -389.82997) (xy 67.841139 -389.778908)
			(xy 67.829554 -389.725656) (xy 67.825667 -389.671296) (xy 67.422418 -389.671296) (xy 67.418531 -389.725651)
			(xy 67.406947 -389.778899) (xy 67.387903 -389.829957) (xy 67.361787 -389.877785) (xy 67.329129 -389.921409)
			(xy 67.290595 -389.959941) (xy 67.24697 -389.992596) (xy 67.199141 -390.018711) (xy 67.148083 -390.037752)
			(xy 67.094834 -390.049333) (xy 67.040479 -390.053218) (xy 66.986124 -390.049327) (xy 66.932877 -390.03774)
			(xy 66.88182 -390.018693) (xy 66.833994 -389.992573) (xy 66.811906 -389.976614) (xy 66.792894 -389.963018)
			(xy 66.751011 -389.942286) (xy 66.706043 -389.92956) (xy 66.659506 -389.92527) (xy 66.612969 -389.92956)
			(xy 66.568001 -389.942286) (xy 66.526118 -389.963018) (xy 66.507106 -389.976614) (xy 66.485012 -389.992566)
			(xy 66.437186 -390.018687) (xy 66.38613 -390.037736) (xy 66.332883 -390.049324) (xy 66.278528 -390.053215)
			(xy 66.224173 -390.049332) (xy 66.170923 -390.037751) (xy 66.119864 -390.01871) (xy 66.072035 -389.992596)
			(xy 66.028409 -389.959941) (xy 65.989875 -389.921409) (xy 65.957217 -389.877786) (xy 65.9311 -389.829958)
			(xy 65.912056 -389.7789) (xy 65.900472 -389.725651) (xy 65.896585 -389.671296) (xy 28.353512 -389.671296)
			(xy 28.353512 -391.428018) (xy 65.896556 -391.428018) (xy 65.900441 -391.373659) (xy 65.912024 -391.320406)
			(xy 65.931067 -391.269343) (xy 65.957185 -391.221511) (xy 65.989843 -391.177883) (xy 66.028379 -391.139346)
			(xy 66.072007 -391.106687) (xy 66.119839 -391.080569) (xy 66.170901 -391.061525) (xy 66.224154 -391.049942)
			(xy 66.278513 -391.046056) (xy 66.332872 -391.049946) (xy 66.386124 -391.061533) (xy 66.437185 -391.080581)
			(xy 66.485016 -391.106702) (xy 66.507106 -391.122662) (xy 66.526118 -391.136258) (xy 66.568001 -391.15699)
			(xy 66.612969 -391.169716) (xy 66.659506 -391.174006) (xy 66.706043 -391.169716) (xy 66.751011 -391.15699)
			(xy 66.792894 -391.136258) (xy 66.811906 -391.122662) (xy 66.834022 -391.106743) (xy 66.881845 -391.080627)
			(xy 66.932899 -391.061583) (xy 66.986143 -391.049999) (xy 67.040493 -391.046111) (xy 67.094844 -391.049998)
			(xy 67.148088 -391.06158) (xy 67.199142 -391.080622) (xy 67.246967 -391.106736) (xy 67.290588 -391.139391)
			(xy 67.329117 -391.177921) (xy 67.36177 -391.221543) (xy 67.387883 -391.269368) (xy 67.406924 -391.320422)
			(xy 67.418504 -391.373667) (xy 67.422389 -391.428018) (xy 67.825638 -391.428018) (xy 67.829524 -391.373655)
			(xy 67.841107 -391.320398) (xy 67.860153 -391.269332) (xy 67.886273 -391.221496) (xy 67.918935 -391.177865)
			(xy 67.957474 -391.139327) (xy 68.001107 -391.106666) (xy 68.048943 -391.080548) (xy 68.10001 -391.061504)
			(xy 68.153267 -391.049922) (xy 68.207631 -391.046038) (xy 68.261993 -391.049931) (xy 68.315249 -391.061521)
			(xy 68.366313 -391.080573) (xy 68.414145 -391.106699) (xy 68.436236 -391.122662) (xy 68.455248 -391.136258)
			(xy 68.497131 -391.15699) (xy 68.542099 -391.169716) (xy 68.588636 -391.174006) (xy 68.635173 -391.169716)
			(xy 68.680141 -391.15699) (xy 68.722024 -391.136258) (xy 68.741036 -391.122662) (xy 68.763171 -391.106671)
			(xy 68.811084 -391.080477) (xy 68.862244 -391.061385) (xy 68.915604 -391.049788) (xy 68.970072 -391.045922)
			(xy 69.024535 -391.049866) (xy 69.077879 -391.061539) (xy 69.129011 -391.080703) (xy 69.176886 -391.106966)
			(xy 69.220525 -391.139791) (xy 69.259035 -391.178505) (xy 69.275706 -391.200132) (xy 69.289496 -391.217885)
			(xy 69.322261 -391.248656) (xy 69.35993 -391.273182) (xy 69.401326 -391.290697) (xy 69.445159 -391.300656)
			(xy 69.490059 -391.302747) (xy 69.534627 -391.296905) (xy 69.577472 -391.283312) (xy 69.617257 -391.262393)
			(xy 69.652741 -391.234801) (xy 69.668136 -391.21842) (xy 69.687452 -391.197806) (xy 69.731038 -391.161872)
			(xy 69.779446 -391.132758) (xy 69.831618 -391.1111) (xy 69.886414 -391.097373) (xy 69.942634 -391.091876)
			(xy 69.999051 -391.094729) (xy 70.05443 -391.10587) (xy 70.107561 -391.125056) (xy 70.157282 -391.151866)
			(xy 70.1802 -391.168382) (xy 70.199212 -391.181978) (xy 70.241095 -391.20271) (xy 70.286063 -391.215436)
			(xy 70.3326 -391.219726) (xy 70.379137 -391.215436) (xy 70.424105 -391.20271) (xy 70.465988 -391.181978)
			(xy 70.485 -391.168382) (xy 70.507098 -391.152436) (xy 70.554922 -391.126316) (xy 70.605978 -391.107269)
			(xy 70.659224 -391.095682) (xy 70.713578 -391.091791) (xy 70.767932 -391.095676) (xy 70.82118 -391.107257)
			(xy 70.872237 -391.126298) (xy 70.920065 -391.152412) (xy 70.96369 -391.185067) (xy 71.002223 -391.223598)
			(xy 71.03488 -391.267221) (xy 71.060996 -391.315048) (xy 71.080039 -391.366105) (xy 71.091622 -391.419352)
			(xy 71.095509 -391.473706) (xy 71.498757 -391.473706) (xy 71.502645 -391.419346) (xy 71.514229 -391.366092)
			(xy 71.533275 -391.31503) (xy 71.559395 -391.267198) (xy 71.592057 -391.22357) (xy 71.630595 -391.185035)
			(xy 71.674225 -391.152377) (xy 71.72206 -391.126262) (xy 71.773124 -391.10722) (xy 71.826379 -391.09564)
			(xy 71.880739 -391.091757) (xy 71.935099 -391.095651) (xy 71.988351 -391.107242) (xy 72.039411 -391.126294)
			(xy 72.08724 -391.15242) (xy 72.10933 -391.168382) (xy 72.128342 -391.181978) (xy 72.170225 -391.20271)
			(xy 72.215193 -391.215436) (xy 72.26173 -391.219726) (xy 72.308267 -391.215436) (xy 72.353235 -391.20271)
			(xy 72.395118 -391.181978) (xy 72.41413 -391.168382) (xy 72.436227 -391.152438) (xy 72.48405 -391.126323)
			(xy 72.535102 -391.107281) (xy 72.588345 -391.095697) (xy 72.642695 -391.091809) (xy 72.697045 -391.095696)
			(xy 72.750288 -391.107278) (xy 72.801341 -391.126319) (xy 72.849165 -391.152433) (xy 72.892785 -391.185086)
			(xy 72.931314 -391.223616) (xy 72.963968 -391.267236) (xy 72.990081 -391.31506) (xy 73.009122 -391.366113)
			(xy 73.020704 -391.419356) (xy 73.024591 -391.473706) (xy 73.020702 -391.528056) (xy 73.009119 -391.581299)
			(xy 72.990076 -391.632351) (xy 72.963961 -391.680174) (xy 72.931306 -391.723793) (xy 72.892776 -391.762321)
			(xy 72.849155 -391.794974) (xy 72.80133 -391.821086) (xy 72.750277 -391.840126) (xy 72.697033 -391.851706)
			(xy 72.642683 -391.855591) (xy 72.588334 -391.851701) (xy 72.535091 -391.840116) (xy 72.484039 -391.821072)
			(xy 72.436217 -391.794955) (xy 72.41413 -391.778998) (xy 72.395118 -391.765402) (xy 72.353235 -391.74467)
			(xy 72.308267 -391.731944) (xy 72.26173 -391.727654) (xy 72.215193 -391.731944) (xy 72.170225 -391.74467)
			(xy 72.128342 -391.765402) (xy 72.10933 -391.778998) (xy 72.087251 -391.794974) (xy 72.039422 -391.821101)
			(xy 71.988363 -391.840154) (xy 71.935111 -391.851747) (xy 71.880751 -391.855643) (xy 71.82639 -391.851762)
			(xy 71.773136 -391.840183) (xy 71.722071 -391.821143) (xy 71.674235 -391.795029) (xy 71.630604 -391.762373)
			(xy 71.592064 -391.723839) (xy 71.559402 -391.680213) (xy 71.53328 -391.632381) (xy 71.514233 -391.581319)
			(xy 71.502647 -391.528066) (xy 71.498757 -391.473706) (xy 71.095509 -391.473706) (xy 71.09162 -391.52806)
			(xy 71.080035 -391.581307) (xy 71.060991 -391.632363) (xy 71.034873 -391.680189) (xy 71.002215 -391.723811)
			(xy 70.963681 -391.762341) (xy 70.920055 -391.794995) (xy 70.872227 -391.821107) (xy 70.821168 -391.840147)
			(xy 70.76792 -391.851726) (xy 70.713566 -391.855609) (xy 70.659213 -391.851716) (xy 70.605966 -391.840128)
			(xy 70.554912 -391.821079) (xy 70.507087 -391.794958) (xy 70.485 -391.778998) (xy 70.465988 -391.765402)
			(xy 70.424105 -391.74467) (xy 70.379137 -391.731944) (xy 70.3326 -391.727654) (xy 70.286063 -391.731944)
			(xy 70.241095 -391.74467) (xy 70.199212 -391.765402) (xy 70.1802 -391.778998) (xy 70.158106 -391.795047)
			(xy 70.110185 -391.821233) (xy 70.059018 -391.840317) (xy 70.005653 -391.851906) (xy 69.95118 -391.855766)
			(xy 69.896714 -391.851815) (xy 69.843368 -391.840136) (xy 69.792234 -391.820967) (xy 69.744356 -391.7947)
			(xy 69.700715 -391.761873) (xy 69.662203 -391.723156) (xy 69.64553 -391.701528) (xy 69.631699 -391.68381)
			(xy 69.598938 -391.653044) (xy 69.561275 -391.628521) (xy 69.519885 -391.611007) (xy 69.47606 -391.601047)
			(xy 69.431166 -391.598952) (xy 69.386603 -391.604789) (xy 69.343763 -391.618373) (xy 69.30398 -391.639283)
			(xy 69.268496 -391.666865) (xy 69.2531 -391.68324) (xy 69.23384 -391.70391) (xy 69.190247 -391.739846)
			(xy 69.141831 -391.768961) (xy 69.08965 -391.790617) (xy 69.034847 -391.80434) (xy 68.978618 -391.809832)
			(xy 68.922195 -391.806971) (xy 68.86681 -391.79582) (xy 68.813676 -391.776623) (xy 68.763954 -391.7498)
			(xy 68.741036 -391.733278) (xy 68.722024 -391.719682) (xy 68.680141 -391.69895) (xy 68.635173 -391.686224)
			(xy 68.588636 -391.681934) (xy 68.542099 -391.686224) (xy 68.497131 -391.69895) (xy 68.455248 -391.719682)
			(xy 68.436236 -391.733278) (xy 68.414175 -391.749281) (xy 68.366345 -391.775412) (xy 68.315283 -391.794469)
			(xy 68.262029 -391.806064) (xy 68.207667 -391.809962) (xy 68.153303 -391.806083) (xy 68.100044 -391.794506)
			(xy 68.048976 -391.775467) (xy 68.001137 -391.749353) (xy 67.957502 -391.716697) (xy 67.918959 -391.678162)
			(xy 67.886292 -391.634534) (xy 67.860168 -391.586701) (xy 67.841118 -391.535637) (xy 67.829529 -391.482381)
			(xy 67.825638 -391.428018) (xy 67.422389 -391.428018) (xy 67.418499 -391.482368) (xy 67.406913 -391.535612)
			(xy 67.387868 -391.586665) (xy 67.361751 -391.634487) (xy 67.329093 -391.678106) (xy 67.29056 -391.716633)
			(xy 67.246936 -391.749284) (xy 67.19911 -391.775393) (xy 67.148054 -391.79443) (xy 67.094808 -391.806008)
			(xy 67.040457 -391.809889) (xy 66.986107 -391.805995) (xy 66.932864 -391.794406) (xy 66.881813 -391.775358)
			(xy 66.833992 -391.749238) (xy 66.811906 -391.733278) (xy 66.792894 -391.719682) (xy 66.751011 -391.69895)
			(xy 66.706043 -391.686224) (xy 66.659506 -391.681934) (xy 66.612969 -391.686224) (xy 66.568001 -391.69895)
			(xy 66.526118 -391.719682) (xy 66.507106 -391.733278) (xy 66.485046 -391.749279) (xy 66.437218 -391.775404)
			(xy 66.386159 -391.794457) (xy 66.332908 -391.806049) (xy 66.278549 -391.809944) (xy 66.22419 -391.806063)
			(xy 66.170936 -391.794485) (xy 66.119872 -391.775446) (xy 66.072037 -391.749332) (xy 66.028406 -391.716677)
			(xy 65.989867 -391.678145) (xy 65.957204 -391.634519) (xy 65.931082 -391.58669) (xy 65.912034 -391.535629)
			(xy 65.900446 -391.482377) (xy 65.896556 -391.428018) (xy 28.353512 -391.428018) (xy 28.353512 -393.194476)
			(xy 65.896612 -393.194476) (xy 65.900503 -393.140125) (xy 65.912089 -393.086881) (xy 65.931136 -393.035828)
			(xy 65.957254 -392.988006) (xy 65.989913 -392.944388) (xy 66.028448 -392.905861) (xy 66.072073 -392.873211)
			(xy 66.119901 -392.847103) (xy 66.170957 -392.828067) (xy 66.224204 -392.816491) (xy 66.278555 -392.812612)
			(xy 66.332906 -392.816507) (xy 66.386149 -392.828098) (xy 66.4372 -392.847149) (xy 66.485021 -392.873271)
			(xy 66.507106 -392.889232) (xy 66.526118 -392.902828) (xy 66.568001 -392.92356) (xy 66.612969 -392.936286)
			(xy 66.659506 -392.940576) (xy 66.706043 -392.936286) (xy 66.751011 -392.92356) (xy 66.792894 -392.902828)
			(xy 66.811906 -392.889232) (xy 66.833957 -392.873219) (xy 66.881784 -392.847094) (xy 66.932843 -392.828041)
			(xy 66.986093 -392.81645) (xy 67.040451 -392.812555) (xy 67.094811 -392.816436) (xy 67.148064 -392.828014)
			(xy 67.199128 -392.847053) (xy 67.246962 -392.873166) (xy 67.290592 -392.905821) (xy 67.329132 -392.944353)
			(xy 67.361795 -392.987977) (xy 67.387917 -393.035806) (xy 67.406965 -393.086866) (xy 67.418554 -393.140118)
			(xy 67.422445 -393.194476) (xy 67.825694 -393.194476) (xy 67.829585 -393.140121) (xy 67.841173 -393.086873)
			(xy 67.860221 -393.035817) (xy 67.886343 -392.987991) (xy 67.919005 -392.94437) (xy 67.957543 -392.905842)
			(xy 68.001172 -392.87319) (xy 68.049004 -392.847081) (xy 68.100066 -392.828046) (xy 68.153317 -392.816471)
			(xy 68.207673 -392.812594) (xy 68.262027 -392.816492) (xy 68.315273 -392.828087) (xy 68.366328 -392.847142)
			(xy 68.41415 -392.873269) (xy 68.436236 -392.889232) (xy 68.455248 -392.902828) (xy 68.497131 -392.92356)
			(xy 68.542099 -392.936286) (xy 68.588636 -392.940576) (xy 68.635173 -392.936286) (xy 68.680141 -392.92356)
			(xy 68.722024 -392.902828) (xy 68.741036 -392.889232) (xy 68.763175 -392.873247) (xy 68.811088 -392.847055)
			(xy 68.862247 -392.827966) (xy 68.915606 -392.816369) (xy 68.970073 -392.812504) (xy 69.024535 -392.816447)
			(xy 69.077877 -392.82812) (xy 69.129009 -392.847283) (xy 69.176884 -392.873543) (xy 69.220523 -392.906365)
			(xy 69.259034 -392.945076) (xy 69.275706 -392.966702) (xy 69.289496 -392.984455) (xy 69.32226 -393.015229)
			(xy 69.359928 -393.039758) (xy 69.401325 -393.057276) (xy 69.445158 -393.067235) (xy 69.49006 -393.069326)
			(xy 69.534629 -393.063484) (xy 69.577474 -393.04989) (xy 69.617259 -393.028968) (xy 69.652742 -393.001372)
			(xy 69.668136 -392.98499) (xy 69.68745 -392.964375) (xy 69.731038 -392.928443) (xy 69.779446 -392.899331)
			(xy 69.831619 -392.877675) (xy 69.886414 -392.863949) (xy 69.942634 -392.858452) (xy 69.99905 -392.861304)
			(xy 70.054429 -392.872445) (xy 70.10756 -392.891629) (xy 70.157282 -392.918437) (xy 70.1802 -392.934952)
			(xy 70.199212 -392.948548) (xy 70.241095 -392.96928) (xy 70.286063 -392.982006) (xy 70.3326 -392.986296)
			(xy 70.379137 -392.982006) (xy 70.424105 -392.96928) (xy 70.465988 -392.948548) (xy 70.485 -392.934952)
			(xy 70.507126 -392.919046) (xy 70.554949 -392.89293) (xy 70.606002 -392.873887) (xy 70.659246 -392.862303)
			(xy 70.713596 -392.858415) (xy 70.767946 -392.862302) (xy 70.82119 -392.873885) (xy 70.872244 -392.892927)
			(xy 70.920068 -392.919042) (xy 70.963688 -392.951697) (xy 71.002216 -392.990227) (xy 71.034869 -393.033849)
			(xy 71.060981 -393.081674) (xy 71.080021 -393.132729) (xy 71.091601 -393.185973) (xy 71.095485 -393.240324)
			(xy 71.498733 -393.240324) (xy 71.502619 -393.18596) (xy 71.514201 -393.132703) (xy 71.533246 -393.081636)
			(xy 71.559365 -393.0338) (xy 71.592027 -392.990168) (xy 71.630566 -392.951629) (xy 71.674197 -392.918967)
			(xy 71.722033 -392.892847) (xy 71.7731 -392.873802) (xy 71.826357 -392.862219) (xy 71.880721 -392.858333)
			(xy 71.935084 -392.862225) (xy 71.988341 -392.873814) (xy 72.039405 -392.892865) (xy 72.087238 -392.91899)
			(xy 72.10933 -392.934952) (xy 72.128342 -392.948548) (xy 72.170225 -392.96928) (xy 72.215193 -392.982006)
			(xy 72.26173 -392.986296) (xy 72.308267 -392.982006) (xy 72.353235 -392.96928) (xy 72.395118 -392.948548)
			(xy 72.41413 -392.934952) (xy 72.436255 -392.919049) (xy 72.484076 -392.892938) (xy 72.535126 -392.873899)
			(xy 72.588367 -392.862319) (xy 72.642713 -392.858433) (xy 72.697059 -392.862322) (xy 72.750299 -392.873906)
			(xy 72.801348 -392.892949) (xy 72.849167 -392.919063) (xy 72.892783 -392.951716) (xy 72.931308 -392.990245)
			(xy 72.963957 -393.033864) (xy 72.990067 -393.081686) (xy 73.009104 -393.132737) (xy 73.020683 -393.185977)
			(xy 73.024567 -393.240324) (xy 73.020676 -393.29467) (xy 73.009091 -393.347909) (xy 72.990047 -393.398958)
			(xy 72.963931 -393.446776) (xy 72.931276 -393.490391) (xy 72.892747 -393.528915) (xy 72.849127 -393.561563)
			(xy 72.801304 -393.587671) (xy 72.750253 -393.606708) (xy 72.697012 -393.618285) (xy 72.642665 -393.622167)
			(xy 72.588319 -393.618275) (xy 72.53508 -393.606688) (xy 72.484032 -393.587642) (xy 72.436215 -393.561525)
			(xy 72.41413 -393.545568) (xy 72.395118 -393.531972) (xy 72.353235 -393.51124) (xy 72.308267 -393.498514)
			(xy 72.26173 -393.494224) (xy 72.215193 -393.498514) (xy 72.170225 -393.51124) (xy 72.128342 -393.531972)
			(xy 72.10933 -393.545568) (xy 72.087279 -393.561584) (xy 72.039449 -393.587715) (xy 71.988387 -393.606772)
			(xy 71.935132 -393.618368) (xy 71.880769 -393.622267) (xy 71.826405 -393.618388) (xy 71.773146 -393.606811)
			(xy 71.722077 -393.587773) (xy 71.674238 -393.561659) (xy 71.630602 -393.529003) (xy 71.592058 -393.490469)
			(xy 71.559391 -393.446841) (xy 71.533266 -393.399008) (xy 71.514215 -393.347943) (xy 71.502625 -393.294687)
			(xy 71.498733 -393.240324) (xy 71.095485 -393.240324) (xy 71.091594 -393.294674) (xy 71.080007 -393.347917)
			(xy 71.060961 -393.398969) (xy 71.034843 -393.446791) (xy 71.002185 -393.490409) (xy 70.963651 -393.528935)
			(xy 70.920027 -393.561584) (xy 70.8722 -393.587693) (xy 70.821144 -393.606729) (xy 70.767899 -393.618305)
			(xy 70.713548 -393.622184) (xy 70.659198 -393.61829) (xy 70.605956 -393.606699) (xy 70.554905 -393.58765)
			(xy 70.507085 -393.561528) (xy 70.485 -393.545568) (xy 70.465988 -393.531972) (xy 70.424105 -393.51124)
			(xy 70.379137 -393.498514) (xy 70.3326 -393.494224) (xy 70.286063 -393.498514) (xy 70.241095 -393.51124)
			(xy 70.199212 -393.531972) (xy 70.1802 -393.545568) (xy 70.15811 -393.561623) (xy 70.110188 -393.587812)
			(xy 70.059021 -393.606897) (xy 70.005655 -393.618488) (xy 69.951181 -393.622348) (xy 69.896713 -393.618397)
			(xy 69.843366 -393.606717) (xy 69.792231 -393.587546) (xy 69.744354 -393.561277) (xy 69.700713 -393.528447)
			(xy 69.662202 -393.489728) (xy 69.64553 -393.468098) (xy 69.631698 -393.450379) (xy 69.59894 -393.419605)
			(xy 69.561279 -393.395076) (xy 69.519888 -393.377557) (xy 69.476061 -393.367594) (xy 69.431164 -393.365499)
			(xy 69.3866 -393.371337) (xy 69.343758 -393.384926) (xy 69.303975 -393.405842) (xy 69.268494 -393.433431)
			(xy 69.2531 -393.44981) (xy 69.233845 -393.470483) (xy 69.190249 -393.506414) (xy 69.141831 -393.535524)
			(xy 69.08965 -393.557176) (xy 69.034847 -393.570897) (xy 68.978619 -393.576388) (xy 68.922197 -393.573528)
			(xy 68.866813 -393.562379) (xy 68.813679 -393.543186) (xy 68.763955 -393.516368) (xy 68.741036 -393.499848)
			(xy 68.722024 -393.486252) (xy 68.680141 -393.46552) (xy 68.635173 -393.452794) (xy 68.588636 -393.448504)
			(xy 68.542099 -393.452794) (xy 68.497131 -393.46552) (xy 68.455248 -393.486252) (xy 68.436236 -393.499848)
			(xy 68.414109 -393.515757) (xy 68.366284 -393.541878) (xy 68.315227 -393.560927) (xy 68.26198 -393.572515)
			(xy 68.207625 -393.576406) (xy 68.153269 -393.572522) (xy 68.10002 -393.560941) (xy 68.048961 -393.541899)
			(xy 68.001132 -393.515784) (xy 67.957507 -393.483127) (xy 67.918973 -393.444594) (xy 67.886317 -393.400969)
			(xy 67.860202 -393.35314) (xy 67.84116 -393.302081) (xy 67.829578 -393.248832) (xy 67.825694 -393.194476)
			(xy 67.422445 -393.194476) (xy 67.41856 -393.248835) (xy 67.406979 -393.302088) (xy 67.387937 -393.35315)
			(xy 67.361821 -393.400982) (xy 67.329163 -393.444611) (xy 67.290629 -393.483148) (xy 67.247002 -393.515808)
			(xy 67.199171 -393.541927) (xy 67.14811 -393.560972) (xy 67.094858 -393.572557) (xy 67.040499 -393.576445)
			(xy 66.986141 -393.572557) (xy 66.932889 -393.560972) (xy 66.881828 -393.541926) (xy 66.833997 -393.515807)
			(xy 66.811906 -393.499848) (xy 66.792894 -393.486252) (xy 66.751011 -393.46552) (xy 66.706043 -393.452794)
			(xy 66.659506 -393.448504) (xy 66.612969 -393.452794) (xy 66.568001 -393.46552) (xy 66.526118 -393.486252)
			(xy 66.507106 -393.499848) (xy 66.48498 -393.515755) (xy 66.437157 -393.541871) (xy 66.386103 -393.560915)
			(xy 66.332859 -393.5725) (xy 66.278507 -393.576388) (xy 66.224156 -393.572502) (xy 66.170911 -393.560919)
			(xy 66.119857 -393.541877) (xy 66.072032 -393.515763) (xy 66.028411 -393.483107) (xy 65.989882 -393.444576)
			(xy 65.957228 -393.400954) (xy 65.931116 -393.353128) (xy 65.912076 -393.302073) (xy 65.900496 -393.248827)
			(xy 65.896612 -393.194476) (xy 28.353512 -393.194476) (xy 28.353512 -394.722604) (xy 51.208432 -394.722604)
			(xy 52.85994 -394.722604) (xy 52.85994 -396.374112) (xy 51.208432 -396.374112) (xy 51.208432 -394.722604)
			(xy 28.353512 -394.722604) (xy 28.353512 -395.588913) (xy 47.708556 -395.588913) (xy 47.708556 -395.507803)
			(xy 47.716506 -395.427084) (xy 47.732329 -395.347533) (xy 47.755874 -395.269917) (xy 47.786913 -395.194981)
			(xy 47.825148 -395.123449) (xy 47.87021 -395.056009) (xy 47.921665 -394.99331) (xy 47.979018 -394.935957)
			(xy 48.041717 -394.884502) (xy 48.109157 -394.83944) (xy 48.180689 -394.801205) (xy 48.255625 -394.770166)
			(xy 48.333241 -394.746621) (xy 48.412792 -394.730798) (xy 48.493511 -394.722848) (xy 48.574621 -394.722848)
			(xy 48.65534 -394.730798) (xy 48.734891 -394.746621) (xy 48.812507 -394.770166) (xy 48.887443 -394.801205)
			(xy 48.958975 -394.83944) (xy 49.026415 -394.884502) (xy 49.089114 -394.935957) (xy 49.146467 -394.99331)
			(xy 49.197922 -395.056009) (xy 49.242984 -395.123449) (xy 49.281219 -395.194981) (xy 49.312258 -395.269917)
			(xy 49.335803 -395.347533) (xy 49.351626 -395.427084) (xy 49.359576 -395.507803) (xy 49.360074 -395.548358)
			(xy 49.359576 -395.588913) (xy 49.351626 -395.669632) (xy 49.335803 -395.749183) (xy 49.312258 -395.826799)
			(xy 49.281219 -395.901735) (xy 49.242984 -395.973267) (xy 49.197922 -396.040707) (xy 49.146467 -396.103406)
			(xy 49.089114 -396.160759) (xy 49.026415 -396.212214) (xy 48.958975 -396.257276) (xy 48.887443 -396.295511)
			(xy 48.812507 -396.32655) (xy 48.734891 -396.350095) (xy 48.65534 -396.365918) (xy 48.574621 -396.373868)
			(xy 48.493511 -396.373868) (xy 48.412792 -396.365918) (xy 48.333241 -396.350095) (xy 48.255625 -396.32655)
			(xy 48.180689 -396.295511) (xy 48.109157 -396.257276) (xy 48.041717 -396.212214) (xy 47.979018 -396.160759)
			(xy 47.921665 -396.103406) (xy 47.87021 -396.040707) (xy 47.825148 -395.973267) (xy 47.786913 -395.901735)
			(xy 47.755874 -395.826799) (xy 47.732329 -395.749183) (xy 47.716506 -395.669632) (xy 47.708556 -395.588913)
			(xy 28.353512 -395.588913) (xy 28.353512 -397.968212) (xy 84.245178 -397.968212) (xy 84.245178 -397.908276)
			(xy 84.253001 -397.848854) (xy 84.268514 -397.790961) (xy 84.29145 -397.735588) (xy 84.321417 -397.683682)
			(xy 84.357904 -397.636132) (xy 84.400284 -397.593752) (xy 84.447834 -397.557265) (xy 84.49974 -397.527298)
			(xy 84.555113 -397.504362) (xy 84.613006 -397.488849) (xy 84.672428 -397.481026) (xy 84.732364 -397.481026)
			(xy 84.791786 -397.488849) (xy 84.849679 -397.504362) (xy 84.905052 -397.527298) (xy 84.956958 -397.557265)
			(xy 85.004508 -397.593752) (xy 85.046888 -397.636132) (xy 85.083375 -397.683682) (xy 85.113342 -397.735588)
			(xy 85.136278 -397.790961) (xy 85.144434 -397.8214) (xy 92.971348 -397.8214) (xy 92.971348 -397.761464)
			(xy 92.979171 -397.702042) (xy 92.994684 -397.644149) (xy 93.01762 -397.588776) (xy 93.047587 -397.53687)
			(xy 93.084074 -397.48932) (xy 93.126454 -397.44694) (xy 93.174004 -397.410453) (xy 93.22591 -397.380486)
			(xy 93.281283 -397.35755) (xy 93.339176 -397.342037) (xy 93.398598 -397.334214) (xy 93.458534 -397.334214)
			(xy 93.517956 -397.342037) (xy 93.575849 -397.35755) (xy 93.631222 -397.380486) (xy 93.683128 -397.410453)
			(xy 93.730678 -397.44694) (xy 93.773058 -397.48932) (xy 93.809545 -397.53687) (xy 93.839512 -397.588776)
			(xy 93.862448 -397.644149) (xy 93.877961 -397.702042) (xy 93.885784 -397.761464) (xy 93.886274 -397.791432)
			(xy 93.885784 -397.8214) (xy 93.877961 -397.880822) (xy 93.862448 -397.938715) (xy 93.839512 -397.994088)
			(xy 93.809545 -398.045994) (xy 93.773058 -398.093544) (xy 93.730678 -398.135924) (xy 93.683128 -398.172411)
			(xy 93.631222 -398.202378) (xy 93.575849 -398.225314) (xy 93.517956 -398.240827) (xy 93.458534 -398.24865)
			(xy 93.398598 -398.24865) (xy 93.339176 -398.240827) (xy 93.281283 -398.225314) (xy 93.22591 -398.202378)
			(xy 93.174004 -398.172411) (xy 93.126454 -398.135924) (xy 93.084074 -398.093544) (xy 93.047587 -398.045994)
			(xy 93.01762 -397.994088) (xy 92.994684 -397.938715) (xy 92.979171 -397.880822) (xy 92.971348 -397.8214)
			(xy 85.144434 -397.8214) (xy 85.151791 -397.848854) (xy 85.159614 -397.908276) (xy 85.160104 -397.938244)
			(xy 85.159614 -397.968212) (xy 85.151791 -398.027634) (xy 85.136278 -398.085527) (xy 85.113342 -398.1409)
			(xy 85.083375 -398.192806) (xy 85.046888 -398.240356) (xy 85.004508 -398.282736) (xy 84.956958 -398.319223)
			(xy 84.905052 -398.34919) (xy 84.849679 -398.372126) (xy 84.791786 -398.387639) (xy 84.732364 -398.395462)
			(xy 84.672428 -398.395462) (xy 84.613006 -398.387639) (xy 84.555113 -398.372126) (xy 84.49974 -398.34919)
			(xy 84.447834 -398.319223) (xy 84.400284 -398.282736) (xy 84.357904 -398.240356) (xy 84.321417 -398.192806)
			(xy 84.29145 -398.1409) (xy 84.268514 -398.085527) (xy 84.253001 -398.027634) (xy 84.245178 -397.968212)
			(xy 28.353512 -397.968212) (xy 28.353512 -399.044664) (xy 81.767662 -399.044664) (xy 81.767662 -398.984728)
			(xy 81.775485 -398.925306) (xy 81.790998 -398.867413) (xy 81.813934 -398.81204) (xy 81.843901 -398.760134)
			(xy 81.880388 -398.712584) (xy 81.922768 -398.670204) (xy 81.970318 -398.633717) (xy 82.022224 -398.60375)
			(xy 82.077597 -398.580814) (xy 82.13549 -398.565301) (xy 82.194912 -398.557478) (xy 82.254848 -398.557478)
			(xy 82.31427 -398.565301) (xy 82.372163 -398.580814) (xy 82.427536 -398.60375) (xy 82.479442 -398.633717)
			(xy 82.526992 -398.670204) (xy 82.569372 -398.712584) (xy 82.605859 -398.760134) (xy 82.635826 -398.81204)
			(xy 82.658762 -398.867413) (xy 82.674275 -398.925306) (xy 82.682098 -398.984728) (xy 82.682588 -399.014696)
			(xy 82.682098 -399.044664) (xy 82.674275 -399.104086) (xy 82.658762 -399.161979) (xy 82.635826 -399.217352)
			(xy 82.605859 -399.269258) (xy 82.569372 -399.316808) (xy 82.526992 -399.359188) (xy 82.479442 -399.395675)
			(xy 82.427536 -399.425642) (xy 82.372163 -399.448578) (xy 82.31427 -399.464091) (xy 82.254848 -399.471914)
			(xy 82.194912 -399.471914) (xy 82.13549 -399.464091) (xy 82.077597 -399.448578) (xy 82.022224 -399.425642)
			(xy 81.970318 -399.395675) (xy 81.922768 -399.359188) (xy 81.880388 -399.316808) (xy 81.843901 -399.269258)
			(xy 81.813934 -399.217352) (xy 81.790998 -399.161979) (xy 81.775485 -399.104086) (xy 81.767662 -399.044664)
			(xy 28.353512 -399.044664) (xy 28.353512 -399.774406) (xy 84.877384 -399.774406) (xy 84.877384 -399.71447)
			(xy 84.885207 -399.655048) (xy 84.90072 -399.597155) (xy 84.923656 -399.541782) (xy 84.953623 -399.489876)
			(xy 84.99011 -399.442326) (xy 85.03249 -399.399946) (xy 85.08004 -399.363459) (xy 85.131946 -399.333492)
			(xy 85.187319 -399.310556) (xy 85.245212 -399.295043) (xy 85.304634 -399.28722) (xy 85.36457 -399.28722)
			(xy 85.423992 -399.295043) (xy 85.481885 -399.310556) (xy 85.537258 -399.333492) (xy 85.545565 -399.338288)
			(xy 86.76689 -399.338288) (xy 86.76689 -399.278352) (xy 86.774713 -399.21893) (xy 86.790226 -399.161037)
			(xy 86.813162 -399.105664) (xy 86.843129 -399.053758) (xy 86.879616 -399.006208) (xy 86.921996 -398.963828)
			(xy 86.969546 -398.927341) (xy 87.021452 -398.897374) (xy 87.076825 -398.874438) (xy 87.134718 -398.858925)
			(xy 87.19414 -398.851102) (xy 87.254076 -398.851102) (xy 87.302416 -398.857466) (xy 88.115122 -398.857466)
			(xy 88.115122 -398.79753) (xy 88.122945 -398.738108) (xy 88.138458 -398.680215) (xy 88.161394 -398.624842)
			(xy 88.191361 -398.572936) (xy 88.227848 -398.525386) (xy 88.270228 -398.483006) (xy 88.317778 -398.446519)
			(xy 88.369684 -398.416552) (xy 88.425057 -398.393616) (xy 88.48295 -398.378103) (xy 88.542372 -398.37028)
			(xy 88.602308 -398.37028) (xy 88.66173 -398.378103) (xy 88.719623 -398.393616) (xy 88.774996 -398.416552)
			(xy 88.826902 -398.446519) (xy 88.874452 -398.483006) (xy 88.916832 -398.525386) (xy 88.918859 -398.528028)
			(xy 91.239576 -398.528028) (xy 91.239576 -398.468092) (xy 91.247399 -398.40867) (xy 91.262912 -398.350777)
			(xy 91.285848 -398.295404) (xy 91.315815 -398.243498) (xy 91.352302 -398.195948) (xy 91.394682 -398.153568)
			(xy 91.442232 -398.117081) (xy 91.494138 -398.087114) (xy 91.549511 -398.064178) (xy 91.607404 -398.048665)
			(xy 91.666826 -398.040842) (xy 91.726762 -398.040842) (xy 91.786184 -398.048665) (xy 91.844077 -398.064178)
			(xy 91.89945 -398.087114) (xy 91.951356 -398.117081) (xy 91.998906 -398.153568) (xy 92.041286 -398.195948)
			(xy 92.077773 -398.243498) (xy 92.10774 -398.295404) (xy 92.130676 -398.350777) (xy 92.146189 -398.40867)
			(xy 92.154012 -398.468092) (xy 92.154502 -398.49806) (xy 92.154012 -398.528028) (xy 92.146189 -398.58745)
			(xy 92.130676 -398.645343) (xy 92.10774 -398.700716) (xy 92.077773 -398.752622) (xy 92.041286 -398.800172)
			(xy 91.998906 -398.842552) (xy 91.951356 -398.879039) (xy 91.89945 -398.909006) (xy 91.844077 -398.931942)
			(xy 91.786184 -398.947455) (xy 91.726762 -398.955278) (xy 91.666826 -398.955278) (xy 91.607404 -398.947455)
			(xy 91.549511 -398.931942) (xy 91.494138 -398.909006) (xy 91.442232 -398.879039) (xy 91.394682 -398.842552)
			(xy 91.352302 -398.800172) (xy 91.315815 -398.752622) (xy 91.285848 -398.700716) (xy 91.262912 -398.645343)
			(xy 91.247399 -398.58745) (xy 91.239576 -398.528028) (xy 88.918859 -398.528028) (xy 88.953319 -398.572936)
			(xy 88.983286 -398.624842) (xy 89.006222 -398.680215) (xy 89.021735 -398.738108) (xy 89.029558 -398.79753)
			(xy 89.030048 -398.827498) (xy 89.029558 -398.857466) (xy 89.021735 -398.916888) (xy 89.006222 -398.974781)
			(xy 88.983286 -399.030154) (xy 88.965231 -399.061428) (xy 89.805238 -399.061428) (xy 89.805238 -399.001492)
			(xy 89.813061 -398.94207) (xy 89.828574 -398.884177) (xy 89.85151 -398.828804) (xy 89.881477 -398.776898)
			(xy 89.917964 -398.729348) (xy 89.960344 -398.686968) (xy 90.007894 -398.650481) (xy 90.0598 -398.620514)
			(xy 90.115173 -398.597578) (xy 90.173066 -398.582065) (xy 90.232488 -398.574242) (xy 90.292424 -398.574242)
			(xy 90.351846 -398.582065) (xy 90.409739 -398.597578) (xy 90.465112 -398.620514) (xy 90.517018 -398.650481)
			(xy 90.564568 -398.686968) (xy 90.606948 -398.729348) (xy 90.643435 -398.776898) (xy 90.673402 -398.828804)
			(xy 90.696338 -398.884177) (xy 90.711851 -398.94207) (xy 90.719674 -399.001492) (xy 90.720164 -399.03146)
			(xy 90.719674 -399.061428) (xy 90.711851 -399.12085) (xy 90.696338 -399.178743) (xy 90.673402 -399.234116)
			(xy 90.643435 -399.286022) (xy 90.606948 -399.333572) (xy 90.564568 -399.375952) (xy 90.517018 -399.412439)
			(xy 90.465112 -399.442406) (xy 90.409739 -399.465342) (xy 90.351846 -399.480855) (xy 90.292424 -399.488678)
			(xy 90.232488 -399.488678) (xy 90.173066 -399.480855) (xy 90.115173 -399.465342) (xy 90.0598 -399.442406)
			(xy 90.007894 -399.412439) (xy 89.960344 -399.375952) (xy 89.917964 -399.333572) (xy 89.881477 -399.286022)
			(xy 89.85151 -399.234116) (xy 89.828574 -399.178743) (xy 89.813061 -399.12085) (xy 89.805238 -399.061428)
			(xy 88.965231 -399.061428) (xy 88.953319 -399.08206) (xy 88.916832 -399.12961) (xy 88.874452 -399.17199)
			(xy 88.826902 -399.208477) (xy 88.774996 -399.238444) (xy 88.719623 -399.26138) (xy 88.66173 -399.276893)
			(xy 88.602308 -399.284716) (xy 88.542372 -399.284716) (xy 88.48295 -399.276893) (xy 88.425057 -399.26138)
			(xy 88.369684 -399.238444) (xy 88.317778 -399.208477) (xy 88.270228 -399.17199) (xy 88.227848 -399.12961)
			(xy 88.191361 -399.08206) (xy 88.161394 -399.030154) (xy 88.138458 -398.974781) (xy 88.122945 -398.916888)
			(xy 88.115122 -398.857466) (xy 87.302416 -398.857466) (xy 87.313498 -398.858925) (xy 87.371391 -398.874438)
			(xy 87.426764 -398.897374) (xy 87.47867 -398.927341) (xy 87.52622 -398.963828) (xy 87.5686 -399.006208)
			(xy 87.605087 -399.053758) (xy 87.635054 -399.105664) (xy 87.65799 -399.161037) (xy 87.673503 -399.21893)
			(xy 87.681326 -399.278352) (xy 87.681816 -399.30832) (xy 87.681326 -399.338288) (xy 87.673503 -399.39771)
			(xy 87.65799 -399.455603) (xy 87.635054 -399.510976) (xy 87.605087 -399.562882) (xy 87.5686 -399.610432)
			(xy 87.52622 -399.652812) (xy 87.47867 -399.689299) (xy 87.426764 -399.719266) (xy 87.371391 -399.742202)
			(xy 87.313498 -399.757715) (xy 87.254076 -399.765538) (xy 87.19414 -399.765538) (xy 87.134718 -399.757715)
			(xy 87.076825 -399.742202) (xy 87.021452 -399.719266) (xy 86.969546 -399.689299) (xy 86.921996 -399.652812)
			(xy 86.879616 -399.610432) (xy 86.843129 -399.562882) (xy 86.813162 -399.510976) (xy 86.790226 -399.455603)
			(xy 86.774713 -399.39771) (xy 86.76689 -399.338288) (xy 85.545565 -399.338288) (xy 85.589164 -399.363459)
			(xy 85.636714 -399.399946) (xy 85.679094 -399.442326) (xy 85.715581 -399.489876) (xy 85.745548 -399.541782)
			(xy 85.768484 -399.597155) (xy 85.783997 -399.655048) (xy 85.79182 -399.71447) (xy 85.79231 -399.744438)
			(xy 85.79182 -399.774406) (xy 85.783997 -399.833828) (xy 85.768484 -399.891721) (xy 85.745548 -399.947094)
			(xy 85.715581 -399.999) (xy 85.679094 -400.04655) (xy 85.636714 -400.08893) (xy 85.589164 -400.125417)
			(xy 85.561857 -400.141182) (xy 87.997012 -400.141182) (xy 87.997012 -400.081246) (xy 88.004835 -400.021824)
			(xy 88.020348 -399.963931) (xy 88.043284 -399.908558) (xy 88.073251 -399.856652) (xy 88.109738 -399.809102)
			(xy 88.152118 -399.766722) (xy 88.199668 -399.730235) (xy 88.251574 -399.700268) (xy 88.306947 -399.677332)
			(xy 88.36484 -399.661819) (xy 88.424262 -399.653996) (xy 88.484198 -399.653996) (xy 88.54362 -399.661819)
			(xy 88.601513 -399.677332) (xy 88.656886 -399.700268) (xy 88.708792 -399.730235) (xy 88.756342 -399.766722)
			(xy 88.798722 -399.809102) (xy 88.835209 -399.856652) (xy 88.865176 -399.908558) (xy 88.888112 -399.963931)
			(xy 88.903625 -400.021824) (xy 88.911448 -400.081246) (xy 88.911938 -400.111214) (xy 88.911448 -400.141182)
			(xy 88.903625 -400.200604) (xy 88.888112 -400.258497) (xy 88.865176 -400.31387) (xy 88.835209 -400.365776)
			(xy 88.798722 -400.413326) (xy 88.756342 -400.455706) (xy 88.708792 -400.492193) (xy 88.656886 -400.52216)
			(xy 88.601513 -400.545096) (xy 88.54362 -400.560609) (xy 88.484198 -400.568432) (xy 88.424262 -400.568432)
			(xy 88.36484 -400.560609) (xy 88.306947 -400.545096) (xy 88.251574 -400.52216) (xy 88.199668 -400.492193)
			(xy 88.152118 -400.455706) (xy 88.109738 -400.413326) (xy 88.073251 -400.365776) (xy 88.043284 -400.31387)
			(xy 88.020348 -400.258497) (xy 88.004835 -400.200604) (xy 87.997012 -400.141182) (xy 85.561857 -400.141182)
			(xy 85.537258 -400.155384) (xy 85.481885 -400.17832) (xy 85.423992 -400.193833) (xy 85.36457 -400.201656)
			(xy 85.304634 -400.201656) (xy 85.245212 -400.193833) (xy 85.187319 -400.17832) (xy 85.131946 -400.155384)
			(xy 85.08004 -400.125417) (xy 85.03249 -400.08893) (xy 84.99011 -400.04655) (xy 84.953623 -399.999)
			(xy 84.923656 -399.947094) (xy 84.90072 -399.891721) (xy 84.885207 -399.833828) (xy 84.877384 -399.774406)
			(xy 28.353512 -399.774406) (xy 28.353512 -400.301202) (xy 78.81034 -400.301202) (xy 78.81034 -400.241266)
			(xy 78.818163 -400.181844) (xy 78.833676 -400.123951) (xy 78.856612 -400.068578) (xy 78.886579 -400.016672)
			(xy 78.923066 -399.969122) (xy 78.965446 -399.926742) (xy 79.012996 -399.890255) (xy 79.064902 -399.860288)
			(xy 79.120275 -399.837352) (xy 79.178168 -399.821839) (xy 79.23759 -399.814016) (xy 79.297526 -399.814016)
			(xy 79.356948 -399.821839) (xy 79.414841 -399.837352) (xy 79.470214 -399.860288) (xy 79.52212 -399.890255)
			(xy 79.56967 -399.926742) (xy 79.61205 -399.969122) (xy 79.648537 -400.016672) (xy 79.678504 -400.068578)
			(xy 79.70144 -400.123951) (xy 79.716953 -400.181844) (xy 79.724776 -400.241266) (xy 79.725266 -400.271234)
			(xy 79.724776 -400.301202) (xy 79.716953 -400.360624) (xy 79.70144 -400.418517) (xy 79.678504 -400.47389)
			(xy 79.648537 -400.525796) (xy 79.61205 -400.573346) (xy 79.56967 -400.615726) (xy 79.52212 -400.652213)
			(xy 79.470214 -400.68218) (xy 79.414841 -400.705116) (xy 79.356948 -400.720629) (xy 79.297526 -400.728452)
			(xy 79.23759 -400.728452) (xy 79.178168 -400.720629) (xy 79.120275 -400.705116) (xy 79.064902 -400.68218)
			(xy 79.012996 -400.652213) (xy 78.965446 -400.615726) (xy 78.923066 -400.573346) (xy 78.886579 -400.525796)
			(xy 78.856612 -400.47389) (xy 78.833676 -400.418517) (xy 78.818163 -400.360624) (xy 78.81034 -400.301202)
			(xy 28.353512 -400.301202) (xy 28.353512 -406.96007) (xy 39.818564 -406.96007) (xy 39.819058 -406.902661)
			(xy 39.826902 -406.788113) (xy 39.842544 -406.674366) (xy 39.865911 -406.561952) (xy 39.896896 -406.451394)
			(xy 39.935352 -406.343209) (xy 39.981101 -406.2379) (xy 40.03393 -406.135958) (xy 40.093592 -406.037859)
			(xy 40.159809 -405.94406) (xy 40.232272 -405.854998) (xy 40.310645 -405.771089) (xy 40.39456 -405.692723)
			(xy 40.483627 -405.620266) (xy 40.577431 -405.554056) (xy 40.675535 -405.494402) (xy 40.777481 -405.441581)
			(xy 40.882793 -405.395839) (xy 40.990981 -405.357391) (xy 41.101541 -405.326415) (xy 41.213957 -405.303056)
			(xy 41.327705 -405.287423) (xy 41.442254 -405.279588) (xy 41.557072 -405.279588) (xy 41.671621 -405.287423)
			(xy 41.785369 -405.303056) (xy 41.897785 -405.326415) (xy 42.008345 -405.357391) (xy 42.116533 -405.395839)
			(xy 42.221845 -405.441581) (xy 42.323791 -405.494402) (xy 42.421895 -405.554056) (xy 42.501239 -405.61006)
			(xy 63.647577 -405.61006) (xy 63.651612 -405.534356) (xy 63.663671 -405.459511) (xy 63.683617 -405.38637)
			(xy 63.711224 -405.315765) (xy 63.74618 -405.248494) (xy 63.788088 -405.185319) (xy 63.836474 -405.126957)
			(xy 63.89079 -405.074069) (xy 63.950419 -405.027254) (xy 64.014687 -404.987042) (xy 64.082864 -404.95389)
			(xy 64.15418 -404.928172) (xy 64.227825 -404.91018) (xy 64.302965 -404.900118) (xy 64.378749 -404.898099)
			(xy 64.454319 -404.904148) (xy 64.528817 -404.918195) (xy 64.6014 -404.940081) (xy 64.671246 -404.969558)
			(xy 64.737563 -405.006293) (xy 64.799599 -405.049868) (xy 64.856652 -405.09979) (xy 64.908076 -405.155494)
			(xy 64.953287 -405.216349) (xy 64.991774 -405.281664) (xy 65.0231 -405.3507) (xy 65.04691 -405.422675)
			(xy 65.062935 -405.496773) (xy 65.070994 -405.572154) (xy 65.071498 -405.61006) (xy 66.187577 -405.61006)
			(xy 66.191612 -405.534356) (xy 66.203671 -405.459511) (xy 66.223617 -405.38637) (xy 66.251224 -405.315765)
			(xy 66.28618 -405.248494) (xy 66.328088 -405.185319) (xy 66.376474 -405.126957) (xy 66.43079 -405.074069)
			(xy 66.490419 -405.027254) (xy 66.554687 -404.987042) (xy 66.622864 -404.95389) (xy 66.69418 -404.928172)
			(xy 66.767825 -404.91018) (xy 66.842965 -404.900118) (xy 66.918749 -404.898099) (xy 66.994319 -404.904148)
			(xy 67.068817 -404.918195) (xy 67.1414 -404.940081) (xy 67.211246 -404.969558) (xy 67.277563 -405.006293)
			(xy 67.339599 -405.049868) (xy 67.396652 -405.09979) (xy 67.448076 -405.155494) (xy 67.493287 -405.216349)
			(xy 67.531774 -405.281664) (xy 67.5631 -405.3507) (xy 67.58691 -405.422675) (xy 67.602935 -405.496773)
			(xy 67.610994 -405.572154) (xy 67.611498 -405.61006) (xy 68.727577 -405.61006) (xy 68.731612 -405.534356)
			(xy 68.743671 -405.459511) (xy 68.763617 -405.38637) (xy 68.791224 -405.315765) (xy 68.82618 -405.248494)
			(xy 68.868088 -405.185319) (xy 68.916474 -405.126957) (xy 68.97079 -405.074069) (xy 69.030419 -405.027254)
			(xy 69.094687 -404.987042) (xy 69.162864 -404.95389) (xy 69.23418 -404.928172) (xy 69.307825 -404.91018)
			(xy 69.382965 -404.900118) (xy 69.458749 -404.898099) (xy 69.534319 -404.904148) (xy 69.608817 -404.918195)
			(xy 69.6814 -404.940081) (xy 69.751246 -404.969558) (xy 69.817563 -405.006293) (xy 69.879599 -405.049868)
			(xy 69.936652 -405.09979) (xy 69.988076 -405.155494) (xy 70.033287 -405.216349) (xy 70.071774 -405.281664)
			(xy 70.1031 -405.3507) (xy 70.12691 -405.422675) (xy 70.142935 -405.496773) (xy 70.150994 -405.572154)
			(xy 70.151498 -405.61006) (xy 71.267577 -405.61006) (xy 71.271612 -405.534356) (xy 71.283671 -405.459511)
			(xy 71.303617 -405.38637) (xy 71.331224 -405.315765) (xy 71.36618 -405.248494) (xy 71.408088 -405.185319)
			(xy 71.456474 -405.126957) (xy 71.51079 -405.074069) (xy 71.570419 -405.027254) (xy 71.634687 -404.987042)
			(xy 71.702864 -404.95389) (xy 71.77418 -404.928172) (xy 71.847825 -404.91018) (xy 71.922965 -404.900118)
			(xy 71.998749 -404.898099) (xy 72.074319 -404.904148) (xy 72.148817 -404.918195) (xy 72.2214 -404.940081)
			(xy 72.291246 -404.969558) (xy 72.357563 -405.006293) (xy 72.419599 -405.049868) (xy 72.476652 -405.09979)
			(xy 72.528076 -405.155494) (xy 72.573287 -405.216349) (xy 72.611774 -405.281664) (xy 72.6431 -405.3507)
			(xy 72.66691 -405.422675) (xy 72.682935 -405.496773) (xy 72.690994 -405.572154) (xy 72.691498 -405.61006)
			(xy 73.807577 -405.61006) (xy 73.811612 -405.534356) (xy 73.823671 -405.459511) (xy 73.843617 -405.38637)
			(xy 73.871224 -405.315765) (xy 73.90618 -405.248494) (xy 73.948088 -405.185319) (xy 73.996474 -405.126957)
			(xy 74.05079 -405.074069) (xy 74.110419 -405.027254) (xy 74.174687 -404.987042) (xy 74.242864 -404.95389)
			(xy 74.31418 -404.928172) (xy 74.387825 -404.91018) (xy 74.462965 -404.900118) (xy 74.538749 -404.898099)
			(xy 74.614319 -404.904148) (xy 74.688817 -404.918195) (xy 74.7614 -404.940081) (xy 74.831246 -404.969558)
			(xy 74.897563 -405.006293) (xy 74.959599 -405.049868) (xy 75.016652 -405.09979) (xy 75.068076 -405.155494)
			(xy 75.113287 -405.216349) (xy 75.151774 -405.281664) (xy 75.1831 -405.3507) (xy 75.20691 -405.422675)
			(xy 75.222935 -405.496773) (xy 75.230994 -405.572154) (xy 75.231498 -405.61006) (xy 76.347577 -405.61006)
			(xy 76.351612 -405.534356) (xy 76.363671 -405.459511) (xy 76.383617 -405.38637) (xy 76.411224 -405.315765)
			(xy 76.44618 -405.248494) (xy 76.488088 -405.185319) (xy 76.536474 -405.126957) (xy 76.59079 -405.074069)
			(xy 76.650419 -405.027254) (xy 76.714687 -404.987042) (xy 76.782864 -404.95389) (xy 76.85418 -404.928172)
			(xy 76.927825 -404.91018) (xy 77.002965 -404.900118) (xy 77.078749 -404.898099) (xy 77.154319 -404.904148)
			(xy 77.228817 -404.918195) (xy 77.3014 -404.940081) (xy 77.371246 -404.969558) (xy 77.437563 -405.006293)
			(xy 77.499599 -405.049868) (xy 77.556652 -405.09979) (xy 77.608076 -405.155494) (xy 77.653287 -405.216349)
			(xy 77.691774 -405.281664) (xy 77.7231 -405.3507) (xy 77.74691 -405.422675) (xy 77.762935 -405.496773)
			(xy 77.770994 -405.572154) (xy 77.771498 -405.61006) (xy 78.887577 -405.61006) (xy 78.891612 -405.534356)
			(xy 78.903671 -405.459511) (xy 78.923617 -405.38637) (xy 78.951224 -405.315765) (xy 78.98618 -405.248494)
			(xy 79.028088 -405.185319) (xy 79.076474 -405.126957) (xy 79.13079 -405.074069) (xy 79.190419 -405.027254)
			(xy 79.254687 -404.987042) (xy 79.322864 -404.95389) (xy 79.39418 -404.928172) (xy 79.467825 -404.91018)
			(xy 79.542965 -404.900118) (xy 79.618749 -404.898099) (xy 79.694319 -404.904148) (xy 79.768817 -404.918195)
			(xy 79.8414 -404.940081) (xy 79.911246 -404.969558) (xy 79.977563 -405.006293) (xy 80.039599 -405.049868)
			(xy 80.096652 -405.09979) (xy 80.148076 -405.155494) (xy 80.193287 -405.216349) (xy 80.231774 -405.281664)
			(xy 80.2631 -405.3507) (xy 80.28691 -405.422675) (xy 80.302935 -405.496773) (xy 80.310994 -405.572154)
			(xy 80.311498 -405.61006) (xy 81.427577 -405.61006) (xy 81.431612 -405.534356) (xy 81.443671 -405.459511)
			(xy 81.463617 -405.38637) (xy 81.491224 -405.315765) (xy 81.52618 -405.248494) (xy 81.568088 -405.185319)
			(xy 81.616474 -405.126957) (xy 81.67079 -405.074069) (xy 81.730419 -405.027254) (xy 81.794687 -404.987042)
			(xy 81.862864 -404.95389) (xy 81.93418 -404.928172) (xy 82.007825 -404.91018) (xy 82.082965 -404.900118)
			(xy 82.158749 -404.898099) (xy 82.234319 -404.904148) (xy 82.308817 -404.918195) (xy 82.3814 -404.940081)
			(xy 82.451246 -404.969558) (xy 82.517563 -405.006293) (xy 82.579599 -405.049868) (xy 82.585544 -405.05507)
			(xy 86.197697 -405.05507) (xy 86.201732 -404.979366) (xy 86.213791 -404.904521) (xy 86.233737 -404.83138)
			(xy 86.261344 -404.760775) (xy 86.2963 -404.693504) (xy 86.338208 -404.630329) (xy 86.386594 -404.571967)
			(xy 86.44091 -404.519079) (xy 86.500539 -404.472264) (xy 86.564807 -404.432052) (xy 86.632984 -404.3989)
			(xy 86.7043 -404.373182) (xy 86.777945 -404.35519) (xy 86.853085 -404.345128) (xy 86.928869 -404.343109)
			(xy 87.004439 -404.349158) (xy 87.078937 -404.363205) (xy 87.15152 -404.385091) (xy 87.221366 -404.414568)
			(xy 87.287683 -404.451303) (xy 87.349719 -404.494878) (xy 87.406772 -404.5448) (xy 87.458196 -404.600504)
			(xy 87.503407 -404.661359) (xy 87.541894 -404.726674) (xy 87.57322 -404.79571) (xy 87.59703 -404.867685)
			(xy 87.613055 -404.941783) (xy 87.621114 -405.017164) (xy 87.621618 -405.05507) (xy 87.621114 -405.092976)
			(xy 87.613055 -405.168357) (xy 87.59703 -405.242455) (xy 87.57322 -405.31443) (xy 87.541894 -405.383466)
			(xy 87.503407 -405.448781) (xy 87.458196 -405.509636) (xy 87.406772 -405.56534) (xy 87.349719 -405.615262)
			(xy 87.287683 -405.658837) (xy 87.221366 -405.695572) (xy 87.15152 -405.725049) (xy 87.078937 -405.746935)
			(xy 87.004439 -405.760982) (xy 86.928869 -405.767031) (xy 86.853085 -405.765012) (xy 86.777945 -405.75495)
			(xy 86.7043 -405.736958) (xy 86.632984 -405.71124) (xy 86.564807 -405.678088) (xy 86.500539 -405.637876)
			(xy 86.44091 -405.591061) (xy 86.386594 -405.538173) (xy 86.338208 -405.479811) (xy 86.2963 -405.416636)
			(xy 86.261344 -405.349365) (xy 86.233737 -405.27876) (xy 86.213791 -405.205619) (xy 86.201732 -405.130774)
			(xy 86.197697 -405.05507) (xy 82.585544 -405.05507) (xy 82.636652 -405.09979) (xy 82.688076 -405.155494)
			(xy 82.733287 -405.216349) (xy 82.771774 -405.281664) (xy 82.8031 -405.3507) (xy 82.82691 -405.422675)
			(xy 82.842935 -405.496773) (xy 82.850994 -405.572154) (xy 82.851498 -405.61006) (xy 82.850994 -405.647966)
			(xy 82.842935 -405.723347) (xy 82.82691 -405.797445) (xy 82.8031 -405.86942) (xy 82.771774 -405.938456)
			(xy 82.733287 -406.003771) (xy 82.688076 -406.064626) (xy 82.636652 -406.12033) (xy 82.579599 -406.170252)
			(xy 82.517563 -406.213827) (xy 82.451246 -406.250562) (xy 82.3814 -406.280039) (xy 82.308817 -406.301925)
			(xy 82.234319 -406.315972) (xy 82.158749 -406.322021) (xy 82.082965 -406.320002) (xy 82.007825 -406.30994)
			(xy 81.93418 -406.291948) (xy 81.862864 -406.26623) (xy 81.794687 -406.233078) (xy 81.730419 -406.192866)
			(xy 81.67079 -406.146051) (xy 81.616474 -406.093163) (xy 81.568088 -406.034801) (xy 81.52618 -405.971626)
			(xy 81.491224 -405.904355) (xy 81.463617 -405.83375) (xy 81.443671 -405.760609) (xy 81.431612 -405.685764)
			(xy 81.427577 -405.61006) (xy 80.311498 -405.61006) (xy 80.310994 -405.647966) (xy 80.302935 -405.723347)
			(xy 80.28691 -405.797445) (xy 80.2631 -405.86942) (xy 80.231774 -405.938456) (xy 80.193287 -406.003771)
			(xy 80.148076 -406.064626) (xy 80.096652 -406.12033) (xy 80.039599 -406.170252) (xy 79.977563 -406.213827)
			(xy 79.911246 -406.250562) (xy 79.8414 -406.280039) (xy 79.768817 -406.301925) (xy 79.694319 -406.315972)
			(xy 79.618749 -406.322021) (xy 79.542965 -406.320002) (xy 79.467825 -406.30994) (xy 79.39418 -406.291948)
			(xy 79.322864 -406.26623) (xy 79.254687 -406.233078) (xy 79.190419 -406.192866) (xy 79.13079 -406.146051)
			(xy 79.076474 -406.093163) (xy 79.028088 -406.034801) (xy 78.98618 -405.971626) (xy 78.951224 -405.904355)
			(xy 78.923617 -405.83375) (xy 78.903671 -405.760609) (xy 78.891612 -405.685764) (xy 78.887577 -405.61006)
			(xy 77.771498 -405.61006) (xy 77.770994 -405.647966) (xy 77.762935 -405.723347) (xy 77.74691 -405.797445)
			(xy 77.7231 -405.86942) (xy 77.691774 -405.938456) (xy 77.653287 -406.003771) (xy 77.608076 -406.064626)
			(xy 77.556652 -406.12033) (xy 77.499599 -406.170252) (xy 77.437563 -406.213827) (xy 77.371246 -406.250562)
			(xy 77.3014 -406.280039) (xy 77.228817 -406.301925) (xy 77.154319 -406.315972) (xy 77.078749 -406.322021)
			(xy 77.002965 -406.320002) (xy 76.927825 -406.30994) (xy 76.85418 -406.291948) (xy 76.782864 -406.26623)
			(xy 76.714687 -406.233078) (xy 76.650419 -406.192866) (xy 76.59079 -406.146051) (xy 76.536474 -406.093163)
			(xy 76.488088 -406.034801) (xy 76.44618 -405.971626) (xy 76.411224 -405.904355) (xy 76.383617 -405.83375)
			(xy 76.363671 -405.760609) (xy 76.351612 -405.685764) (xy 76.347577 -405.61006) (xy 75.231498 -405.61006)
			(xy 75.230994 -405.647966) (xy 75.222935 -405.723347) (xy 75.20691 -405.797445) (xy 75.1831 -405.86942)
			(xy 75.151774 -405.938456) (xy 75.113287 -406.003771) (xy 75.068076 -406.064626) (xy 75.016652 -406.12033)
			(xy 74.959599 -406.170252) (xy 74.897563 -406.213827) (xy 74.831246 -406.250562) (xy 74.7614 -406.280039)
			(xy 74.688817 -406.301925) (xy 74.614319 -406.315972) (xy 74.538749 -406.322021) (xy 74.462965 -406.320002)
			(xy 74.387825 -406.30994) (xy 74.31418 -406.291948) (xy 74.242864 -406.26623) (xy 74.174687 -406.233078)
			(xy 74.110419 -406.192866) (xy 74.05079 -406.146051) (xy 73.996474 -406.093163) (xy 73.948088 -406.034801)
			(xy 73.90618 -405.971626) (xy 73.871224 -405.904355) (xy 73.843617 -405.83375) (xy 73.823671 -405.760609)
			(xy 73.811612 -405.685764) (xy 73.807577 -405.61006) (xy 72.691498 -405.61006) (xy 72.690994 -405.647966)
			(xy 72.682935 -405.723347) (xy 72.66691 -405.797445) (xy 72.6431 -405.86942) (xy 72.611774 -405.938456)
			(xy 72.573287 -406.003771) (xy 72.528076 -406.064626) (xy 72.476652 -406.12033) (xy 72.419599 -406.170252)
			(xy 72.357563 -406.213827) (xy 72.291246 -406.250562) (xy 72.2214 -406.280039) (xy 72.148817 -406.301925)
			(xy 72.074319 -406.315972) (xy 71.998749 -406.322021) (xy 71.922965 -406.320002) (xy 71.847825 -406.30994)
			(xy 71.77418 -406.291948) (xy 71.702864 -406.26623) (xy 71.634687 -406.233078) (xy 71.570419 -406.192866)
			(xy 71.51079 -406.146051) (xy 71.456474 -406.093163) (xy 71.408088 -406.034801) (xy 71.36618 -405.971626)
			(xy 71.331224 -405.904355) (xy 71.303617 -405.83375) (xy 71.283671 -405.760609) (xy 71.271612 -405.685764)
			(xy 71.267577 -405.61006) (xy 70.151498 -405.61006) (xy 70.150994 -405.647966) (xy 70.142935 -405.723347)
			(xy 70.12691 -405.797445) (xy 70.1031 -405.86942) (xy 70.071774 -405.938456) (xy 70.033287 -406.003771)
			(xy 69.988076 -406.064626) (xy 69.936652 -406.12033) (xy 69.879599 -406.170252) (xy 69.817563 -406.213827)
			(xy 69.751246 -406.250562) (xy 69.6814 -406.280039) (xy 69.608817 -406.301925) (xy 69.534319 -406.315972)
			(xy 69.458749 -406.322021) (xy 69.382965 -406.320002) (xy 69.307825 -406.30994) (xy 69.23418 -406.291948)
			(xy 69.162864 -406.26623) (xy 69.094687 -406.233078) (xy 69.030419 -406.192866) (xy 68.97079 -406.146051)
			(xy 68.916474 -406.093163) (xy 68.868088 -406.034801) (xy 68.82618 -405.971626) (xy 68.791224 -405.904355)
			(xy 68.763617 -405.83375) (xy 68.743671 -405.760609) (xy 68.731612 -405.685764) (xy 68.727577 -405.61006)
			(xy 67.611498 -405.61006) (xy 67.610994 -405.647966) (xy 67.602935 -405.723347) (xy 67.58691 -405.797445)
			(xy 67.5631 -405.86942) (xy 67.531774 -405.938456) (xy 67.493287 -406.003771) (xy 67.448076 -406.064626)
			(xy 67.396652 -406.12033) (xy 67.339599 -406.170252) (xy 67.277563 -406.213827) (xy 67.211246 -406.250562)
			(xy 67.1414 -406.280039) (xy 67.068817 -406.301925) (xy 66.994319 -406.315972) (xy 66.918749 -406.322021)
			(xy 66.842965 -406.320002) (xy 66.767825 -406.30994) (xy 66.69418 -406.291948) (xy 66.622864 -406.26623)
			(xy 66.554687 -406.233078) (xy 66.490419 -406.192866) (xy 66.43079 -406.146051) (xy 66.376474 -406.093163)
			(xy 66.328088 -406.034801) (xy 66.28618 -405.971626) (xy 66.251224 -405.904355) (xy 66.223617 -405.83375)
			(xy 66.203671 -405.760609) (xy 66.191612 -405.685764) (xy 66.187577 -405.61006) (xy 65.071498 -405.61006)
			(xy 65.070994 -405.647966) (xy 65.062935 -405.723347) (xy 65.04691 -405.797445) (xy 65.0231 -405.86942)
			(xy 64.991774 -405.938456) (xy 64.953287 -406.003771) (xy 64.908076 -406.064626) (xy 64.856652 -406.12033)
			(xy 64.799599 -406.170252) (xy 64.737563 -406.213827) (xy 64.671246 -406.250562) (xy 64.6014 -406.280039)
			(xy 64.528817 -406.301925) (xy 64.454319 -406.315972) (xy 64.378749 -406.322021) (xy 64.302965 -406.320002)
			(xy 64.227825 -406.30994) (xy 64.15418 -406.291948) (xy 64.082864 -406.26623) (xy 64.014687 -406.233078)
			(xy 63.950419 -406.192866) (xy 63.89079 -406.146051) (xy 63.836474 -406.093163) (xy 63.788088 -406.034801)
			(xy 63.74618 -405.971626) (xy 63.711224 -405.904355) (xy 63.683617 -405.83375) (xy 63.663671 -405.760609)
			(xy 63.651612 -405.685764) (xy 63.647577 -405.61006) (xy 42.501239 -405.61006) (xy 42.515699 -405.620266)
			(xy 42.604766 -405.692723) (xy 42.688681 -405.771089) (xy 42.767054 -405.854998) (xy 42.839517 -405.94406)
			(xy 42.905734 -406.037859) (xy 42.965396 -406.135958) (xy 43.018225 -406.2379) (xy 43.056094 -406.32507)
			(xy 84.927697 -406.32507) (xy 84.931732 -406.249366) (xy 84.943791 -406.174521) (xy 84.963737 -406.10138)
			(xy 84.991344 -406.030775) (xy 85.0263 -405.963504) (xy 85.068208 -405.900329) (xy 85.116594 -405.841967)
			(xy 85.17091 -405.789079) (xy 85.230539 -405.742264) (xy 85.294807 -405.702052) (xy 85.362984 -405.6689)
			(xy 85.4343 -405.643182) (xy 85.507945 -405.62519) (xy 85.583085 -405.615128) (xy 85.658869 -405.613109)
			(xy 85.734439 -405.619158) (xy 85.808937 -405.633205) (xy 85.88152 -405.655091) (xy 85.951366 -405.684568)
			(xy 86.017683 -405.721303) (xy 86.079719 -405.764878) (xy 86.136772 -405.8148) (xy 86.188196 -405.870504)
			(xy 86.233407 -405.931359) (xy 86.271894 -405.996674) (xy 86.30322 -406.06571) (xy 86.32703 -406.137685)
			(xy 86.343055 -406.211783) (xy 86.351114 -406.287164) (xy 86.351618 -406.32507) (xy 86.351114 -406.362976)
			(xy 86.343055 -406.438357) (xy 86.32703 -406.512455) (xy 86.30322 -406.58443) (xy 86.271894 -406.653466)
			(xy 86.233407 -406.718781) (xy 86.188196 -406.779636) (xy 86.136772 -406.83534) (xy 86.079719 -406.885262)
			(xy 86.017683 -406.928837) (xy 85.951366 -406.965572) (xy 85.88152 -406.995049) (xy 85.808937 -407.016935)
			(xy 85.734439 -407.030982) (xy 85.658869 -407.037031) (xy 85.583085 -407.035012) (xy 85.507945 -407.02495)
			(xy 85.4343 -407.006958) (xy 85.362984 -406.98124) (xy 85.294807 -406.948088) (xy 85.230539 -406.907876)
			(xy 85.17091 -406.861061) (xy 85.116594 -406.808173) (xy 85.068208 -406.749811) (xy 85.0263 -406.686636)
			(xy 84.991344 -406.619365) (xy 84.963737 -406.54876) (xy 84.943791 -406.475619) (xy 84.931732 -406.400774)
			(xy 84.927697 -406.32507) (xy 43.056094 -406.32507) (xy 43.063974 -406.343209) (xy 43.10243 -406.451394)
			(xy 43.133415 -406.561952) (xy 43.156782 -406.674366) (xy 43.172424 -406.788113) (xy 43.180268 -406.902661)
			(xy 43.180762 -406.96007) (xy 43.180576 -406.993253) (xy 43.177909 -407.059567) (xy 43.175428 -407.092658)
			(xy 43.170272 -407.150942) (xy 43.152948 -407.266671) (xy 43.127616 -407.380914) (xy 43.094401 -407.493119)
			(xy 43.056327 -407.59507) (xy 86.197697 -407.59507) (xy 86.201732 -407.519366) (xy 86.213791 -407.444521)
			(xy 86.233737 -407.37138) (xy 86.261344 -407.300775) (xy 86.2963 -407.233504) (xy 86.338208 -407.170329)
			(xy 86.386594 -407.111967) (xy 86.44091 -407.059079) (xy 86.500539 -407.012264) (xy 86.564807 -406.972052)
			(xy 86.632984 -406.9389) (xy 86.7043 -406.913182) (xy 86.777945 -406.89519) (xy 86.853085 -406.885128)
			(xy 86.928869 -406.883109) (xy 87.004439 -406.889158) (xy 87.078937 -406.903205) (xy 87.15152 -406.925091)
			(xy 87.221366 -406.954568) (xy 87.287683 -406.991303) (xy 87.349719 -407.034878) (xy 87.406772 -407.0848)
			(xy 87.458196 -407.140504) (xy 87.503407 -407.201359) (xy 87.541894 -407.266674) (xy 87.57322 -407.33571)
			(xy 87.59703 -407.407685) (xy 87.613055 -407.481783) (xy 87.621114 -407.557164) (xy 87.621618 -407.59507)
			(xy 87.621114 -407.632976) (xy 87.613055 -407.708357) (xy 87.59703 -407.782455) (xy 87.57322 -407.85443)
			(xy 87.541894 -407.923466) (xy 87.503407 -407.988781) (xy 87.458196 -408.049636) (xy 87.406772 -408.10534)
			(xy 87.349719 -408.155262) (xy 87.287683 -408.198837) (xy 87.221366 -408.235572) (xy 87.15152 -408.265049)
			(xy 87.078937 -408.286935) (xy 87.004439 -408.300982) (xy 86.928869 -408.307031) (xy 86.853085 -408.305012)
			(xy 86.777945 -408.29495) (xy 86.7043 -408.276958) (xy 86.632984 -408.25124) (xy 86.564807 -408.218088)
			(xy 86.500539 -408.177876) (xy 86.44091 -408.131061) (xy 86.386594 -408.078173) (xy 86.338208 -408.019811)
			(xy 86.2963 -407.956636) (xy 86.261344 -407.889365) (xy 86.233737 -407.81876) (xy 86.213791 -407.745619)
			(xy 86.201732 -407.670774) (xy 86.197697 -407.59507) (xy 43.056327 -407.59507) (xy 43.053462 -407.602742)
			(xy 43.004999 -407.709253) (xy 42.949245 -407.812135) (xy 42.886471 -407.910891) (xy 42.816981 -408.005042)
			(xy 42.741111 -408.094132) (xy 42.659229 -408.177729) (xy 42.571732 -408.25543) (xy 42.500813 -408.31008)
			(xy 63.647577 -408.31008) (xy 63.651612 -408.234376) (xy 63.663671 -408.159531) (xy 63.683617 -408.08639)
			(xy 63.711224 -408.015785) (xy 63.74618 -407.948514) (xy 63.788088 -407.885339) (xy 63.836474 -407.826977)
			(xy 63.89079 -407.774089) (xy 63.950419 -407.727274) (xy 64.014687 -407.687062) (xy 64.082864 -407.65391)
			(xy 64.15418 -407.628192) (xy 64.227825 -407.6102) (xy 64.302965 -407.600138) (xy 64.378749 -407.598119)
			(xy 64.454319 -407.604168) (xy 64.528817 -407.618215) (xy 64.6014 -407.640101) (xy 64.671246 -407.669578)
			(xy 64.737563 -407.706313) (xy 64.799599 -407.749888) (xy 64.856652 -407.79981) (xy 64.908076 -407.855514)
			(xy 64.953287 -407.916369) (xy 64.991774 -407.981684) (xy 65.0231 -408.05072) (xy 65.04691 -408.122695)
			(xy 65.062935 -408.196793) (xy 65.070994 -408.272174) (xy 65.071498 -408.31008) (xy 66.187577 -408.31008)
			(xy 66.191612 -408.234376) (xy 66.203671 -408.159531) (xy 66.223617 -408.08639) (xy 66.251224 -408.015785)
			(xy 66.28618 -407.948514) (xy 66.328088 -407.885339) (xy 66.376474 -407.826977) (xy 66.43079 -407.774089)
			(xy 66.490419 -407.727274) (xy 66.554687 -407.687062) (xy 66.622864 -407.65391) (xy 66.69418 -407.628192)
			(xy 66.767825 -407.6102) (xy 66.842965 -407.600138) (xy 66.918749 -407.598119) (xy 66.994319 -407.604168)
			(xy 67.068817 -407.618215) (xy 67.1414 -407.640101) (xy 67.211246 -407.669578) (xy 67.277563 -407.706313)
			(xy 67.339599 -407.749888) (xy 67.396652 -407.79981) (xy 67.448076 -407.855514) (xy 67.493287 -407.916369)
			(xy 67.531774 -407.981684) (xy 67.5631 -408.05072) (xy 67.58691 -408.122695) (xy 67.602935 -408.196793)
			(xy 67.610994 -408.272174) (xy 67.611498 -408.31008) (xy 68.727577 -408.31008) (xy 68.731612 -408.234376)
			(xy 68.743671 -408.159531) (xy 68.763617 -408.08639) (xy 68.791224 -408.015785) (xy 68.82618 -407.948514)
			(xy 68.868088 -407.885339) (xy 68.916474 -407.826977) (xy 68.97079 -407.774089) (xy 69.030419 -407.727274)
			(xy 69.094687 -407.687062) (xy 69.162864 -407.65391) (xy 69.23418 -407.628192) (xy 69.307825 -407.6102)
			(xy 69.382965 -407.600138) (xy 69.458749 -407.598119) (xy 69.534319 -407.604168) (xy 69.608817 -407.618215)
			(xy 69.6814 -407.640101) (xy 69.751246 -407.669578) (xy 69.817563 -407.706313) (xy 69.879599 -407.749888)
			(xy 69.936652 -407.79981) (xy 69.988076 -407.855514) (xy 70.033287 -407.916369) (xy 70.071774 -407.981684)
			(xy 70.1031 -408.05072) (xy 70.12691 -408.122695) (xy 70.142935 -408.196793) (xy 70.150994 -408.272174)
			(xy 70.151498 -408.31008) (xy 71.267577 -408.31008) (xy 71.271612 -408.234376) (xy 71.283671 -408.159531)
			(xy 71.303617 -408.08639) (xy 71.331224 -408.015785) (xy 71.36618 -407.948514) (xy 71.408088 -407.885339)
			(xy 71.456474 -407.826977) (xy 71.51079 -407.774089) (xy 71.570419 -407.727274) (xy 71.634687 -407.687062)
			(xy 71.702864 -407.65391) (xy 71.77418 -407.628192) (xy 71.847825 -407.6102) (xy 71.922965 -407.600138)
			(xy 71.998749 -407.598119) (xy 72.074319 -407.604168) (xy 72.148817 -407.618215) (xy 72.2214 -407.640101)
			(xy 72.291246 -407.669578) (xy 72.357563 -407.706313) (xy 72.419599 -407.749888) (xy 72.476652 -407.79981)
			(xy 72.528076 -407.855514) (xy 72.573287 -407.916369) (xy 72.611774 -407.981684) (xy 72.6431 -408.05072)
			(xy 72.66691 -408.122695) (xy 72.682935 -408.196793) (xy 72.690994 -408.272174) (xy 72.691498 -408.31008)
			(xy 73.807577 -408.31008) (xy 73.811612 -408.234376) (xy 73.823671 -408.159531) (xy 73.843617 -408.08639)
			(xy 73.871224 -408.015785) (xy 73.90618 -407.948514) (xy 73.948088 -407.885339) (xy 73.996474 -407.826977)
			(xy 74.05079 -407.774089) (xy 74.110419 -407.727274) (xy 74.174687 -407.687062) (xy 74.242864 -407.65391)
			(xy 74.31418 -407.628192) (xy 74.387825 -407.6102) (xy 74.462965 -407.600138) (xy 74.538749 -407.598119)
			(xy 74.614319 -407.604168) (xy 74.688817 -407.618215) (xy 74.7614 -407.640101) (xy 74.831246 -407.669578)
			(xy 74.897563 -407.706313) (xy 74.959599 -407.749888) (xy 75.016652 -407.79981) (xy 75.068076 -407.855514)
			(xy 75.113287 -407.916369) (xy 75.151774 -407.981684) (xy 75.1831 -408.05072) (xy 75.20691 -408.122695)
			(xy 75.222935 -408.196793) (xy 75.230994 -408.272174) (xy 75.231498 -408.31008) (xy 76.347577 -408.31008)
			(xy 76.351612 -408.234376) (xy 76.363671 -408.159531) (xy 76.383617 -408.08639) (xy 76.411224 -408.015785)
			(xy 76.44618 -407.948514) (xy 76.488088 -407.885339) (xy 76.536474 -407.826977) (xy 76.59079 -407.774089)
			(xy 76.650419 -407.727274) (xy 76.714687 -407.687062) (xy 76.782864 -407.65391) (xy 76.85418 -407.628192)
			(xy 76.927825 -407.6102) (xy 77.002965 -407.600138) (xy 77.078749 -407.598119) (xy 77.154319 -407.604168)
			(xy 77.228817 -407.618215) (xy 77.3014 -407.640101) (xy 77.371246 -407.669578) (xy 77.437563 -407.706313)
			(xy 77.499599 -407.749888) (xy 77.556652 -407.79981) (xy 77.608076 -407.855514) (xy 77.653287 -407.916369)
			(xy 77.691774 -407.981684) (xy 77.7231 -408.05072) (xy 77.74691 -408.122695) (xy 77.762935 -408.196793)
			(xy 77.770994 -408.272174) (xy 77.771498 -408.31008) (xy 78.887577 -408.31008) (xy 78.891612 -408.234376)
			(xy 78.903671 -408.159531) (xy 78.923617 -408.08639) (xy 78.951224 -408.015785) (xy 78.98618 -407.948514)
			(xy 79.028088 -407.885339) (xy 79.076474 -407.826977) (xy 79.13079 -407.774089) (xy 79.190419 -407.727274)
			(xy 79.254687 -407.687062) (xy 79.322864 -407.65391) (xy 79.39418 -407.628192) (xy 79.467825 -407.6102)
			(xy 79.542965 -407.600138) (xy 79.618749 -407.598119) (xy 79.694319 -407.604168) (xy 79.768817 -407.618215)
			(xy 79.8414 -407.640101) (xy 79.911246 -407.669578) (xy 79.977563 -407.706313) (xy 80.039599 -407.749888)
			(xy 80.096652 -407.79981) (xy 80.148076 -407.855514) (xy 80.193287 -407.916369) (xy 80.231774 -407.981684)
			(xy 80.2631 -408.05072) (xy 80.28691 -408.122695) (xy 80.302935 -408.196793) (xy 80.310994 -408.272174)
			(xy 80.311498 -408.31008) (xy 81.427577 -408.31008) (xy 81.431612 -408.234376) (xy 81.443671 -408.159531)
			(xy 81.463617 -408.08639) (xy 81.491224 -408.015785) (xy 81.52618 -407.948514) (xy 81.568088 -407.885339)
			(xy 81.616474 -407.826977) (xy 81.67079 -407.774089) (xy 81.730419 -407.727274) (xy 81.794687 -407.687062)
			(xy 81.862864 -407.65391) (xy 81.93418 -407.628192) (xy 82.007825 -407.6102) (xy 82.082965 -407.600138)
			(xy 82.158749 -407.598119) (xy 82.234319 -407.604168) (xy 82.308817 -407.618215) (xy 82.3814 -407.640101)
			(xy 82.451246 -407.669578) (xy 82.517563 -407.706313) (xy 82.579599 -407.749888) (xy 82.636652 -407.79981)
			(xy 82.688076 -407.855514) (xy 82.733287 -407.916369) (xy 82.771774 -407.981684) (xy 82.8031 -408.05072)
			(xy 82.82691 -408.122695) (xy 82.842935 -408.196793) (xy 82.850994 -408.272174) (xy 82.851498 -408.31008)
			(xy 82.850994 -408.347986) (xy 82.842935 -408.423367) (xy 82.82691 -408.497465) (xy 82.8031 -408.56944)
			(xy 82.771774 -408.638476) (xy 82.733287 -408.703791) (xy 82.688076 -408.764646) (xy 82.636652 -408.82035)
			(xy 82.585544 -408.86507) (xy 84.927697 -408.86507) (xy 84.931732 -408.789366) (xy 84.943791 -408.714521)
			(xy 84.963737 -408.64138) (xy 84.991344 -408.570775) (xy 85.0263 -408.503504) (xy 85.068208 -408.440329)
			(xy 85.116594 -408.381967) (xy 85.17091 -408.329079) (xy 85.230539 -408.282264) (xy 85.294807 -408.242052)
			(xy 85.362984 -408.2089) (xy 85.4343 -408.183182) (xy 85.507945 -408.16519) (xy 85.583085 -408.155128)
			(xy 85.658869 -408.153109) (xy 85.734439 -408.159158) (xy 85.808937 -408.173205) (xy 85.88152 -408.195091)
			(xy 85.951366 -408.224568) (xy 86.017683 -408.261303) (xy 86.079719 -408.304878) (xy 86.136772 -408.3548)
			(xy 86.188196 -408.410504) (xy 86.233407 -408.471359) (xy 86.271894 -408.536674) (xy 86.30322 -408.60571)
			(xy 86.32703 -408.677685) (xy 86.343055 -408.751783) (xy 86.351114 -408.827164) (xy 86.351618 -408.86507)
			(xy 86.351114 -408.902976) (xy 86.343055 -408.978357) (xy 86.32703 -409.052455) (xy 86.30322 -409.12443)
			(xy 86.271894 -409.193466) (xy 86.233407 -409.258781) (xy 86.188196 -409.319636) (xy 86.136772 -409.37534)
			(xy 86.079719 -409.425262) (xy 86.017683 -409.468837) (xy 85.951366 -409.505572) (xy 85.88152 -409.535049)
			(xy 85.808937 -409.556935) (xy 85.734439 -409.570982) (xy 85.658869 -409.577031) (xy 85.583085 -409.575012)
			(xy 85.507945 -409.56495) (xy 85.4343 -409.546958) (xy 85.362984 -409.52124) (xy 85.294807 -409.488088)
			(xy 85.230539 -409.447876) (xy 85.17091 -409.401061) (xy 85.116594 -409.348173) (xy 85.068208 -409.289811)
			(xy 85.0263 -409.226636) (xy 84.991344 -409.159365) (xy 84.963737 -409.08876) (xy 84.943791 -409.015619)
			(xy 84.931732 -408.940774) (xy 84.927697 -408.86507) (xy 82.585544 -408.86507) (xy 82.579599 -408.870272)
			(xy 82.517563 -408.913847) (xy 82.451246 -408.950582) (xy 82.3814 -408.980059) (xy 82.308817 -409.001945)
			(xy 82.234319 -409.015992) (xy 82.158749 -409.022041) (xy 82.082965 -409.020022) (xy 82.007825 -409.00996)
			(xy 81.93418 -408.991968) (xy 81.862864 -408.96625) (xy 81.794687 -408.933098) (xy 81.730419 -408.892886)
			(xy 81.67079 -408.846071) (xy 81.616474 -408.793183) (xy 81.568088 -408.734821) (xy 81.52618 -408.671646)
			(xy 81.491224 -408.604375) (xy 81.463617 -408.53377) (xy 81.443671 -408.460629) (xy 81.431612 -408.385784)
			(xy 81.427577 -408.31008) (xy 80.311498 -408.31008) (xy 80.310994 -408.347986) (xy 80.302935 -408.423367)
			(xy 80.28691 -408.497465) (xy 80.2631 -408.56944) (xy 80.231774 -408.638476) (xy 80.193287 -408.703791)
			(xy 80.148076 -408.764646) (xy 80.096652 -408.82035) (xy 80.039599 -408.870272) (xy 79.977563 -408.913847)
			(xy 79.911246 -408.950582) (xy 79.8414 -408.980059) (xy 79.768817 -409.001945) (xy 79.694319 -409.015992)
			(xy 79.618749 -409.022041) (xy 79.542965 -409.020022) (xy 79.467825 -409.00996) (xy 79.39418 -408.991968)
			(xy 79.322864 -408.96625) (xy 79.254687 -408.933098) (xy 79.190419 -408.892886) (xy 79.13079 -408.846071)
			(xy 79.076474 -408.793183) (xy 79.028088 -408.734821) (xy 78.98618 -408.671646) (xy 78.951224 -408.604375)
			(xy 78.923617 -408.53377) (xy 78.903671 -408.460629) (xy 78.891612 -408.385784) (xy 78.887577 -408.31008)
			(xy 77.771498 -408.31008) (xy 77.770994 -408.347986) (xy 77.762935 -408.423367) (xy 77.74691 -408.497465)
			(xy 77.7231 -408.56944) (xy 77.691774 -408.638476) (xy 77.653287 -408.703791) (xy 77.608076 -408.764646)
			(xy 77.556652 -408.82035) (xy 77.499599 -408.870272) (xy 77.437563 -408.913847) (xy 77.371246 -408.950582)
			(xy 77.3014 -408.980059) (xy 77.228817 -409.001945) (xy 77.154319 -409.015992) (xy 77.078749 -409.022041)
			(xy 77.002965 -409.020022) (xy 76.927825 -409.00996) (xy 76.85418 -408.991968) (xy 76.782864 -408.96625)
			(xy 76.714687 -408.933098) (xy 76.650419 -408.892886) (xy 76.59079 -408.846071) (xy 76.536474 -408.793183)
			(xy 76.488088 -408.734821) (xy 76.44618 -408.671646) (xy 76.411224 -408.604375) (xy 76.383617 -408.53377)
			(xy 76.363671 -408.460629) (xy 76.351612 -408.385784) (xy 76.347577 -408.31008) (xy 75.231498 -408.31008)
			(xy 75.230994 -408.347986) (xy 75.222935 -408.423367) (xy 75.20691 -408.497465) (xy 75.1831 -408.56944)
			(xy 75.151774 -408.638476) (xy 75.113287 -408.703791) (xy 75.068076 -408.764646) (xy 75.016652 -408.82035)
			(xy 74.959599 -408.870272) (xy 74.897563 -408.913847) (xy 74.831246 -408.950582) (xy 74.7614 -408.980059)
			(xy 74.688817 -409.001945) (xy 74.614319 -409.015992) (xy 74.538749 -409.022041) (xy 74.462965 -409.020022)
			(xy 74.387825 -409.00996) (xy 74.31418 -408.991968) (xy 74.242864 -408.96625) (xy 74.174687 -408.933098)
			(xy 74.110419 -408.892886) (xy 74.05079 -408.846071) (xy 73.996474 -408.793183) (xy 73.948088 -408.734821)
			(xy 73.90618 -408.671646) (xy 73.871224 -408.604375) (xy 73.843617 -408.53377) (xy 73.823671 -408.460629)
			(xy 73.811612 -408.385784) (xy 73.807577 -408.31008) (xy 72.691498 -408.31008) (xy 72.690994 -408.347986)
			(xy 72.682935 -408.423367) (xy 72.66691 -408.497465) (xy 72.6431 -408.56944) (xy 72.611774 -408.638476)
			(xy 72.573287 -408.703791) (xy 72.528076 -408.764646) (xy 72.476652 -408.82035) (xy 72.419599 -408.870272)
			(xy 72.357563 -408.913847) (xy 72.291246 -408.950582) (xy 72.2214 -408.980059) (xy 72.148817 -409.001945)
			(xy 72.074319 -409.015992) (xy 71.998749 -409.022041) (xy 71.922965 -409.020022) (xy 71.847825 -409.00996)
			(xy 71.77418 -408.991968) (xy 71.702864 -408.96625) (xy 71.634687 -408.933098) (xy 71.570419 -408.892886)
			(xy 71.51079 -408.846071) (xy 71.456474 -408.793183) (xy 71.408088 -408.734821) (xy 71.36618 -408.671646)
			(xy 71.331224 -408.604375) (xy 71.303617 -408.53377) (xy 71.283671 -408.460629) (xy 71.271612 -408.385784)
			(xy 71.267577 -408.31008) (xy 70.151498 -408.31008) (xy 70.150994 -408.347986) (xy 70.142935 -408.423367)
			(xy 70.12691 -408.497465) (xy 70.1031 -408.56944) (xy 70.071774 -408.638476) (xy 70.033287 -408.703791)
			(xy 69.988076 -408.764646) (xy 69.936652 -408.82035) (xy 69.879599 -408.870272) (xy 69.817563 -408.913847)
			(xy 69.751246 -408.950582) (xy 69.6814 -408.980059) (xy 69.608817 -409.001945) (xy 69.534319 -409.015992)
			(xy 69.458749 -409.022041) (xy 69.382965 -409.020022) (xy 69.307825 -409.00996) (xy 69.23418 -408.991968)
			(xy 69.162864 -408.96625) (xy 69.094687 -408.933098) (xy 69.030419 -408.892886) (xy 68.97079 -408.846071)
			(xy 68.916474 -408.793183) (xy 68.868088 -408.734821) (xy 68.82618 -408.671646) (xy 68.791224 -408.604375)
			(xy 68.763617 -408.53377) (xy 68.743671 -408.460629) (xy 68.731612 -408.385784) (xy 68.727577 -408.31008)
			(xy 67.611498 -408.31008) (xy 67.610994 -408.347986) (xy 67.602935 -408.423367) (xy 67.58691 -408.497465)
			(xy 67.5631 -408.56944) (xy 67.531774 -408.638476) (xy 67.493287 -408.703791) (xy 67.448076 -408.764646)
			(xy 67.396652 -408.82035) (xy 67.339599 -408.870272) (xy 67.277563 -408.913847) (xy 67.211246 -408.950582)
			(xy 67.1414 -408.980059) (xy 67.068817 -409.001945) (xy 66.994319 -409.015992) (xy 66.918749 -409.022041)
			(xy 66.842965 -409.020022) (xy 66.767825 -409.00996) (xy 66.69418 -408.991968) (xy 66.622864 -408.96625)
			(xy 66.554687 -408.933098) (xy 66.490419 -408.892886) (xy 66.43079 -408.846071) (xy 66.376474 -408.793183)
			(xy 66.328088 -408.734821) (xy 66.28618 -408.671646) (xy 66.251224 -408.604375) (xy 66.223617 -408.53377)
			(xy 66.203671 -408.460629) (xy 66.191612 -408.385784) (xy 66.187577 -408.31008) (xy 65.071498 -408.31008)
			(xy 65.070994 -408.347986) (xy 65.062935 -408.423367) (xy 65.04691 -408.497465) (xy 65.0231 -408.56944)
			(xy 64.991774 -408.638476) (xy 64.953287 -408.703791) (xy 64.908076 -408.764646) (xy 64.856652 -408.82035)
			(xy 64.799599 -408.870272) (xy 64.737563 -408.913847) (xy 64.671246 -408.950582) (xy 64.6014 -408.980059)
			(xy 64.528817 -409.001945) (xy 64.454319 -409.015992) (xy 64.378749 -409.022041) (xy 64.302965 -409.020022)
			(xy 64.227825 -409.00996) (xy 64.15418 -408.991968) (xy 64.082864 -408.96625) (xy 64.014687 -408.933098)
			(xy 63.950419 -408.892886) (xy 63.89079 -408.846071) (xy 63.836474 -408.793183) (xy 63.788088 -408.734821)
			(xy 63.74618 -408.671646) (xy 63.711224 -408.604375) (xy 63.683617 -408.53377) (xy 63.663671 -408.460629)
			(xy 63.651612 -408.385784) (xy 63.647577 -408.31008) (xy 42.500813 -408.31008) (xy 42.479042 -408.326857)
			(xy 42.381609 -408.391665) (xy 42.279905 -408.44954) (xy 42.174422 -408.500202) (xy 42.065671 -408.543404)
			(xy 41.954179 -408.578939) (xy 41.840485 -408.606634) (xy 41.725141 -408.626354) (xy 41.608704 -408.638005)
			(xy 41.491739 -408.64153) (xy 41.374812 -408.636912) (xy 41.258489 -408.624173) (xy 41.143334 -408.603375)
			(xy 41.029905 -408.574618) (xy 40.91875 -408.538042) (xy 40.810407 -408.493825) (xy 40.705403 -408.442179)
			(xy 40.604244 -408.383356) (xy 40.507421 -408.31764) (xy 40.415403 -408.245349) (xy 40.328636 -408.166834)
			(xy 40.247539 -408.082474) (xy 40.172506 -407.992679) (xy 40.103899 -407.897883) (xy 40.042051 -407.798544)
			(xy 39.987262 -407.695145) (xy 39.939796 -407.588186) (xy 39.899884 -407.478185) (xy 39.86772 -407.365674)
			(xy 39.843457 -407.251199) (xy 39.827215 -407.135313) (xy 39.819072 -407.018579) (xy 39.818564 -406.96007)
			(xy 28.353512 -406.96007) (xy 28.353512 -409.033488) (xy 29.519874 -409.033488) (xy 29.519874 -408.946588)
			(xy 29.527892 -408.860059) (xy 29.54386 -408.774639) (xy 29.567641 -408.691057) (xy 29.599033 -408.610025)
			(xy 29.637767 -408.532236) (xy 29.683514 -408.458352) (xy 29.735883 -408.389005) (xy 29.794427 -408.324785)
			(xy 29.858647 -408.266241) (xy 29.927994 -408.213872) (xy 30.001878 -408.168125) (xy 30.079667 -408.129391)
			(xy 30.160699 -408.097999) (xy 30.244281 -408.074218) (xy 30.329701 -408.05825) (xy 30.41623 -408.050232)
			(xy 30.50313 -408.050232) (xy 30.589659 -408.05825) (xy 30.675079 -408.074218) (xy 30.758661 -408.097999)
			(xy 30.839693 -408.129391) (xy 30.917482 -408.168125) (xy 30.991366 -408.213872) (xy 31.060713 -408.266241)
			(xy 31.124933 -408.324785) (xy 31.183477 -408.389005) (xy 31.235846 -408.458352) (xy 31.281593 -408.532236)
			(xy 31.320327 -408.610025) (xy 31.351719 -408.691057) (xy 31.3755 -408.774639) (xy 31.391468 -408.860059)
			(xy 31.399486 -408.946588) (xy 31.399988 -408.990038) (xy 31.399486 -409.033488) (xy 34.599874 -409.033488)
			(xy 34.599874 -408.946588) (xy 34.607892 -408.860059) (xy 34.62386 -408.774639) (xy 34.647641 -408.691057)
			(xy 34.679033 -408.610025) (xy 34.717767 -408.532236) (xy 34.763514 -408.458352) (xy 34.815883 -408.389005)
			(xy 34.874427 -408.324785) (xy 34.938647 -408.266241) (xy 35.007994 -408.213872) (xy 35.081878 -408.168125)
			(xy 35.159667 -408.129391) (xy 35.240699 -408.097999) (xy 35.324281 -408.074218) (xy 35.409701 -408.05825)
			(xy 35.49623 -408.050232) (xy 35.58313 -408.050232) (xy 35.669659 -408.05825) (xy 35.755079 -408.074218)
			(xy 35.838661 -408.097999) (xy 35.919693 -408.129391) (xy 35.997482 -408.168125) (xy 36.071366 -408.213872)
			(xy 36.140713 -408.266241) (xy 36.204933 -408.324785) (xy 36.263477 -408.389005) (xy 36.315846 -408.458352)
			(xy 36.361593 -408.532236) (xy 36.400327 -408.610025) (xy 36.431719 -408.691057) (xy 36.4555 -408.774639)
			(xy 36.471468 -408.860059) (xy 36.479486 -408.946588) (xy 36.479988 -408.990038) (xy 36.479486 -409.033488)
			(xy 36.471468 -409.120017) (xy 36.4555 -409.205437) (xy 36.431719 -409.289019) (xy 36.400327 -409.370051)
			(xy 36.361593 -409.44784) (xy 36.315846 -409.521724) (xy 36.263477 -409.591071) (xy 36.204933 -409.655291)
			(xy 36.140713 -409.713835) (xy 36.071366 -409.766204) (xy 35.997482 -409.811951) (xy 35.919693 -409.850685)
			(xy 35.838661 -409.882077) (xy 35.755079 -409.905858) (xy 35.669659 -409.921826) (xy 35.58313 -409.929844)
			(xy 35.49623 -409.929844) (xy 35.409701 -409.921826) (xy 35.324281 -409.905858) (xy 35.240699 -409.882077)
			(xy 35.159667 -409.850685) (xy 35.081878 -409.811951) (xy 35.007994 -409.766204) (xy 34.938647 -409.713835)
			(xy 34.874427 -409.655291) (xy 34.815883 -409.591071) (xy 34.763514 -409.521724) (xy 34.717767 -409.44784)
			(xy 34.679033 -409.370051) (xy 34.647641 -409.289019) (xy 34.62386 -409.205437) (xy 34.607892 -409.120017)
			(xy 34.599874 -409.033488) (xy 31.399486 -409.033488) (xy 31.391468 -409.120017) (xy 31.3755 -409.205437)
			(xy 31.351719 -409.289019) (xy 31.320327 -409.370051) (xy 31.281593 -409.44784) (xy 31.235846 -409.521724)
			(xy 31.183477 -409.591071) (xy 31.124933 -409.655291) (xy 31.060713 -409.713835) (xy 30.991366 -409.766204)
			(xy 30.917482 -409.811951) (xy 30.839693 -409.850685) (xy 30.758661 -409.882077) (xy 30.675079 -409.905858)
			(xy 30.589659 -409.921826) (xy 30.50313 -409.929844) (xy 30.41623 -409.929844) (xy 30.329701 -409.921826)
			(xy 30.244281 -409.905858) (xy 30.160699 -409.882077) (xy 30.079667 -409.850685) (xy 30.001878 -409.811951)
			(xy 29.927994 -409.766204) (xy 29.858647 -409.713835) (xy 29.794427 -409.655291) (xy 29.735883 -409.591071)
			(xy 29.683514 -409.521724) (xy 29.637767 -409.44784) (xy 29.599033 -409.370051) (xy 29.567641 -409.289019)
			(xy 29.54386 -409.205437) (xy 29.527892 -409.120017) (xy 29.519874 -409.033488) (xy 28.353512 -409.033488)
			(xy 28.353512 -411.573488) (xy 29.519874 -411.573488) (xy 29.519874 -411.486588) (xy 29.527892 -411.400059)
			(xy 29.54386 -411.314639) (xy 29.567641 -411.231057) (xy 29.599033 -411.150025) (xy 29.637767 -411.072236)
			(xy 29.683514 -410.998352) (xy 29.735883 -410.929005) (xy 29.794427 -410.864785) (xy 29.858647 -410.806241)
			(xy 29.927994 -410.753872) (xy 30.001878 -410.708125) (xy 30.079667 -410.669391) (xy 30.160699 -410.637999)
			(xy 30.244281 -410.614218) (xy 30.329701 -410.59825) (xy 30.41623 -410.590232) (xy 30.50313 -410.590232)
			(xy 30.589659 -410.59825) (xy 30.675079 -410.614218) (xy 30.758661 -410.637999) (xy 30.839693 -410.669391)
			(xy 30.917482 -410.708125) (xy 30.991366 -410.753872) (xy 31.060713 -410.806241) (xy 31.124933 -410.864785)
			(xy 31.183477 -410.929005) (xy 31.235846 -410.998352) (xy 31.281593 -411.072236) (xy 31.320327 -411.150025)
			(xy 31.351719 -411.231057) (xy 31.3755 -411.314639) (xy 31.391468 -411.400059) (xy 31.399486 -411.486588)
			(xy 31.399988 -411.530038) (xy 31.399486 -411.573488) (xy 34.599874 -411.573488) (xy 34.599874 -411.486588)
			(xy 34.607892 -411.400059) (xy 34.62386 -411.314639) (xy 34.647641 -411.231057) (xy 34.679033 -411.150025)
			(xy 34.717767 -411.072236) (xy 34.763514 -410.998352) (xy 34.815883 -410.929005) (xy 34.874427 -410.864785)
			(xy 34.938647 -410.806241) (xy 35.007994 -410.753872) (xy 35.081878 -410.708125) (xy 35.159667 -410.669391)
			(xy 35.240699 -410.637999) (xy 35.324281 -410.614218) (xy 35.409701 -410.59825) (xy 35.49623 -410.590232)
			(xy 35.58313 -410.590232) (xy 35.669659 -410.59825) (xy 35.755079 -410.614218) (xy 35.838661 -410.637999)
			(xy 35.919693 -410.669391) (xy 35.997482 -410.708125) (xy 36.071366 -410.753872) (xy 36.140713 -410.806241)
			(xy 36.204933 -410.864785) (xy 36.263477 -410.929005) (xy 36.315846 -410.998352) (xy 36.361593 -411.072236)
			(xy 36.400327 -411.150025) (xy 36.431719 -411.231057) (xy 36.4555 -411.314639) (xy 36.471468 -411.400059)
			(xy 36.479486 -411.486588) (xy 36.479988 -411.530038) (xy 36.479486 -411.573488) (xy 36.471468 -411.660017)
			(xy 36.4555 -411.745437) (xy 36.431719 -411.829019) (xy 36.400327 -411.910051) (xy 36.383933 -411.942975)
			(xy 65.293443 -411.942975) (xy 65.297334 -411.888631) (xy 65.308919 -411.835394) (xy 65.327962 -411.784347)
			(xy 65.354076 -411.736531) (xy 65.386729 -411.692917) (xy 65.425257 -411.654395) (xy 65.468876 -411.621747)
			(xy 65.516696 -411.59564) (xy 65.567745 -411.576604) (xy 65.620984 -411.565026) (xy 65.675328 -411.561143)
			(xy 65.729672 -411.565034) (xy 65.782909 -411.576619) (xy 65.833955 -411.595663) (xy 65.881772 -411.621778)
			(xy 65.903856 -411.637734) (xy 65.922868 -411.65133) (xy 65.964751 -411.672062) (xy 66.009719 -411.684788)
			(xy 66.056256 -411.689078) (xy 66.102793 -411.684788) (xy 66.147761 -411.672062) (xy 66.189644 -411.65133)
			(xy 66.208656 -411.637734) (xy 66.230706 -411.621714) (xy 66.278537 -411.59558) (xy 66.3296 -411.576521)
			(xy 66.382857 -411.564923) (xy 66.437222 -411.561023) (xy 66.491588 -411.564901) (xy 66.544849 -411.576477)
			(xy 66.595921 -411.595515) (xy 66.643762 -411.621629) (xy 66.6874 -411.654286) (xy 66.725946 -411.692821)
			(xy 66.758615 -411.73645) (xy 66.784742 -411.784285) (xy 66.803794 -411.835351) (xy 66.815384 -411.888609)
			(xy 66.819277 -411.942975) (xy 68.285036 -411.942975) (xy 68.288927 -411.888629) (xy 68.300512 -411.835391)
			(xy 68.319556 -411.784343) (xy 68.345671 -411.736525) (xy 68.378326 -411.69291) (xy 68.416856 -411.654387)
			(xy 68.460475 -411.621739) (xy 68.508298 -411.595631) (xy 68.559348 -411.576595) (xy 68.612589 -411.565018)
			(xy 68.666935 -411.561136) (xy 68.72128 -411.565028) (xy 68.774519 -411.576615) (xy 68.825566 -411.59566)
			(xy 68.873384 -411.621777) (xy 68.895468 -411.637734) (xy 68.91448 -411.65133) (xy 68.956363 -411.672062)
			(xy 69.001331 -411.684788) (xy 69.047868 -411.689078) (xy 69.094405 -411.684788) (xy 69.139373 -411.672062)
			(xy 69.181256 -411.65133) (xy 69.200268 -411.637734) (xy 69.222318 -411.621715) (xy 69.270148 -411.595583)
			(xy 69.32121 -411.576526) (xy 69.374465 -411.564929) (xy 69.428829 -411.561031) (xy 69.483193 -411.564909)
			(xy 69.536453 -411.576485) (xy 69.587522 -411.595524) (xy 69.635362 -411.621637) (xy 69.678999 -411.654294)
			(xy 69.717543 -411.692828) (xy 69.75021 -411.736456) (xy 69.776336 -411.78429) (xy 69.795387 -411.835355)
			(xy 69.806977 -411.888611) (xy 69.810869 -411.942975) (xy 69.806984 -411.997339) (xy 69.795402 -412.050597)
			(xy 69.776357 -412.101664) (xy 69.750238 -412.149501) (xy 69.717576 -412.193134) (xy 69.679037 -412.231673)
			(xy 69.635405 -412.264335) (xy 69.587568 -412.290455) (xy 69.536501 -412.3095) (xy 69.483243 -412.321084)
			(xy 69.428879 -412.324969) (xy 69.374515 -412.321078) (xy 69.321259 -412.309489) (xy 69.270194 -412.290438)
			(xy 69.22236 -412.264313) (xy 69.200268 -412.24835) (xy 69.181256 -412.234754) (xy 69.139373 -412.214022)
			(xy 69.094405 -412.201296) (xy 69.047868 -412.197006) (xy 69.001331 -412.201296) (xy 68.956363 -412.214022)
			(xy 68.91448 -412.234754) (xy 68.895468 -412.24835) (xy 68.873341 -412.264251) (xy 68.82552 -412.290361)
			(xy 68.77447 -412.309399) (xy 68.721231 -412.320979) (xy 68.666885 -412.324864) (xy 68.612539 -412.320975)
			(xy 68.5593 -412.309391) (xy 68.508252 -412.290348) (xy 68.460433 -412.264234) (xy 68.416817 -412.23158)
			(xy 68.378293 -412.193052) (xy 68.345644 -412.149433) (xy 68.319535 -412.101611) (xy 68.300498 -412.050561)
			(xy 68.28892 -411.997321) (xy 68.285036 -411.942975) (xy 66.819277 -411.942975) (xy 66.815391 -411.997341)
			(xy 66.803808 -412.0506) (xy 66.784763 -412.101669) (xy 66.758642 -412.149507) (xy 66.725979 -412.193141)
			(xy 66.687439 -412.231681) (xy 66.643805 -412.264344) (xy 66.595967 -412.290464) (xy 66.544898 -412.309509)
			(xy 66.491638 -412.321092) (xy 66.437272 -412.324977) (xy 66.382907 -412.321084) (xy 66.329649 -412.309493)
			(xy 66.278583 -412.29044) (xy 66.230748 -412.264314) (xy 66.208656 -412.24835) (xy 66.189644 -412.234754)
			(xy 66.147761 -412.214022) (xy 66.102793 -412.201296) (xy 66.056256 -412.197006) (xy 66.009719 -412.201296)
			(xy 65.964751 -412.214022) (xy 65.922868 -412.234754) (xy 65.903856 -412.24835) (xy 65.881729 -412.26425)
			(xy 65.833909 -412.290358) (xy 65.782861 -412.309395) (xy 65.729622 -412.320973) (xy 65.675278 -412.324857)
			(xy 65.620934 -412.320967) (xy 65.567697 -412.309382) (xy 65.51665 -412.290339) (xy 65.468833 -412.264226)
			(xy 65.425219 -412.231572) (xy 65.386696 -412.193045) (xy 65.354049 -412.149427) (xy 65.327941 -412.101607)
			(xy 65.308904 -412.050558) (xy 65.297327 -411.997319) (xy 65.293443 -411.942975) (xy 36.383933 -411.942975)
			(xy 36.361593 -411.98784) (xy 36.315846 -412.061724) (xy 36.263477 -412.131071) (xy 36.204933 -412.195291)
			(xy 36.140713 -412.253835) (xy 36.071366 -412.306204) (xy 35.997482 -412.351951) (xy 35.919693 -412.390685)
			(xy 35.838661 -412.422077) (xy 35.755079 -412.445858) (xy 35.669659 -412.461826) (xy 35.58313 -412.469844)
			(xy 35.49623 -412.469844) (xy 35.409701 -412.461826) (xy 35.324281 -412.445858) (xy 35.240699 -412.422077)
			(xy 35.159667 -412.390685) (xy 35.081878 -412.351951) (xy 35.007994 -412.306204) (xy 34.938647 -412.253835)
			(xy 34.874427 -412.195291) (xy 34.815883 -412.131071) (xy 34.763514 -412.061724) (xy 34.717767 -411.98784)
			(xy 34.679033 -411.910051) (xy 34.647641 -411.829019) (xy 34.62386 -411.745437) (xy 34.607892 -411.660017)
			(xy 34.599874 -411.573488) (xy 31.399486 -411.573488) (xy 31.391468 -411.660017) (xy 31.3755 -411.745437)
			(xy 31.351719 -411.829019) (xy 31.320327 -411.910051) (xy 31.281593 -411.98784) (xy 31.235846 -412.061724)
			(xy 31.183477 -412.131071) (xy 31.124933 -412.195291) (xy 31.060713 -412.253835) (xy 30.991366 -412.306204)
			(xy 30.917482 -412.351951) (xy 30.839693 -412.390685) (xy 30.758661 -412.422077) (xy 30.675079 -412.445858)
			(xy 30.589659 -412.461826) (xy 30.50313 -412.469844) (xy 30.41623 -412.469844) (xy 30.329701 -412.461826)
			(xy 30.244281 -412.445858) (xy 30.160699 -412.422077) (xy 30.079667 -412.390685) (xy 30.001878 -412.351951)
			(xy 29.927994 -412.306204) (xy 29.858647 -412.253835) (xy 29.794427 -412.195291) (xy 29.735883 -412.131071)
			(xy 29.683514 -412.061724) (xy 29.637767 -411.98784) (xy 29.599033 -411.910051) (xy 29.567641 -411.829019)
			(xy 29.54386 -411.745437) (xy 29.527892 -411.660017) (xy 29.519874 -411.573488) (xy 28.353512 -411.573488)
			(xy 28.353512 -414.113488) (xy 29.519874 -414.113488) (xy 29.519874 -414.026588) (xy 29.527892 -413.940059)
			(xy 29.54386 -413.854639) (xy 29.567641 -413.771057) (xy 29.599033 -413.690025) (xy 29.637767 -413.612236)
			(xy 29.683514 -413.538352) (xy 29.735883 -413.469005) (xy 29.794427 -413.404785) (xy 29.858647 -413.346241)
			(xy 29.927994 -413.293872) (xy 30.001878 -413.248125) (xy 30.079667 -413.209391) (xy 30.160699 -413.177999)
			(xy 30.244281 -413.154218) (xy 30.329701 -413.13825) (xy 30.41623 -413.130232) (xy 30.50313 -413.130232)
			(xy 30.589659 -413.13825) (xy 30.675079 -413.154218) (xy 30.758661 -413.177999) (xy 30.839693 -413.209391)
			(xy 30.917482 -413.248125) (xy 30.991366 -413.293872) (xy 31.060713 -413.346241) (xy 31.124933 -413.404785)
			(xy 31.183477 -413.469005) (xy 31.235846 -413.538352) (xy 31.281593 -413.612236) (xy 31.320327 -413.690025)
			(xy 31.351719 -413.771057) (xy 31.3755 -413.854639) (xy 31.391468 -413.940059) (xy 31.399486 -414.026588)
			(xy 31.399988 -414.070038) (xy 31.399486 -414.113488) (xy 34.599874 -414.113488) (xy 34.599874 -414.026588)
			(xy 34.607892 -413.940059) (xy 34.62386 -413.854639) (xy 34.647641 -413.771057) (xy 34.679033 -413.690025)
			(xy 34.717767 -413.612236) (xy 34.763514 -413.538352) (xy 34.815883 -413.469005) (xy 34.874427 -413.404785)
			(xy 34.938647 -413.346241) (xy 35.007994 -413.293872) (xy 35.081878 -413.248125) (xy 35.159667 -413.209391)
			(xy 35.240699 -413.177999) (xy 35.324281 -413.154218) (xy 35.409701 -413.13825) (xy 35.49623 -413.130232)
			(xy 35.58313 -413.130232) (xy 35.669659 -413.13825) (xy 35.755079 -413.154218) (xy 35.838661 -413.177999)
			(xy 35.919693 -413.209391) (xy 35.997482 -413.248125) (xy 36.071366 -413.293872) (xy 36.140713 -413.346241)
			(xy 36.204933 -413.404785) (xy 36.263477 -413.469005) (xy 36.315846 -413.538352) (xy 36.361593 -413.612236)
			(xy 36.400327 -413.690025) (xy 36.431719 -413.771057) (xy 36.4555 -413.854639) (xy 36.471468 -413.940059)
			(xy 36.479486 -414.026588) (xy 36.479988 -414.070038) (xy 36.479486 -414.113488) (xy 36.471468 -414.200017)
			(xy 36.4555 -414.285437) (xy 36.431719 -414.369019) (xy 36.400327 -414.450051) (xy 36.361593 -414.52784)
			(xy 36.315846 -414.601724) (xy 36.306629 -414.613929) (xy 65.293371 -414.613929) (xy 65.297255 -414.559574)
			(xy 65.308834 -414.506325) (xy 65.327874 -414.455267) (xy 65.353986 -414.407437) (xy 65.38664 -414.363811)
			(xy 65.425169 -414.325275) (xy 65.468791 -414.292616) (xy 65.516617 -414.266497) (xy 65.567673 -414.24745)
			(xy 65.62092 -414.235863) (xy 65.675274 -414.231971) (xy 65.729629 -414.235855) (xy 65.782877 -414.247435)
			(xy 65.833936 -414.266475) (xy 65.881765 -414.292588) (xy 65.903856 -414.308544) (xy 65.922868 -414.32214)
			(xy 65.964751 -414.342872) (xy 66.009719 -414.355598) (xy 66.056256 -414.359888) (xy 66.102793 -414.355598)
			(xy 66.147761 -414.342872) (xy 66.189644 -414.32214) (xy 66.208656 -414.308544) (xy 66.23079 -414.292645)
			(xy 66.278616 -414.266524) (xy 66.329673 -414.247475) (xy 66.382921 -414.235887) (xy 66.437276 -414.231996)
			(xy 66.491631 -414.23588) (xy 66.544881 -414.247461) (xy 66.59594 -414.266503) (xy 66.643769 -414.292619)
			(xy 66.687394 -414.325276) (xy 66.725927 -414.363809) (xy 66.758584 -414.407435) (xy 66.784698 -414.455264)
			(xy 66.80374 -414.506323) (xy 66.815321 -414.559573) (xy 66.819204 -414.613929) (xy 68.284964 -414.613929)
			(xy 68.288848 -414.559573) (xy 68.300428 -414.506322) (xy 68.319468 -414.455262) (xy 68.345582 -414.407431)
			(xy 68.378236 -414.363804) (xy 68.416768 -414.325268) (xy 68.460391 -414.292607) (xy 68.508218 -414.266488)
			(xy 68.559276 -414.247441) (xy 68.612525 -414.235855) (xy 68.666881 -414.231964) (xy 68.721237 -414.235849)
			(xy 68.774487 -414.24743) (xy 68.825547 -414.266472) (xy 68.873377 -414.292587) (xy 68.895468 -414.308544)
			(xy 68.91448 -414.32214) (xy 68.956363 -414.342872) (xy 69.001331 -414.355598) (xy 69.047868 -414.359888)
			(xy 69.094405 -414.355598) (xy 69.139373 -414.342872) (xy 69.181256 -414.32214) (xy 69.200268 -414.308544)
			(xy 69.222402 -414.292646) (xy 69.270227 -414.266526) (xy 69.321282 -414.24748) (xy 69.374529 -414.235893)
			(xy 69.428883 -414.232003) (xy 69.483237 -414.235888) (xy 69.536484 -414.24747) (xy 69.587541 -414.266512)
			(xy 69.635369 -414.292627) (xy 69.678992 -414.325284) (xy 69.717524 -414.363816) (xy 69.750179 -414.407441)
			(xy 69.776293 -414.455269) (xy 69.795334 -414.506327) (xy 69.806914 -414.559575) (xy 69.810797 -414.613929)
			(xy 69.806905 -414.668282) (xy 69.795317 -414.721529) (xy 69.776269 -414.772584) (xy 69.750148 -414.820408)
			(xy 69.717486 -414.864027) (xy 69.678949 -414.902554) (xy 69.63532 -414.935204) (xy 69.587489 -414.961312)
			(xy 69.536429 -414.980347) (xy 69.48318 -414.99192) (xy 69.428825 -414.995797) (xy 69.374472 -414.991899)
			(xy 69.321227 -414.980304) (xy 69.270174 -414.96125) (xy 69.222353 -414.935123) (xy 69.200268 -414.91916)
			(xy 69.181256 -414.905564) (xy 69.139373 -414.884832) (xy 69.094405 -414.872106) (xy 69.047868 -414.867816)
			(xy 69.001331 -414.872106) (xy 68.956363 -414.884832) (xy 68.91448 -414.905564) (xy 68.895468 -414.91916)
			(xy 68.873426 -414.935182) (xy 68.825599 -414.961304) (xy 68.774543 -414.980353) (xy 68.721294 -414.991943)
			(xy 68.666939 -414.995836) (xy 68.612582 -414.991954) (xy 68.559332 -414.980375) (xy 68.508271 -414.961336)
			(xy 68.460439 -414.935224) (xy 68.416811 -414.90257) (xy 68.378274 -414.86404) (xy 68.345613 -414.820417)
			(xy 68.319492 -414.77259) (xy 68.300444 -414.721533) (xy 68.288856 -414.668285) (xy 68.284964 -414.613929)
			(xy 66.819204 -414.613929) (xy 66.815312 -414.668284) (xy 66.803724 -414.721532) (xy 66.784675 -414.772588)
			(xy 66.758552 -414.820414) (xy 66.725889 -414.864034) (xy 66.687351 -414.902562) (xy 66.64372 -414.935212)
			(xy 66.595888 -414.961321) (xy 66.544826 -414.980355) (xy 66.491574 -414.991928) (xy 66.437218 -414.995804)
			(xy 66.382864 -414.991905) (xy 66.329617 -414.980309) (xy 66.278564 -414.961252) (xy 66.230742 -414.935124)
			(xy 66.208656 -414.91916) (xy 66.189644 -414.905564) (xy 66.147761 -414.884832) (xy 66.102793 -414.872106)
			(xy 66.056256 -414.867816) (xy 66.009719 -414.872106) (xy 65.964751 -414.884832) (xy 65.922868 -414.905564)
			(xy 65.903856 -414.91916) (xy 65.881814 -414.935181) (xy 65.833989 -414.961301) (xy 65.782933 -414.980349)
			(xy 65.729686 -414.991937) (xy 65.675332 -414.995829) (xy 65.620977 -414.991946) (xy 65.567728 -414.980367)
			(xy 65.516669 -414.961327) (xy 65.46884 -414.935215) (xy 65.425213 -414.902562) (xy 65.386677 -414.864033)
			(xy 65.354017 -414.820411) (xy 65.327898 -414.772586) (xy 65.30885 -414.72153) (xy 65.297263 -414.668283)
			(xy 65.293371 -414.613929) (xy 36.306629 -414.613929) (xy 36.263477 -414.671071) (xy 36.204933 -414.735291)
			(xy 36.140713 -414.793835) (xy 36.071366 -414.846204) (xy 35.997482 -414.891951) (xy 35.919693 -414.930685)
			(xy 35.838661 -414.962077) (xy 35.755079 -414.985858) (xy 35.669659 -415.001826) (xy 35.58313 -415.009844)
			(xy 35.49623 -415.009844) (xy 35.409701 -415.001826) (xy 35.324281 -414.985858) (xy 35.240699 -414.962077)
			(xy 35.159667 -414.930685) (xy 35.081878 -414.891951) (xy 35.007994 -414.846204) (xy 34.938647 -414.793835)
			(xy 34.874427 -414.735291) (xy 34.815883 -414.671071) (xy 34.763514 -414.601724) (xy 34.717767 -414.52784)
			(xy 34.679033 -414.450051) (xy 34.647641 -414.369019) (xy 34.62386 -414.285437) (xy 34.607892 -414.200017)
			(xy 34.599874 -414.113488) (xy 31.399486 -414.113488) (xy 31.391468 -414.200017) (xy 31.3755 -414.285437)
			(xy 31.351719 -414.369019) (xy 31.320327 -414.450051) (xy 31.281593 -414.52784) (xy 31.235846 -414.601724)
			(xy 31.183477 -414.671071) (xy 31.124933 -414.735291) (xy 31.060713 -414.793835) (xy 30.991366 -414.846204)
			(xy 30.917482 -414.891951) (xy 30.839693 -414.930685) (xy 30.758661 -414.962077) (xy 30.675079 -414.985858)
			(xy 30.589659 -415.001826) (xy 30.50313 -415.009844) (xy 30.41623 -415.009844) (xy 30.329701 -415.001826)
			(xy 30.244281 -414.985858) (xy 30.160699 -414.962077) (xy 30.079667 -414.930685) (xy 30.001878 -414.891951)
			(xy 29.927994 -414.846204) (xy 29.858647 -414.793835) (xy 29.794427 -414.735291) (xy 29.735883 -414.671071)
			(xy 29.683514 -414.601724) (xy 29.637767 -414.52784) (xy 29.599033 -414.450051) (xy 29.567641 -414.369019)
			(xy 29.54386 -414.285437) (xy 29.527892 -414.200017) (xy 29.519874 -414.113488) (xy 28.353512 -414.113488)
			(xy 28.353512 -416.653488) (xy 29.519874 -416.653488) (xy 29.519874 -416.566588) (xy 29.527892 -416.480059)
			(xy 29.54386 -416.394639) (xy 29.567641 -416.311057) (xy 29.599033 -416.230025) (xy 29.637767 -416.152236)
			(xy 29.683514 -416.078352) (xy 29.735883 -416.009005) (xy 29.794427 -415.944785) (xy 29.858647 -415.886241)
			(xy 29.927994 -415.833872) (xy 30.001878 -415.788125) (xy 30.079667 -415.749391) (xy 30.160699 -415.717999)
			(xy 30.244281 -415.694218) (xy 30.329701 -415.67825) (xy 30.41623 -415.670232) (xy 30.50313 -415.670232)
			(xy 30.589659 -415.67825) (xy 30.675079 -415.694218) (xy 30.758661 -415.717999) (xy 30.839693 -415.749391)
			(xy 30.917482 -415.788125) (xy 30.991366 -415.833872) (xy 31.060713 -415.886241) (xy 31.124933 -415.944785)
			(xy 31.183477 -416.009005) (xy 31.235846 -416.078352) (xy 31.281593 -416.152236) (xy 31.320327 -416.230025)
			(xy 31.351719 -416.311057) (xy 31.3755 -416.394639) (xy 31.391468 -416.480059) (xy 31.399486 -416.566588)
			(xy 31.399988 -416.610038) (xy 31.399486 -416.653488) (xy 34.599874 -416.653488) (xy 34.599874 -416.566588)
			(xy 34.607892 -416.480059) (xy 34.62386 -416.394639) (xy 34.647641 -416.311057) (xy 34.679033 -416.230025)
			(xy 34.717767 -416.152236) (xy 34.763514 -416.078352) (xy 34.815883 -416.009005) (xy 34.874427 -415.944785)
			(xy 34.938647 -415.886241) (xy 35.007994 -415.833872) (xy 35.081878 -415.788125) (xy 35.159667 -415.749391)
			(xy 35.240699 -415.717999) (xy 35.324281 -415.694218) (xy 35.409701 -415.67825) (xy 35.49623 -415.670232)
			(xy 35.58313 -415.670232) (xy 35.669659 -415.67825) (xy 35.755079 -415.694218) (xy 35.838661 -415.717999)
			(xy 35.919693 -415.749391) (xy 35.997482 -415.788125) (xy 36.071366 -415.833872) (xy 36.140713 -415.886241)
			(xy 36.204933 -415.944785) (xy 36.263477 -416.009005) (xy 36.315846 -416.078352) (xy 36.361593 -416.152236)
			(xy 36.400327 -416.230025) (xy 36.431719 -416.311057) (xy 36.4555 -416.394639) (xy 36.471468 -416.480059)
			(xy 36.479486 -416.566588) (xy 36.479988 -416.610038) (xy 36.479486 -416.653488) (xy 36.471468 -416.740017)
			(xy 36.4555 -416.825437) (xy 36.431719 -416.909019) (xy 36.400327 -416.990051) (xy 36.361593 -417.06784)
			(xy 36.315846 -417.141724) (xy 36.263477 -417.211071) (xy 36.204933 -417.275291) (xy 36.197478 -417.282087)
			(xy 65.293427 -417.282087) (xy 65.297316 -417.227741) (xy 65.3089 -417.174501) (xy 65.327942 -417.123452)
			(xy 65.354056 -417.075632) (xy 65.38671 -417.032016) (xy 65.425238 -416.99349) (xy 65.468857 -416.96084)
			(xy 65.516678 -416.93473) (xy 65.567729 -416.915692) (xy 65.62097 -416.904112) (xy 65.675316 -416.900227)
			(xy 65.729662 -416.904117) (xy 65.782902 -416.915701) (xy 65.833951 -416.934744) (xy 65.88177 -416.960858)
			(xy 65.903856 -416.976814) (xy 65.922868 -416.99041) (xy 65.964751 -417.011142) (xy 66.009719 -417.023868)
			(xy 66.056256 -417.028158) (xy 66.102793 -417.023868) (xy 66.147761 -417.011142) (xy 66.189644 -416.99041)
			(xy 66.208656 -416.976814) (xy 66.230725 -416.960821) (xy 66.278554 -416.93469) (xy 66.329616 -416.915633)
			(xy 66.382871 -416.904037) (xy 66.437234 -416.90014) (xy 66.491598 -416.904019) (xy 66.544856 -416.915596)
			(xy 66.595925 -416.934635) (xy 66.643764 -416.960749) (xy 66.687399 -416.993406) (xy 66.725942 -417.031941)
			(xy 66.758608 -417.075569) (xy 66.784732 -417.123403) (xy 66.803782 -417.174467) (xy 66.81537 -417.227724)
			(xy 66.819261 -417.282087) (xy 68.28502 -417.282087) (xy 68.288909 -417.227739) (xy 68.300493 -417.174498)
			(xy 68.319537 -417.123447) (xy 68.345651 -417.075626) (xy 68.378306 -417.032009) (xy 68.416836 -416.993482)
			(xy 68.460457 -416.960832) (xy 68.50828 -416.934722) (xy 68.559332 -416.915683) (xy 68.612575 -416.904104)
			(xy 68.666923 -416.90022) (xy 68.721271 -416.904111) (xy 68.774512 -416.915696) (xy 68.825562 -416.934741)
			(xy 68.873382 -416.960857) (xy 68.895468 -416.976814) (xy 68.91448 -416.99041) (xy 68.956363 -417.011142)
			(xy 69.001331 -417.023868) (xy 69.047868 -417.028158) (xy 69.094405 -417.023868) (xy 69.139373 -417.011142)
			(xy 69.181256 -416.99041) (xy 69.200268 -416.976814) (xy 69.222336 -416.960822) (xy 69.270165 -416.934693)
			(xy 69.321226 -416.915638) (xy 69.374479 -416.904043) (xy 69.428841 -416.900147) (xy 69.483203 -416.904027)
			(xy 69.53646 -416.915604) (xy 69.587527 -416.934644) (xy 69.635364 -416.960757) (xy 69.678997 -416.993414)
			(xy 69.717539 -417.031948) (xy 69.750203 -417.075575) (xy 69.776326 -417.123407) (xy 69.795375 -417.174471)
			(xy 69.806963 -417.227725) (xy 69.810853 -417.282087) (xy 69.806967 -417.336449) (xy 69.795383 -417.389704)
			(xy 69.776337 -417.440769) (xy 69.750218 -417.488603) (xy 69.717556 -417.532232) (xy 69.679017 -417.570769)
			(xy 69.635386 -417.603428) (xy 69.587551 -417.629545) (xy 69.536485 -417.648588) (xy 69.483229 -417.66017)
			(xy 69.428867 -417.664053) (xy 69.374506 -417.66016) (xy 69.321252 -417.64857) (xy 69.270189 -417.629518)
			(xy 69.222359 -417.603393) (xy 69.200268 -417.58743) (xy 69.181256 -417.573834) (xy 69.139373 -417.553102)
			(xy 69.094405 -417.540376) (xy 69.047868 -417.536086) (xy 69.001331 -417.540376) (xy 68.956363 -417.553102)
			(xy 68.91448 -417.573834) (xy 68.895468 -417.58743) (xy 68.87336 -417.603358) (xy 68.825538 -417.62947)
			(xy 68.774486 -417.648511) (xy 68.721245 -417.660093) (xy 68.666897 -417.66398) (xy 68.612549 -417.660092)
			(xy 68.559307 -417.648509) (xy 68.508256 -417.629468) (xy 68.460434 -417.603354) (xy 68.416816 -417.5707)
			(xy 68.378289 -417.532171) (xy 68.345637 -417.488552) (xy 68.319526 -417.440729) (xy 68.300486 -417.389677)
			(xy 68.288906 -417.336435) (xy 68.28502 -417.282087) (xy 66.819261 -417.282087) (xy 66.815374 -417.33645)
			(xy 66.803789 -417.389707) (xy 66.784743 -417.440773) (xy 66.758622 -417.488609) (xy 66.725959 -417.532239)
			(xy 66.687419 -417.570777) (xy 66.643786 -417.603437) (xy 66.595949 -417.629554) (xy 66.544882 -417.648597)
			(xy 66.491624 -417.660178) (xy 66.43726 -417.664061) (xy 66.382897 -417.660166) (xy 66.329642 -417.648574)
			(xy 66.278578 -417.629521) (xy 66.230747 -417.603394) (xy 66.208656 -417.58743) (xy 66.189644 -417.573834)
			(xy 66.147761 -417.553102) (xy 66.102793 -417.540376) (xy 66.056256 -417.536086) (xy 66.009719 -417.540376)
			(xy 65.964751 -417.553102) (xy 65.922868 -417.573834) (xy 65.903856 -417.58743) (xy 65.881748 -417.603357)
			(xy 65.833927 -417.629467) (xy 65.782877 -417.648507) (xy 65.729636 -417.660087) (xy 65.67529 -417.663973)
			(xy 65.620944 -417.660084) (xy 65.567704 -417.648501) (xy 65.516654 -417.629459) (xy 65.468835 -417.603346)
			(xy 65.425218 -417.570692) (xy 65.386692 -417.532164) (xy 65.354042 -417.488546) (xy 65.327931 -417.440724)
			(xy 65.308892 -417.389674) (xy 65.297313 -417.336433) (xy 65.293427 -417.282087) (xy 36.197478 -417.282087)
			(xy 36.140713 -417.333835) (xy 36.071366 -417.386204) (xy 35.997482 -417.431951) (xy 35.919693 -417.470685)
			(xy 35.838661 -417.502077) (xy 35.755079 -417.525858) (xy 35.669659 -417.541826) (xy 35.58313 -417.549844)
			(xy 35.49623 -417.549844) (xy 35.409701 -417.541826) (xy 35.324281 -417.525858) (xy 35.240699 -417.502077)
			(xy 35.159667 -417.470685) (xy 35.081878 -417.431951) (xy 35.007994 -417.386204) (xy 34.938647 -417.333835)
			(xy 34.874427 -417.275291) (xy 34.815883 -417.211071) (xy 34.763514 -417.141724) (xy 34.717767 -417.06784)
			(xy 34.679033 -416.990051) (xy 34.647641 -416.909019) (xy 34.62386 -416.825437) (xy 34.607892 -416.740017)
			(xy 34.599874 -416.653488) (xy 31.399486 -416.653488) (xy 31.391468 -416.740017) (xy 31.3755 -416.825437)
			(xy 31.351719 -416.909019) (xy 31.320327 -416.990051) (xy 31.281593 -417.06784) (xy 31.235846 -417.141724)
			(xy 31.183477 -417.211071) (xy 31.124933 -417.275291) (xy 31.060713 -417.333835) (xy 30.991366 -417.386204)
			(xy 30.917482 -417.431951) (xy 30.839693 -417.470685) (xy 30.758661 -417.502077) (xy 30.675079 -417.525858)
			(xy 30.589659 -417.541826) (xy 30.50313 -417.549844) (xy 30.41623 -417.549844) (xy 30.329701 -417.541826)
			(xy 30.244281 -417.525858) (xy 30.160699 -417.502077) (xy 30.079667 -417.470685) (xy 30.001878 -417.431951)
			(xy 29.927994 -417.386204) (xy 29.858647 -417.333835) (xy 29.794427 -417.275291) (xy 29.735883 -417.211071)
			(xy 29.683514 -417.141724) (xy 29.637767 -417.06784) (xy 29.599033 -416.990051) (xy 29.567641 -416.909019)
			(xy 29.54386 -416.825437) (xy 29.527892 -416.740017) (xy 29.519874 -416.653488) (xy 28.353512 -416.653488)
			(xy 28.353512 -417.811204) (xy 51.478688 -417.811204) (xy 53.130196 -417.811204) (xy 53.130196 -419.462712)
			(xy 51.478688 -419.462712) (xy 51.478688 -417.811204) (xy 28.353512 -417.811204) (xy 28.353512 -419.193488)
			(xy 29.519874 -419.193488) (xy 29.519874 -419.106588) (xy 29.527892 -419.020059) (xy 29.54386 -418.934639)
			(xy 29.567641 -418.851057) (xy 29.599033 -418.770025) (xy 29.637767 -418.692236) (xy 29.683514 -418.618352)
			(xy 29.735883 -418.549005) (xy 29.794427 -418.484785) (xy 29.858647 -418.426241) (xy 29.927994 -418.373872)
			(xy 30.001878 -418.328125) (xy 30.079667 -418.289391) (xy 30.160699 -418.257999) (xy 30.244281 -418.234218)
			(xy 30.329701 -418.21825) (xy 30.41623 -418.210232) (xy 30.50313 -418.210232) (xy 30.589659 -418.21825)
			(xy 30.675079 -418.234218) (xy 30.758661 -418.257999) (xy 30.839693 -418.289391) (xy 30.917482 -418.328125)
			(xy 30.991366 -418.373872) (xy 31.060713 -418.426241) (xy 31.124933 -418.484785) (xy 31.183477 -418.549005)
			(xy 31.235846 -418.618352) (xy 31.281593 -418.692236) (xy 31.320327 -418.770025) (xy 31.351719 -418.851057)
			(xy 31.3755 -418.934639) (xy 31.391468 -419.020059) (xy 31.399486 -419.106588) (xy 31.399988 -419.150038)
			(xy 31.399486 -419.193488) (xy 34.599874 -419.193488) (xy 34.599874 -419.106588) (xy 34.607892 -419.020059)
			(xy 34.62386 -418.934639) (xy 34.647641 -418.851057) (xy 34.679033 -418.770025) (xy 34.717767 -418.692236)
			(xy 34.763514 -418.618352) (xy 34.815883 -418.549005) (xy 34.874427 -418.484785) (xy 34.938647 -418.426241)
			(xy 35.007994 -418.373872) (xy 35.081878 -418.328125) (xy 35.159667 -418.289391) (xy 35.240699 -418.257999)
			(xy 35.324281 -418.234218) (xy 35.409701 -418.21825) (xy 35.49623 -418.210232) (xy 35.58313 -418.210232)
			(xy 35.669659 -418.21825) (xy 35.755079 -418.234218) (xy 35.838661 -418.257999) (xy 35.919693 -418.289391)
			(xy 35.997482 -418.328125) (xy 36.071366 -418.373872) (xy 36.140713 -418.426241) (xy 36.204933 -418.484785)
			(xy 36.263477 -418.549005) (xy 36.315846 -418.618352) (xy 36.352477 -418.677513) (xy 47.978812 -418.677513)
			(xy 47.978812 -418.596403) (xy 47.986762 -418.515684) (xy 48.002585 -418.436133) (xy 48.02613 -418.358517)
			(xy 48.057169 -418.283581) (xy 48.095404 -418.212049) (xy 48.140466 -418.144609) (xy 48.191921 -418.08191)
			(xy 48.249274 -418.024557) (xy 48.311973 -417.973102) (xy 48.379413 -417.92804) (xy 48.450945 -417.889805)
			(xy 48.525881 -417.858766) (xy 48.603497 -417.835221) (xy 48.683048 -417.819398) (xy 48.763767 -417.811448)
			(xy 48.844877 -417.811448) (xy 48.925596 -417.819398) (xy 49.005147 -417.835221) (xy 49.082763 -417.858766)
			(xy 49.157699 -417.889805) (xy 49.229231 -417.92804) (xy 49.296671 -417.973102) (xy 49.35937 -418.024557)
			(xy 49.416723 -418.08191) (xy 49.468178 -418.144609) (xy 49.51324 -418.212049) (xy 49.551475 -418.283581)
			(xy 49.582514 -418.358517) (xy 49.606059 -418.436133) (xy 49.621882 -418.515684) (xy 49.629832 -418.596403)
			(xy 49.63033 -418.636958) (xy 49.629832 -418.677513) (xy 49.621882 -418.758232) (xy 49.606059 -418.837783)
			(xy 49.582514 -418.915399) (xy 49.551475 -418.990335) (xy 49.51324 -419.061867) (xy 49.468178 -419.129307)
			(xy 49.416723 -419.192006) (xy 49.35937 -419.249359) (xy 49.296671 -419.300814) (xy 49.229231 -419.345876)
			(xy 49.157699 -419.384111) (xy 49.082763 -419.41515) (xy 49.005147 -419.438695) (xy 48.925596 -419.454518)
			(xy 48.844877 -419.462468) (xy 48.763767 -419.462468) (xy 48.683048 -419.454518) (xy 48.603497 -419.438695)
			(xy 48.525881 -419.41515) (xy 48.450945 -419.384111) (xy 48.379413 -419.345876) (xy 48.311973 -419.300814)
			(xy 48.249274 -419.249359) (xy 48.191921 -419.192006) (xy 48.140466 -419.129307) (xy 48.095404 -419.061867)
			(xy 48.057169 -418.990335) (xy 48.02613 -418.915399) (xy 48.002585 -418.837783) (xy 47.986762 -418.758232)
			(xy 47.978812 -418.677513) (xy 36.352477 -418.677513) (xy 36.361593 -418.692236) (xy 36.400327 -418.770025)
			(xy 36.431719 -418.851057) (xy 36.4555 -418.934639) (xy 36.471468 -419.020059) (xy 36.479486 -419.106588)
			(xy 36.479988 -419.150038) (xy 36.479486 -419.193488) (xy 36.471468 -419.280017) (xy 36.4555 -419.365437)
			(xy 36.431719 -419.449019) (xy 36.400327 -419.530051) (xy 36.361593 -419.60784) (xy 36.333205 -419.653688)
			(xy 65.293426 -419.653688) (xy 65.297315 -419.599341) (xy 65.308898 -419.546102) (xy 65.32794 -419.495052)
			(xy 65.354054 -419.447232) (xy 65.386708 -419.403616) (xy 65.425236 -419.36509) (xy 65.468855 -419.33244)
			(xy 65.516677 -419.306329) (xy 65.567728 -419.28729) (xy 65.620968 -419.275711) (xy 65.675315 -419.271826)
			(xy 65.729661 -419.275715) (xy 65.782901 -419.287299) (xy 65.833951 -419.306342) (xy 65.88177 -419.332456)
			(xy 65.903856 -419.348412) (xy 65.922868 -419.362008) (xy 65.964751 -419.38274) (xy 66.009719 -419.395466)
			(xy 66.056256 -419.399756) (xy 66.102793 -419.395466) (xy 66.147761 -419.38274) (xy 66.189644 -419.362008)
			(xy 66.208656 -419.348412) (xy 66.230726 -419.332421) (xy 66.278556 -419.306291) (xy 66.329618 -419.287234)
			(xy 66.382872 -419.275639) (xy 66.437235 -419.271741) (xy 66.491599 -419.27562) (xy 66.544857 -419.287198)
			(xy 66.595925 -419.306237) (xy 66.643764 -419.332351) (xy 66.687399 -419.365008) (xy 66.725942 -419.403543)
			(xy 66.758607 -419.447171) (xy 66.784731 -419.495004) (xy 66.803781 -419.546069) (xy 66.815369 -419.599325)
			(xy 66.819259 -419.653688) (xy 68.285019 -419.653688) (xy 68.288908 -419.59934) (xy 68.300491 -419.546098)
			(xy 68.319535 -419.495047) (xy 68.345649 -419.447226) (xy 68.378304 -419.403608) (xy 68.416834 -419.365082)
			(xy 68.460455 -419.332431) (xy 68.508278 -419.306321) (xy 68.559331 -419.287282) (xy 68.612573 -419.275703)
			(xy 68.666922 -419.271819) (xy 68.72127 -419.275709) (xy 68.774511 -419.287294) (xy 68.825562 -419.306339)
			(xy 68.873382 -419.332455) (xy 68.895468 -419.348412) (xy 68.91448 -419.362008) (xy 68.956363 -419.38274)
			(xy 69.001331 -419.395466) (xy 69.047868 -419.399756) (xy 69.094405 -419.395466) (xy 69.139373 -419.38274)
			(xy 69.181256 -419.362008) (xy 69.200268 -419.348412) (xy 69.222338 -419.332422) (xy 69.270167 -419.306294)
			(xy 69.321228 -419.287239) (xy 69.374481 -419.275645) (xy 69.428842 -419.271748) (xy 69.483204 -419.275628)
			(xy 69.53646 -419.287206) (xy 69.587527 -419.306246) (xy 69.635364 -419.332359) (xy 69.678997 -419.365016)
			(xy 69.717538 -419.40355) (xy 69.750203 -419.447177) (xy 69.776325 -419.495009) (xy 69.795374 -419.546072)
			(xy 69.806962 -419.599327) (xy 69.810852 -419.653688) (xy 69.806965 -419.70805) (xy 69.795381 -419.761305)
			(xy 69.776335 -419.812369) (xy 69.750216 -419.860203) (xy 69.717554 -419.903832) (xy 69.679015 -419.942369)
			(xy 69.635384 -419.975028) (xy 69.587549 -420.001144) (xy 69.536483 -420.020187) (xy 69.483228 -420.031768)
			(xy 69.428866 -420.035652) (xy 69.374505 -420.031759) (xy 69.321251 -420.020168) (xy 69.270189 -420.001116)
			(xy 69.222358 -419.974991) (xy 69.200268 -419.959028) (xy 69.181256 -419.945432) (xy 69.139373 -419.9247)
			(xy 69.094405 -419.911974) (xy 69.047868 -419.907684) (xy 69.001331 -419.911974) (xy 68.956363 -419.9247)
			(xy 68.91448 -419.945432) (xy 68.895468 -419.959028) (xy 68.873362 -419.974958) (xy 68.82554 -420.001071)
			(xy 68.774488 -420.020113) (xy 68.721246 -420.031695) (xy 68.666898 -420.035581) (xy 68.61255 -420.031694)
			(xy 68.559308 -420.020111) (xy 68.508256 -420.001069) (xy 68.460435 -419.974956) (xy 68.416816 -419.942302)
			(xy 68.378288 -419.903773) (xy 68.345636 -419.860154) (xy 68.319525 -419.812331) (xy 68.300485 -419.761279)
			(xy 68.288904 -419.708036) (xy 68.285019 -419.653688) (xy 66.819259 -419.653688) (xy 66.815372 -419.708051)
			(xy 66.803788 -419.761308) (xy 66.784741 -419.812374) (xy 66.75862 -419.860209) (xy 66.725957 -419.903839)
			(xy 66.687417 -419.942376) (xy 66.643784 -419.975036) (xy 66.595947 -420.001153) (xy 66.54488 -420.020196)
			(xy 66.491623 -420.031776) (xy 66.437259 -420.035659) (xy 66.382896 -420.031765) (xy 66.329641 -420.020173)
			(xy 66.278578 -420.001119) (xy 66.230747 -419.974992) (xy 66.208656 -419.959028) (xy 66.189644 -419.945432)
			(xy 66.147761 -419.9247) (xy 66.102793 -419.911974) (xy 66.056256 -419.907684) (xy 66.009719 -419.911974)
			(xy 65.964751 -419.9247) (xy 65.922868 -419.945432) (xy 65.903856 -419.959028) (xy 65.88175 -419.974957)
			(xy 65.833929 -420.001068) (xy 65.782878 -420.020108) (xy 65.729638 -420.031688) (xy 65.675291 -420.035574)
			(xy 65.620944 -420.031686) (xy 65.567704 -420.020103) (xy 65.516655 -420.001061) (xy 65.468835 -419.974948)
			(xy 65.425218 -419.942294) (xy 65.386692 -419.903766) (xy 65.354041 -419.860148) (xy 65.32793 -419.812326)
			(xy 65.308891 -419.761275) (xy 65.297311 -419.708035) (xy 65.293426 -419.653688) (xy 36.333205 -419.653688)
			(xy 36.315846 -419.681724) (xy 36.263477 -419.751071) (xy 36.204933 -419.815291) (xy 36.140713 -419.873835)
			(xy 36.071366 -419.926204) (xy 35.997482 -419.971951) (xy 35.919693 -420.010685) (xy 35.838661 -420.042077)
			(xy 35.775246 -420.06012) (xy 86.39887 -420.06012) (xy 86.402874 -419.860022) (xy 86.414881 -419.660244)
			(xy 86.434872 -419.461107) (xy 86.462814 -419.262929) (xy 86.498662 -419.066027) (xy 86.54236 -418.870718)
			(xy 86.593837 -418.677313) (xy 86.653011 -418.486123) (xy 86.719787 -418.297453) (xy 86.794059 -418.111606)
			(xy 86.875706 -417.928879) (xy 86.964599 -417.749566) (xy 87.060595 -417.573952) (xy 87.16354 -417.40232)
			(xy 87.27327 -417.234944) (xy 87.389608 -417.072093) (xy 87.512369 -416.914026) (xy 87.641356 -416.760998)
			(xy 87.776363 -416.613253) (xy 87.917172 -416.471027) (xy 88.063559 -416.33455) (xy 88.215289 -416.204038)
			(xy 88.37212 -416.079702) (xy 88.533799 -415.96174) (xy 88.700069 -415.850341) (xy 88.870662 -415.745684)
			(xy 89.045306 -415.647936) (xy 89.223722 -415.557253) (xy 89.405622 -415.473782) (xy 89.590717 -415.397655)
			(xy 89.778709 -415.328995) (xy 89.969298 -415.267911) (xy 90.162178 -415.214501) (xy 90.35704 -415.168852)
			(xy 90.553573 -415.131035) (xy 90.751462 -415.101111) (xy 90.950389 -415.079129) (xy 91.150037 -415.065124)
			(xy 91.350085 -415.059118) (xy 91.550213 -415.06112) (xy 91.750101 -415.071128) (xy 91.949428 -415.089125)
			(xy 92.147876 -415.115083) (xy 92.345126 -415.14896) (xy 92.540863 -415.190702) (xy 92.734773 -415.240241)
			(xy 92.926546 -415.297499) (xy 93.115875 -415.362384) (xy 93.302455 -415.434792) (xy 93.48599 -415.514608)
			(xy 93.666184 -415.601702) (xy 93.842749 -415.695936) (xy 94.015402 -415.797159) (xy 94.183867 -415.905209)
			(xy 94.347875 -416.019912) (xy 94.507162 -416.141086) (xy 94.661473 -416.268535) (xy 94.810561 -416.402056)
			(xy 94.954188 -416.541436) (xy 95.092124 -416.68645) (xy 95.224147 -416.836867) (xy 95.350046 -416.992445)
			(xy 95.46962 -417.152937) (xy 95.582676 -417.318083) (xy 95.689035 -417.487621) (xy 95.788526 -417.661279)
			(xy 95.880989 -417.838778) (xy 95.966276 -418.019834) (xy 96.044251 -418.204158) (xy 96.114788 -418.391454)
			(xy 96.177776 -418.581422) (xy 96.233113 -418.773758) (xy 96.28071 -418.968154) (xy 96.320491 -419.164299)
			(xy 96.352393 -419.361878) (xy 96.376364 -419.560575) (xy 96.392366 -419.760073) (xy 96.400373 -419.960051)
			(xy 96.400874 -420.06012) (xy 96.400373 -420.160189) (xy 96.392366 -420.360167) (xy 96.376364 -420.559665)
			(xy 96.352393 -420.758362) (xy 96.320491 -420.955941) (xy 96.28071 -421.152086) (xy 96.233113 -421.346482)
			(xy 96.177776 -421.538818) (xy 96.114788 -421.728786) (xy 96.044251 -421.916082) (xy 95.966276 -422.100406)
			(xy 95.880989 -422.281462) (xy 95.788526 -422.458961) (xy 95.689035 -422.632619) (xy 95.582676 -422.802157)
			(xy 95.46962 -422.967303) (xy 95.350046 -423.127795) (xy 95.224147 -423.283373) (xy 95.092124 -423.43379)
			(xy 94.954188 -423.578804) (xy 94.810561 -423.718184) (xy 94.661473 -423.851705) (xy 94.507162 -423.979154)
			(xy 94.347875 -424.100328) (xy 94.183867 -424.215031) (xy 94.015402 -424.323081) (xy 93.842749 -424.424304)
			(xy 93.666184 -424.518538) (xy 93.48599 -424.605632) (xy 93.302455 -424.685448) (xy 93.115875 -424.757856)
			(xy 92.926546 -424.822741) (xy 92.734773 -424.879999) (xy 92.540863 -424.929538) (xy 92.345126 -424.97128)
			(xy 92.147876 -425.005157) (xy 91.949428 -425.031115) (xy 91.750101 -425.049112) (xy 91.550213 -425.05912)
			(xy 91.350085 -425.061122) (xy 91.150037 -425.055116) (xy 90.950389 -425.041111) (xy 90.751462 -425.019129)
			(xy 90.553573 -424.989205) (xy 90.35704 -424.951388) (xy 90.162178 -424.905739) (xy 89.969298 -424.852329)
			(xy 89.778709 -424.791245) (xy 89.590717 -424.722585) (xy 89.405622 -424.646458) (xy 89.223722 -424.562987)
			(xy 89.045306 -424.472304) (xy 88.870662 -424.374556) (xy 88.700069 -424.269899) (xy 88.533799 -424.1585)
			(xy 88.37212 -424.040538) (xy 88.215289 -423.916202) (xy 88.063559 -423.78569) (xy 87.917172 -423.649213)
			(xy 87.776363 -423.506987) (xy 87.641356 -423.359242) (xy 87.512369 -423.206214) (xy 87.389608 -423.048147)
			(xy 87.27327 -422.885296) (xy 87.16354 -422.71792) (xy 87.060595 -422.546288) (xy 86.964599 -422.370674)
			(xy 86.875706 -422.191361) (xy 86.794059 -422.008634) (xy 86.719787 -421.822787) (xy 86.653011 -421.634117)
			(xy 86.593837 -421.442927) (xy 86.54236 -421.249522) (xy 86.498662 -421.054213) (xy 86.462814 -420.857311)
			(xy 86.434872 -420.659133) (xy 86.414881 -420.459996) (xy 86.402874 -420.260218) (xy 86.39887 -420.06012)
			(xy 35.775246 -420.06012) (xy 35.755079 -420.065858) (xy 35.669659 -420.081826) (xy 35.58313 -420.089844)
			(xy 35.49623 -420.089844) (xy 35.409701 -420.081826) (xy 35.324281 -420.065858) (xy 35.240699 -420.042077)
			(xy 35.159667 -420.010685) (xy 35.081878 -419.971951) (xy 35.007994 -419.926204) (xy 34.938647 -419.873835)
			(xy 34.874427 -419.815291) (xy 34.815883 -419.751071) (xy 34.763514 -419.681724) (xy 34.717767 -419.60784)
			(xy 34.679033 -419.530051) (xy 34.647641 -419.449019) (xy 34.62386 -419.365437) (xy 34.607892 -419.280017)
			(xy 34.599874 -419.193488) (xy 31.399486 -419.193488) (xy 31.391468 -419.280017) (xy 31.3755 -419.365437)
			(xy 31.351719 -419.449019) (xy 31.320327 -419.530051) (xy 31.281593 -419.60784) (xy 31.235846 -419.681724)
			(xy 31.183477 -419.751071) (xy 31.124933 -419.815291) (xy 31.060713 -419.873835) (xy 30.991366 -419.926204)
			(xy 30.917482 -419.971951) (xy 30.839693 -420.010685) (xy 30.758661 -420.042077) (xy 30.675079 -420.065858)
			(xy 30.589659 -420.081826) (xy 30.50313 -420.089844) (xy 30.41623 -420.089844) (xy 30.329701 -420.081826)
			(xy 30.244281 -420.065858) (xy 30.160699 -420.042077) (xy 30.079667 -420.010685) (xy 30.001878 -419.971951)
			(xy 29.927994 -419.926204) (xy 29.858647 -419.873835) (xy 29.794427 -419.815291) (xy 29.735883 -419.751071)
			(xy 29.683514 -419.681724) (xy 29.637767 -419.60784) (xy 29.599033 -419.530051) (xy 29.567641 -419.449019)
			(xy 29.54386 -419.365437) (xy 29.527892 -419.280017) (xy 29.519874 -419.193488) (xy 28.353512 -419.193488)
			(xy 28.353512 -421.733488) (xy 29.519874 -421.733488) (xy 29.519874 -421.646588) (xy 29.527892 -421.560059)
			(xy 29.54386 -421.474639) (xy 29.567641 -421.391057) (xy 29.599033 -421.310025) (xy 29.637767 -421.232236)
			(xy 29.683514 -421.158352) (xy 29.735883 -421.089005) (xy 29.794427 -421.024785) (xy 29.858647 -420.966241)
			(xy 29.927994 -420.913872) (xy 30.001878 -420.868125) (xy 30.079667 -420.829391) (xy 30.160699 -420.797999)
			(xy 30.244281 -420.774218) (xy 30.329701 -420.75825) (xy 30.41623 -420.750232) (xy 30.50313 -420.750232)
			(xy 30.589659 -420.75825) (xy 30.675079 -420.774218) (xy 30.758661 -420.797999) (xy 30.839693 -420.829391)
			(xy 30.917482 -420.868125) (xy 30.991366 -420.913872) (xy 31.060713 -420.966241) (xy 31.124933 -421.024785)
			(xy 31.183477 -421.089005) (xy 31.235846 -421.158352) (xy 31.281593 -421.232236) (xy 31.320327 -421.310025)
			(xy 31.351719 -421.391057) (xy 31.3755 -421.474639) (xy 31.391468 -421.560059) (xy 31.399486 -421.646588)
			(xy 31.399988 -421.690038) (xy 31.399486 -421.733488) (xy 34.599874 -421.733488) (xy 34.599874 -421.646588)
			(xy 34.607892 -421.560059) (xy 34.62386 -421.474639) (xy 34.647641 -421.391057) (xy 34.679033 -421.310025)
			(xy 34.717767 -421.232236) (xy 34.763514 -421.158352) (xy 34.815883 -421.089005) (xy 34.874427 -421.024785)
			(xy 34.938647 -420.966241) (xy 35.007994 -420.913872) (xy 35.081878 -420.868125) (xy 35.159667 -420.829391)
			(xy 35.240699 -420.797999) (xy 35.324281 -420.774218) (xy 35.409701 -420.75825) (xy 35.49623 -420.750232)
			(xy 35.58313 -420.750232) (xy 35.669659 -420.75825) (xy 35.755079 -420.774218) (xy 35.838661 -420.797999)
			(xy 35.919693 -420.829391) (xy 35.997482 -420.868125) (xy 36.071366 -420.913872) (xy 36.107296 -420.941005)
			(xy 39.875096 -420.941005) (xy 39.878983 -420.886653) (xy 39.890565 -420.833408) (xy 39.909607 -420.782353)
			(xy 39.935721 -420.734528) (xy 39.968376 -420.690906) (xy 40.006907 -420.652376) (xy 40.050528 -420.619721)
			(xy 40.098354 -420.593607) (xy 40.149408 -420.574565) (xy 40.202654 -420.562983) (xy 40.257005 -420.559096)
			(xy 40.311356 -420.562984) (xy 40.364601 -420.574568) (xy 40.415656 -420.593611) (xy 40.46348 -420.619727)
			(xy 40.485568 -420.635684) (xy 40.50458 -420.64928) (xy 40.546463 -420.670012) (xy 40.591431 -420.682738)
			(xy 40.637968 -420.687028) (xy 40.684505 -420.682738) (xy 40.729473 -420.670012) (xy 40.771356 -420.64928)
			(xy 40.790368 -420.635684) (xy 40.812464 -420.619732) (xy 40.860292 -420.593607) (xy 40.91135 -420.574556)
			(xy 40.964601 -420.562965) (xy 41.018959 -420.559071) (xy 41.073317 -420.562953) (xy 41.12657 -420.574532)
			(xy 41.177633 -420.593573) (xy 41.225466 -420.619687) (xy 41.269095 -420.652344) (xy 41.307632 -420.690877)
			(xy 41.340293 -420.734503) (xy 41.366412 -420.782334) (xy 41.385457 -420.833395) (xy 41.397042 -420.886646)
			(xy 41.400929 -420.941005) (xy 41.397041 -420.995363) (xy 41.385455 -421.048615) (xy 41.366408 -421.099675)
			(xy 41.340288 -421.147505) (xy 41.307626 -421.19113) (xy 41.269088 -421.229663) (xy 41.225458 -421.262318)
			(xy 41.177624 -421.288431) (xy 41.126561 -421.30747) (xy 41.073308 -421.319048) (xy 41.018949 -421.322929)
			(xy 40.964591 -421.319034) (xy 40.911341 -421.307442) (xy 40.860283 -421.288389) (xy 40.812456 -421.262263)
			(xy 40.790368 -421.2463) (xy 40.771356 -421.232704) (xy 40.729473 -421.211972) (xy 40.684505 -421.199246)
			(xy 40.637968 -421.194956) (xy 40.591431 -421.199246) (xy 40.546463 -421.211972) (xy 40.50458 -421.232704)
			(xy 40.485568 -421.2463) (xy 40.463488 -421.262268) (xy 40.415664 -421.288385) (xy 40.36461 -421.307429)
			(xy 40.311366 -421.319014) (xy 40.257015 -421.322904) (xy 40.202663 -421.319018) (xy 40.149418 -421.307438)
			(xy 40.098362 -421.288397) (xy 40.050537 -421.262284) (xy 40.006914 -421.22963) (xy 39.968382 -421.191101)
			(xy 39.935727 -421.14748) (xy 39.909611 -421.099655) (xy 39.890568 -421.048601) (xy 39.878984 -420.995356)
			(xy 39.875096 -420.941005) (xy 36.107296 -420.941005) (xy 36.140713 -420.966241) (xy 36.204933 -421.024785)
			(xy 36.263477 -421.089005) (xy 36.315846 -421.158352) (xy 36.361593 -421.232236) (xy 36.400327 -421.310025)
			(xy 36.431719 -421.391057) (xy 36.4555 -421.474639) (xy 36.471468 -421.560059) (xy 36.476705 -421.616581)
			(xy 65.293435 -421.616581) (xy 65.297325 -421.562236) (xy 65.308909 -421.508997) (xy 65.327952 -421.45795)
			(xy 65.354066 -421.410131) (xy 65.38672 -421.366516) (xy 65.425248 -421.327992) (xy 65.468866 -421.295344)
			(xy 65.516687 -421.269235) (xy 65.567737 -421.250198) (xy 65.620977 -421.238619) (xy 65.675322 -421.234735)
			(xy 65.729667 -421.238625) (xy 65.782906 -421.25021) (xy 65.833953 -421.269253) (xy 65.881771 -421.295368)
			(xy 65.903856 -421.311324) (xy 65.922868 -421.32492) (xy 65.964751 -421.345652) (xy 66.009719 -421.358378)
			(xy 66.056256 -421.362668) (xy 66.102793 -421.358378) (xy 66.147761 -421.345652) (xy 66.189644 -421.32492)
			(xy 66.208656 -421.311324) (xy 66.230715 -421.295317) (xy 66.278546 -421.269185) (xy 66.329608 -421.250127)
			(xy 66.382864 -421.23853) (xy 66.437228 -421.234631) (xy 66.491593 -421.23851) (xy 66.544853 -421.250086)
			(xy 66.595923 -421.269125) (xy 66.643763 -421.295239) (xy 66.6874 -421.327896) (xy 66.725944 -421.366431)
			(xy 66.758612 -421.41006) (xy 66.784737 -421.457894) (xy 66.803788 -421.508959) (xy 66.815377 -421.562216)
			(xy 66.819269 -421.616581) (xy 68.285028 -421.616581) (xy 68.288918 -421.562234) (xy 68.300503 -421.508994)
			(xy 68.319546 -421.457945) (xy 68.345661 -421.410125) (xy 68.378316 -421.366509) (xy 68.416846 -421.327985)
			(xy 68.460466 -421.295335) (xy 68.508289 -421.269226) (xy 68.55934 -421.250189) (xy 68.612582 -421.238611)
			(xy 68.666929 -421.234728) (xy 68.721276 -421.238619) (xy 68.774515 -421.250205) (xy 68.825564 -421.26925)
			(xy 68.873383 -421.295367) (xy 68.895468 -421.311324) (xy 68.91448 -421.32492) (xy 68.956363 -421.345652)
			(xy 69.001331 -421.358378) (xy 69.047868 -421.362668) (xy 69.094405 -421.358378) (xy 69.139373 -421.345652)
			(xy 69.181256 -421.32492) (xy 69.200268 -421.311324) (xy 69.222327 -421.295318) (xy 69.270157 -421.269188)
			(xy 69.321218 -421.250132) (xy 69.374472 -421.238536) (xy 69.428835 -421.234639) (xy 69.483198 -421.238518)
			(xy 69.536456 -421.250095) (xy 69.587524 -421.269134) (xy 69.635363 -421.295247) (xy 69.678998 -421.327904)
			(xy 69.717541 -421.366438) (xy 69.750207 -421.410066) (xy 69.776331 -421.457899) (xy 69.795381 -421.508963)
			(xy 69.80697 -421.562218) (xy 69.810861 -421.616581) (xy 69.806976 -421.670944) (xy 69.795392 -421.724201)
			(xy 69.776347 -421.775266) (xy 69.750228 -421.823102) (xy 69.717566 -421.866733) (xy 69.679027 -421.905271)
			(xy 69.635395 -421.937932) (xy 69.587559 -421.96405) (xy 69.536493 -421.983094) (xy 69.483236 -421.994677)
			(xy 69.428873 -421.998561) (xy 69.37451 -421.994669) (xy 69.321255 -421.983079) (xy 69.270191 -421.964028)
			(xy 69.222359 -421.937903) (xy 69.200268 -421.92194) (xy 69.181256 -421.908344) (xy 69.139373 -421.887612)
			(xy 69.094405 -421.874886) (xy 69.047868 -421.870596) (xy 69.001331 -421.874886) (xy 68.956363 -421.887612)
			(xy 68.91448 -421.908344) (xy 68.895468 -421.92194) (xy 68.873351 -421.937854) (xy 68.825529 -421.963966)
			(xy 68.774478 -421.983005) (xy 68.721238 -421.994586) (xy 68.666891 -421.998472) (xy 68.612544 -421.994583)
			(xy 68.559304 -421.983) (xy 68.508254 -421.963958) (xy 68.460434 -421.937844) (xy 68.416817 -421.90519)
			(xy 68.378291 -421.866662) (xy 68.345641 -421.823042) (xy 68.31953 -421.77522) (xy 68.300492 -421.724169)
			(xy 68.288913 -421.670928) (xy 68.285028 -421.616581) (xy 66.819269 -421.616581) (xy 66.815383 -421.670946)
			(xy 66.803799 -421.724204) (xy 66.784753 -421.775271) (xy 66.758632 -421.823108) (xy 66.725969 -421.86674)
			(xy 66.687429 -421.905279) (xy 66.643796 -421.93794) (xy 66.595958 -421.964059) (xy 66.54489 -421.983103)
			(xy 66.491631 -421.994685) (xy 66.437266 -421.998569) (xy 66.382902 -421.994675) (xy 66.329645 -421.983084)
			(xy 66.278581 -421.964031) (xy 66.230748 -421.937904) (xy 66.208656 -421.92194) (xy 66.189644 -421.908344)
			(xy 66.147761 -421.887612) (xy 66.102793 -421.874886) (xy 66.056256 -421.870596) (xy 66.009719 -421.874886)
			(xy 65.964751 -421.887612) (xy 65.922868 -421.908344) (xy 65.903856 -421.92194) (xy 65.881739 -421.937853)
			(xy 65.833918 -421.963963) (xy 65.782869 -421.983001) (xy 65.729629 -421.99458) (xy 65.675284 -421.998465)
			(xy 65.620939 -421.994575) (xy 65.5677 -421.982992) (xy 65.516652 -421.963949) (xy 65.468834 -421.937836)
			(xy 65.425219 -421.905182) (xy 65.386694 -421.866655) (xy 65.354045 -421.823036) (xy 65.327936 -421.775216)
			(xy 65.308898 -421.724166) (xy 65.29732 -421.670926) (xy 65.293435 -421.616581) (xy 36.476705 -421.616581)
			(xy 36.479486 -421.646588) (xy 36.479988 -421.690038) (xy 36.479486 -421.733488) (xy 36.471468 -421.820017)
			(xy 36.4555 -421.905437) (xy 36.431719 -421.989019) (xy 36.400327 -422.070051) (xy 36.361593 -422.14784)
			(xy 36.315846 -422.221724) (xy 36.263477 -422.291071) (xy 36.204933 -422.355291) (xy 36.140713 -422.413835)
			(xy 36.071366 -422.466204) (xy 35.997482 -422.511951) (xy 35.919693 -422.550685) (xy 35.838661 -422.582077)
			(xy 35.755079 -422.605858) (xy 35.669659 -422.621826) (xy 35.58313 -422.629844) (xy 35.49623 -422.629844)
			(xy 35.409701 -422.621826) (xy 35.324281 -422.605858) (xy 35.240699 -422.582077) (xy 35.159667 -422.550685)
			(xy 35.081878 -422.511951) (xy 35.007994 -422.466204) (xy 34.938647 -422.413835) (xy 34.874427 -422.355291)
			(xy 34.815883 -422.291071) (xy 34.763514 -422.221724) (xy 34.717767 -422.14784) (xy 34.679033 -422.070051)
			(xy 34.647641 -421.989019) (xy 34.62386 -421.905437) (xy 34.607892 -421.820017) (xy 34.599874 -421.733488)
			(xy 31.399486 -421.733488) (xy 31.391468 -421.820017) (xy 31.3755 -421.905437) (xy 31.351719 -421.989019)
			(xy 31.320327 -422.070051) (xy 31.281593 -422.14784) (xy 31.235846 -422.221724) (xy 31.183477 -422.291071)
			(xy 31.124933 -422.355291) (xy 31.060713 -422.413835) (xy 30.991366 -422.466204) (xy 30.917482 -422.511951)
			(xy 30.839693 -422.550685) (xy 30.758661 -422.582077) (xy 30.675079 -422.605858) (xy 30.589659 -422.621826)
			(xy 30.50313 -422.629844) (xy 30.41623 -422.629844) (xy 30.329701 -422.621826) (xy 30.244281 -422.605858)
			(xy 30.160699 -422.582077) (xy 30.079667 -422.550685) (xy 30.001878 -422.511951) (xy 29.927994 -422.466204)
			(xy 29.858647 -422.413835) (xy 29.794427 -422.355291) (xy 29.735883 -422.291071) (xy 29.683514 -422.221724)
			(xy 29.637767 -422.14784) (xy 29.599033 -422.070051) (xy 29.567641 -421.989019) (xy 29.54386 -421.905437)
			(xy 29.527892 -421.820017) (xy 29.519874 -421.733488) (xy 28.353512 -421.733488) (xy 28.353512 -424.273488)
			(xy 29.519874 -424.273488) (xy 29.519874 -424.186588) (xy 29.527892 -424.100059) (xy 29.54386 -424.014639)
			(xy 29.567641 -423.931057) (xy 29.599033 -423.850025) (xy 29.637767 -423.772236) (xy 29.683514 -423.698352)
			(xy 29.735883 -423.629005) (xy 29.794427 -423.564785) (xy 29.858647 -423.506241) (xy 29.927994 -423.453872)
			(xy 30.001878 -423.408125) (xy 30.079667 -423.369391) (xy 30.160699 -423.337999) (xy 30.244281 -423.314218)
			(xy 30.329701 -423.29825) (xy 30.41623 -423.290232) (xy 30.50313 -423.290232) (xy 30.589659 -423.29825)
			(xy 30.675079 -423.314218) (xy 30.758661 -423.337999) (xy 30.839693 -423.369391) (xy 30.917482 -423.408125)
			(xy 30.991366 -423.453872) (xy 31.060713 -423.506241) (xy 31.124933 -423.564785) (xy 31.183477 -423.629005)
			(xy 31.235846 -423.698352) (xy 31.281593 -423.772236) (xy 31.320327 -423.850025) (xy 31.351719 -423.931057)
			(xy 31.3755 -424.014639) (xy 31.391468 -424.100059) (xy 31.399486 -424.186588) (xy 31.399988 -424.230038)
			(xy 31.399486 -424.273488) (xy 34.599874 -424.273488) (xy 34.599874 -424.186588) (xy 34.607892 -424.100059)
			(xy 34.62386 -424.014639) (xy 34.647641 -423.931057) (xy 34.679033 -423.850025) (xy 34.717767 -423.772236)
			(xy 34.763514 -423.698352) (xy 34.815883 -423.629005) (xy 34.874427 -423.564785) (xy 34.938647 -423.506241)
			(xy 35.007994 -423.453872) (xy 35.081878 -423.408125) (xy 35.159667 -423.369391) (xy 35.240699 -423.337999)
			(xy 35.324281 -423.314218) (xy 35.409701 -423.29825) (xy 35.49623 -423.290232) (xy 35.58313 -423.290232)
			(xy 35.669659 -423.29825) (xy 35.755079 -423.314218) (xy 35.838661 -423.337999) (xy 35.919693 -423.369391)
			(xy 35.997482 -423.408125) (xy 36.071366 -423.453872) (xy 36.140713 -423.506241) (xy 36.204933 -423.564785)
			(xy 36.247792 -423.611799) (xy 39.875104 -423.611799) (xy 39.878992 -423.557448) (xy 39.890575 -423.504205)
			(xy 39.909617 -423.453151) (xy 39.935731 -423.405328) (xy 39.968386 -423.361707) (xy 40.006916 -423.323178)
			(xy 40.050538 -423.290525) (xy 40.098362 -423.264412) (xy 40.149416 -423.245371) (xy 40.202661 -423.23379)
			(xy 40.257011 -423.229904) (xy 40.311361 -423.233793) (xy 40.364605 -423.245377) (xy 40.415658 -423.264421)
			(xy 40.463481 -423.290537) (xy 40.485568 -423.306494) (xy 40.50458 -423.32009) (xy 40.546463 -423.340822)
			(xy 40.591431 -423.353548) (xy 40.637968 -423.357838) (xy 40.684505 -423.353548) (xy 40.729473 -423.340822)
			(xy 40.771356 -423.32009) (xy 40.790368 -423.306494) (xy 40.812455 -423.290529) (xy 40.860283 -423.264403)
			(xy 40.911342 -423.24535) (xy 40.964594 -423.233758) (xy 41.018953 -423.229863) (xy 41.073313 -423.233744)
			(xy 41.126567 -423.245323) (xy 41.177631 -423.264363) (xy 41.225465 -423.290477) (xy 41.269096 -423.323134)
			(xy 41.307634 -423.361667) (xy 41.340296 -423.405294) (xy 41.366417 -423.453125) (xy 41.385463 -423.504187)
			(xy 41.397049 -423.557439) (xy 41.400937 -423.611799) (xy 41.397049 -423.666158) (xy 41.385464 -423.719411)
			(xy 41.370296 -423.760077) (xy 65.29344 -423.760077) (xy 65.29733 -423.705733) (xy 65.308915 -423.652495)
			(xy 65.327958 -423.601448) (xy 65.354072 -423.553631) (xy 65.386725 -423.510017) (xy 65.425254 -423.471494)
			(xy 65.468872 -423.438846) (xy 65.516692 -423.412738) (xy 65.567742 -423.393701) (xy 65.620981 -423.382123)
			(xy 65.675326 -423.37824) (xy 65.72967 -423.382131) (xy 65.782908 -423.393716) (xy 65.833954 -423.412759)
			(xy 65.881772 -423.438874) (xy 65.903856 -423.45483) (xy 65.922868 -423.468426) (xy 65.964751 -423.489158)
			(xy 66.009719 -423.501884) (xy 66.056256 -423.506174) (xy 66.102793 -423.501884) (xy 66.147761 -423.489158)
			(xy 66.189644 -423.468426) (xy 66.208656 -423.45483) (xy 66.23071 -423.438815) (xy 66.27854 -423.412682)
			(xy 66.329604 -423.393623) (xy 66.38286 -423.382026) (xy 66.437224 -423.378127) (xy 66.49159 -423.382005)
			(xy 66.544851 -423.393581) (xy 66.595922 -423.412619) (xy 66.643763 -423.438733) (xy 66.6874 -423.47139)
			(xy 66.725945 -423.509925) (xy 66.758614 -423.553554) (xy 66.78474 -423.601389) (xy 66.803792 -423.652455)
			(xy 66.815381 -423.705712) (xy 66.819273 -423.760077) (xy 68.285033 -423.760077) (xy 68.288923 -423.705731)
			(xy 68.300508 -423.652492) (xy 68.319552 -423.601444) (xy 68.345667 -423.553625) (xy 68.378322 -423.51001)
			(xy 68.416852 -423.471486) (xy 68.460472 -423.438837) (xy 68.508294 -423.412729) (xy 68.559345 -423.393693)
			(xy 68.612586 -423.382115) (xy 68.666933 -423.378233) (xy 68.721279 -423.382125) (xy 68.774517 -423.393711)
			(xy 68.825565 -423.412756) (xy 68.873383 -423.438873) (xy 68.895468 -423.45483) (xy 68.91448 -423.468426)
			(xy 68.956363 -423.489158) (xy 69.001331 -423.501884) (xy 69.047868 -423.506174) (xy 69.094405 -423.501884)
			(xy 69.139373 -423.489158) (xy 69.181256 -423.468426) (xy 69.200268 -423.45483) (xy 69.222321 -423.438816)
			(xy 69.270151 -423.412685) (xy 69.321213 -423.393628) (xy 69.374468 -423.382032) (xy 69.428831 -423.378134)
			(xy 69.483195 -423.382013) (xy 69.536454 -423.393589) (xy 69.587523 -423.412628) (xy 69.635363 -423.438741)
			(xy 69.678998 -423.471398) (xy 69.717542 -423.509932) (xy 69.750209 -423.55356) (xy 69.776334 -423.601393)
			(xy 69.795385 -423.652458) (xy 69.806974 -423.705714) (xy 69.810866 -423.760077) (xy 69.806981 -423.814441)
			(xy 69.795398 -423.867698) (xy 69.776353 -423.918765) (xy 69.750234 -423.966601) (xy 69.717572 -424.010233)
			(xy 69.679033 -424.048772) (xy 69.635401 -424.081434) (xy 69.587565 -424.107553) (xy 69.536498 -424.126598)
			(xy 69.48324 -424.138181) (xy 69.428877 -424.142066) (xy 69.374513 -424.138174) (xy 69.321257 -424.126585)
			(xy 69.270193 -424.107534) (xy 69.22236 -424.081409) (xy 69.200268 -424.065446) (xy 69.181256 -424.05185)
			(xy 69.139373 -424.031118) (xy 69.094405 -424.018392) (xy 69.047868 -424.014102) (xy 69.001331 -424.018392)
			(xy 68.956363 -424.031118) (xy 68.91448 -424.05185) (xy 68.895468 -424.065446) (xy 68.873345 -424.081352)
			(xy 68.825524 -424.107463) (xy 68.774474 -424.126502) (xy 68.721233 -424.138082) (xy 68.666887 -424.141967)
			(xy 68.612541 -424.138078) (xy 68.559302 -424.126494) (xy 68.508253 -424.107452) (xy 68.460433 -424.081338)
			(xy 68.416817 -424.048684) (xy 68.378292 -424.010156) (xy 68.345643 -423.966537) (xy 68.319533 -423.918715)
			(xy 68.300495 -423.867664) (xy 68.288917 -423.814424) (xy 68.285033 -423.760077) (xy 66.819273 -423.760077)
			(xy 66.815388 -423.814443) (xy 66.803804 -423.867702) (xy 66.784759 -423.91877) (xy 66.758638 -423.966607)
			(xy 66.725975 -424.01024) (xy 66.687435 -424.04878) (xy 66.643801 -424.081442) (xy 66.595963 -424.107562)
			(xy 66.544895 -424.126607) (xy 66.491635 -424.138189) (xy 66.43727 -424.142073) (xy 66.382905 -424.13818)
			(xy 66.329647 -424.126589) (xy 66.278582 -424.107537) (xy 66.230748 -424.08141) (xy 66.208656 -424.065446)
			(xy 66.189644 -424.05185) (xy 66.147761 -424.031118) (xy 66.102793 -424.018392) (xy 66.056256 -424.014102)
			(xy 66.009719 -424.018392) (xy 65.964751 -424.031118) (xy 65.922868 -424.05185) (xy 65.903856 -424.065446)
			(xy 65.881733 -424.081351) (xy 65.833913 -424.10746) (xy 65.782864 -424.126497) (xy 65.729625 -424.138076)
			(xy 65.67528 -424.14196) (xy 65.620936 -424.13807) (xy 65.567698 -424.126486) (xy 65.516651 -424.107443)
			(xy 65.468833 -424.08133) (xy 65.425219 -424.048676) (xy 65.386696 -424.010149) (xy 65.354047 -423.966531)
			(xy 65.327939 -423.91871) (xy 65.308902 -423.867661) (xy 65.297324 -423.814422) (xy 65.29344 -423.760077)
			(xy 41.370296 -423.760077) (xy 41.366418 -423.770473) (xy 41.340298 -423.818304) (xy 41.307636 -423.861931)
			(xy 41.269098 -423.900465) (xy 41.225467 -423.933121) (xy 41.177633 -423.959236) (xy 41.126569 -423.978276)
			(xy 41.073315 -423.989856) (xy 41.018955 -423.993737) (xy 40.964596 -423.989843) (xy 40.911345 -423.978251)
			(xy 40.860285 -423.959198) (xy 40.812457 -423.933073) (xy 40.790368 -423.91711) (xy 40.771356 -423.903514)
			(xy 40.729473 -423.882782) (xy 40.684505 -423.870056) (xy 40.637968 -423.865766) (xy 40.591431 -423.870056)
			(xy 40.546463 -423.882782) (xy 40.50458 -423.903514) (xy 40.485568 -423.91711) (xy 40.463479 -423.933065)
			(xy 40.415656 -423.95918) (xy 40.364602 -423.978223) (xy 40.311359 -423.989807) (xy 40.257009 -423.993696)
			(xy 40.202658 -423.98981) (xy 40.149414 -423.978228) (xy 40.09836 -423.959187) (xy 40.050536 -423.933074)
			(xy 40.006915 -423.90042) (xy 39.968385 -423.861891) (xy 39.93573 -423.81827) (xy 39.909616 -423.770447)
			(xy 39.890574 -423.719393) (xy 39.878991 -423.666149) (xy 39.875104 -423.611799) (xy 36.247792 -423.611799)
			(xy 36.263477 -423.629005) (xy 36.315846 -423.698352) (xy 36.361593 -423.772236) (xy 36.400327 -423.850025)
			(xy 36.431719 -423.931057) (xy 36.4555 -424.014639) (xy 36.471468 -424.100059) (xy 36.479486 -424.186588)
			(xy 36.479988 -424.230038) (xy 36.479486 -424.273488) (xy 36.471468 -424.360017) (xy 36.4555 -424.445437)
			(xy 36.431719 -424.529019) (xy 36.400327 -424.610051) (xy 36.361593 -424.68784) (xy 36.315846 -424.761724)
			(xy 36.263477 -424.831071) (xy 36.204933 -424.895291) (xy 36.140713 -424.953835) (xy 36.071366 -425.006204)
			(xy 35.997482 -425.051951) (xy 35.919693 -425.090685) (xy 35.838661 -425.122077) (xy 35.755079 -425.145858)
			(xy 35.669659 -425.161826) (xy 35.58313 -425.169844) (xy 35.49623 -425.169844) (xy 35.409701 -425.161826)
			(xy 35.324281 -425.145858) (xy 35.240699 -425.122077) (xy 35.159667 -425.090685) (xy 35.081878 -425.051951)
			(xy 35.007994 -425.006204) (xy 34.938647 -424.953835) (xy 34.874427 -424.895291) (xy 34.815883 -424.831071)
			(xy 34.763514 -424.761724) (xy 34.717767 -424.68784) (xy 34.679033 -424.610051) (xy 34.647641 -424.529019)
			(xy 34.62386 -424.445437) (xy 34.607892 -424.360017) (xy 34.599874 -424.273488) (xy 31.399486 -424.273488)
			(xy 31.391468 -424.360017) (xy 31.3755 -424.445437) (xy 31.351719 -424.529019) (xy 31.320327 -424.610051)
			(xy 31.281593 -424.68784) (xy 31.235846 -424.761724) (xy 31.183477 -424.831071) (xy 31.124933 -424.895291)
			(xy 31.060713 -424.953835) (xy 30.991366 -425.006204) (xy 30.917482 -425.051951) (xy 30.839693 -425.090685)
			(xy 30.758661 -425.122077) (xy 30.675079 -425.145858) (xy 30.589659 -425.161826) (xy 30.50313 -425.169844)
			(xy 30.41623 -425.169844) (xy 30.329701 -425.161826) (xy 30.244281 -425.145858) (xy 30.160699 -425.122077)
			(xy 30.079667 -425.090685) (xy 30.001878 -425.051951) (xy 29.927994 -425.006204) (xy 29.858647 -424.953835)
			(xy 29.794427 -424.895291) (xy 29.735883 -424.831071) (xy 29.683514 -424.761724) (xy 29.637767 -424.68784)
			(xy 29.599033 -424.610051) (xy 29.567641 -424.529019) (xy 29.54386 -424.445437) (xy 29.527892 -424.360017)
			(xy 29.519874 -424.273488) (xy 28.353512 -424.273488) (xy 28.353512 -426.813488) (xy 29.519874 -426.813488)
			(xy 29.519874 -426.726588) (xy 29.527892 -426.640059) (xy 29.54386 -426.554639) (xy 29.567641 -426.471057)
			(xy 29.599033 -426.390025) (xy 29.637767 -426.312236) (xy 29.683514 -426.238352) (xy 29.735883 -426.169005)
			(xy 29.794427 -426.104785) (xy 29.858647 -426.046241) (xy 29.927994 -425.993872) (xy 30.001878 -425.948125)
			(xy 30.079667 -425.909391) (xy 30.160699 -425.877999) (xy 30.244281 -425.854218) (xy 30.329701 -425.83825)
			(xy 30.41623 -425.830232) (xy 30.50313 -425.830232) (xy 30.589659 -425.83825) (xy 30.675079 -425.854218)
			(xy 30.758661 -425.877999) (xy 30.839693 -425.909391) (xy 30.917482 -425.948125) (xy 30.991366 -425.993872)
			(xy 31.060713 -426.046241) (xy 31.124933 -426.104785) (xy 31.183477 -426.169005) (xy 31.235846 -426.238352)
			(xy 31.281593 -426.312236) (xy 31.320327 -426.390025) (xy 31.351719 -426.471057) (xy 31.3755 -426.554639)
			(xy 31.391468 -426.640059) (xy 31.399486 -426.726588) (xy 31.399988 -426.770038) (xy 31.399486 -426.813488)
			(xy 34.599874 -426.813488) (xy 34.599874 -426.726588) (xy 34.607892 -426.640059) (xy 34.62386 -426.554639)
			(xy 34.647641 -426.471057) (xy 34.679033 -426.390025) (xy 34.717767 -426.312236) (xy 34.763514 -426.238352)
			(xy 34.815883 -426.169005) (xy 34.874427 -426.104785) (xy 34.938647 -426.046241) (xy 35.007994 -425.993872)
			(xy 35.081878 -425.948125) (xy 35.159667 -425.909391) (xy 35.240699 -425.877999) (xy 35.324281 -425.854218)
			(xy 35.409701 -425.83825) (xy 35.49623 -425.830232) (xy 35.58313 -425.830232) (xy 35.669659 -425.83825)
			(xy 35.755079 -425.854218) (xy 35.756376 -425.854587) (xy 63.554518 -425.854587) (xy 63.558407 -425.800238)
			(xy 63.569991 -425.746997) (xy 63.589035 -425.695945) (xy 63.61515 -425.648124) (xy 63.647805 -425.604506)
			(xy 63.686335 -425.56598) (xy 63.729957 -425.533329) (xy 63.77778 -425.507219) (xy 63.828834 -425.48818)
			(xy 63.882076 -425.476601) (xy 63.936425 -425.472718) (xy 63.990774 -425.476609) (xy 64.044015 -425.488195)
			(xy 64.095066 -425.50724) (xy 64.142886 -425.533356) (xy 64.164972 -425.549314) (xy 64.183984 -425.56291)
			(xy 64.225867 -425.583642) (xy 64.270835 -425.596368) (xy 64.317372 -425.600658) (xy 64.363909 -425.596368)
			(xy 64.408877 -425.583642) (xy 64.45076 -425.56291) (xy 64.469772 -425.549314) (xy 64.49184 -425.533322)
			(xy 64.539669 -425.507194) (xy 64.590729 -425.488139) (xy 64.643982 -425.476546) (xy 64.698343 -425.472649)
			(xy 64.752705 -425.476529) (xy 64.805961 -425.488107) (xy 64.857027 -425.507146) (xy 64.904864 -425.53326)
			(xy 64.948497 -425.565916) (xy 64.987038 -425.60445) (xy 65.019702 -425.648077) (xy 65.045824 -425.695909)
			(xy 65.064873 -425.746972) (xy 65.076461 -425.800226) (xy 65.080351 -425.854587) (xy 66.358909 -425.854587)
			(xy 66.362799 -425.800236) (xy 66.374383 -425.746993) (xy 66.393428 -425.69594) (xy 66.419544 -425.648117)
			(xy 66.452201 -425.604498) (xy 66.490733 -425.565971) (xy 66.534356 -425.533319) (xy 66.582182 -425.507209)
			(xy 66.633237 -425.48817) (xy 66.686482 -425.476592) (xy 66.740833 -425.472709) (xy 66.795183 -425.476602)
			(xy 66.848426 -425.488189) (xy 66.899478 -425.507236) (xy 66.9473 -425.533355) (xy 66.969386 -425.549314)
			(xy 66.988398 -425.56291) (xy 67.030281 -425.583642) (xy 67.075249 -425.596368) (xy 67.121786 -425.600658)
			(xy 67.168323 -425.596368) (xy 67.213291 -425.583642) (xy 67.255174 -425.56291) (xy 67.274186 -425.549314)
			(xy 67.296254 -425.533323) (xy 67.344082 -425.507197) (xy 67.395141 -425.488145) (xy 67.448392 -425.476553)
			(xy 67.502751 -425.472657) (xy 67.557111 -425.476539) (xy 67.610365 -425.488117) (xy 67.661429 -425.507156)
			(xy 67.709263 -425.53327) (xy 67.752894 -425.565926) (xy 67.791434 -425.604458) (xy 67.824096 -425.648084)
			(xy 67.850218 -425.695914) (xy 67.869266 -425.746975) (xy 67.880853 -425.800228) (xy 67.884743 -425.854587)
			(xy 67.880856 -425.908946) (xy 67.869273 -425.962199) (xy 67.850229 -426.013262) (xy 67.824111 -426.061094)
			(xy 67.791451 -426.104722) (xy 67.752914 -426.143257) (xy 67.709286 -426.175916) (xy 67.661453 -426.202033)
			(xy 67.61039 -426.221076) (xy 67.557137 -426.232658) (xy 67.502777 -426.236543) (xy 67.448418 -426.232651)
			(xy 67.395166 -426.221063) (xy 67.344106 -426.202014) (xy 67.296276 -426.175891) (xy 67.274186 -426.15993)
			(xy 67.255174 -426.146334) (xy 67.213291 -426.125602) (xy 67.168323 -426.112876) (xy 67.121786 -426.108586)
			(xy 67.075249 -426.112876) (xy 67.030281 -426.125602) (xy 66.988398 -426.146334) (xy 66.969386 -426.15993)
			(xy 66.947278 -426.175859) (xy 66.899454 -426.201975) (xy 66.848401 -426.221018) (xy 66.795157 -426.232602)
			(xy 66.740807 -426.236491) (xy 66.686456 -426.232604) (xy 66.633212 -426.221022) (xy 66.582158 -426.20198)
			(xy 66.534334 -426.175867) (xy 66.490713 -426.143212) (xy 66.452184 -426.104682) (xy 66.41953 -426.061061)
			(xy 66.393417 -426.013236) (xy 66.374376 -425.962182) (xy 66.362795 -425.908937) (xy 66.358909 -425.854587)
			(xy 65.080351 -425.854587) (xy 65.076465 -425.908948) (xy 65.064881 -425.962203) (xy 65.045835 -426.013267)
			(xy 65.019716 -426.061101) (xy 64.987055 -426.10473) (xy 64.948517 -426.143266) (xy 64.904886 -426.175926)
			(xy 64.857051 -426.202043) (xy 64.805986 -426.221086) (xy 64.752731 -426.232667) (xy 64.698369 -426.236551)
			(xy 64.644008 -426.232658) (xy 64.590755 -426.221068) (xy 64.539693 -426.202017) (xy 64.491862 -426.175892)
			(xy 64.469772 -426.15993) (xy 64.45076 -426.146334) (xy 64.408877 -426.125602) (xy 64.363909 -426.112876)
			(xy 64.317372 -426.108586) (xy 64.270835 -426.112876) (xy 64.225867 -426.125602) (xy 64.183984 -426.146334)
			(xy 64.164972 -426.15993) (xy 64.142864 -426.175858) (xy 64.095042 -426.201971) (xy 64.04399 -426.221013)
			(xy 63.990748 -426.232595) (xy 63.936399 -426.236482) (xy 63.88205 -426.232595) (xy 63.828808 -426.221012)
			(xy 63.777756 -426.20197) (xy 63.729934 -426.175857) (xy 63.686315 -426.143203) (xy 63.647788 -426.104674)
			(xy 63.615136 -426.061054) (xy 63.589024 -426.013231) (xy 63.569984 -425.962178) (xy 63.558403 -425.908936)
			(xy 63.554518 -425.854587) (xy 35.756376 -425.854587) (xy 35.838661 -425.877999) (xy 35.919693 -425.909391)
			(xy 35.997482 -425.948125) (xy 36.071366 -425.993872) (xy 36.140713 -426.046241) (xy 36.204933 -426.104785)
			(xy 36.263477 -426.169005) (xy 36.315846 -426.238352) (xy 36.341706 -426.280117) (xy 39.87508 -426.280117)
			(xy 39.878965 -426.225763) (xy 39.890546 -426.172515) (xy 39.909588 -426.121458) (xy 39.935702 -426.07363)
			(xy 39.968356 -426.030005) (xy 40.006887 -425.991472) (xy 40.05051 -425.958814) (xy 40.098336 -425.932698)
			(xy 40.149392 -425.913653) (xy 40.202639 -425.902069) (xy 40.256993 -425.89818) (xy 40.311347 -425.902067)
			(xy 40.364594 -425.913649) (xy 40.415651 -425.932692) (xy 40.463479 -425.958807) (xy 40.485568 -425.974764)
			(xy 40.50458 -425.98836) (xy 40.546463 -426.009092) (xy 40.591431 -426.021818) (xy 40.637968 -426.026108)
			(xy 40.684505 -426.021818) (xy 40.729473 -426.009092) (xy 40.771356 -425.98836) (xy 40.790368 -425.974764)
			(xy 40.812483 -425.958839) (xy 40.860309 -425.932717) (xy 40.911366 -425.913668) (xy 40.964615 -425.902079)
			(xy 41.018971 -425.898187) (xy 41.073327 -425.90207) (xy 41.126577 -425.913651) (xy 41.177637 -425.932692)
			(xy 41.225467 -425.958807) (xy 41.269094 -425.991464) (xy 41.307628 -426.029997) (xy 41.340286 -426.073622)
			(xy 41.366402 -426.121451) (xy 41.385445 -426.172511) (xy 41.397028 -426.225761) (xy 41.400913 -426.280117)
			(xy 41.397023 -426.334473) (xy 41.385436 -426.387722) (xy 41.366388 -426.438779) (xy 41.340268 -426.486606)
			(xy 41.307606 -426.530229) (xy 41.269068 -426.568758) (xy 41.225439 -426.601411) (xy 41.177607 -426.627521)
			(xy 41.126545 -426.646559) (xy 41.073294 -426.658134) (xy 41.018937 -426.662013) (xy 40.964582 -426.658116)
			(xy 40.911334 -426.646523) (xy 40.860279 -426.627469) (xy 40.812455 -426.601343) (xy 40.790368 -426.58538)
			(xy 40.771356 -426.571784) (xy 40.729473 -426.551052) (xy 40.684505 -426.538326) (xy 40.637968 -426.534036)
			(xy 40.591431 -426.538326) (xy 40.546463 -426.551052) (xy 40.50458 -426.571784) (xy 40.485568 -426.58538)
			(xy 40.463507 -426.601375) (xy 40.415682 -426.627494) (xy 40.364627 -426.646541) (xy 40.31138 -426.658128)
			(xy 40.257027 -426.66202) (xy 40.202673 -426.658136) (xy 40.149425 -426.646556) (xy 40.098367 -426.627516)
			(xy 40.050538 -426.601404) (xy 40.006913 -426.56875) (xy 39.968378 -426.53022) (xy 39.93572 -426.486599)
			(xy 39.909602 -426.438773) (xy 39.890556 -426.387717) (xy 39.87897 -426.33447) (xy 39.87508 -426.280117)
			(xy 36.341706 -426.280117) (xy 36.361593 -426.312236) (xy 36.400327 -426.390025) (xy 36.431719 -426.471057)
			(xy 36.4555 -426.554639) (xy 36.471468 -426.640059) (xy 36.479486 -426.726588) (xy 36.479988 -426.770038)
			(xy 36.479486 -426.813488) (xy 36.471468 -426.900017) (xy 36.4555 -426.985437) (xy 36.431719 -427.069019)
			(xy 36.400327 -427.150051) (xy 36.361593 -427.22784) (xy 36.315846 -427.301724) (xy 36.263477 -427.371071)
			(xy 36.204933 -427.435291) (xy 36.140713 -427.493835) (xy 36.071366 -427.546204) (xy 35.997482 -427.591951)
			(xy 35.919693 -427.630685) (xy 35.838661 -427.662077) (xy 35.755079 -427.685858) (xy 35.669659 -427.701826)
			(xy 35.58313 -427.709844) (xy 35.49623 -427.709844) (xy 35.409701 -427.701826) (xy 35.324281 -427.685858)
			(xy 35.240699 -427.662077) (xy 35.159667 -427.630685) (xy 35.081878 -427.591951) (xy 35.007994 -427.546204)
			(xy 34.938647 -427.493835) (xy 34.874427 -427.435291) (xy 34.815883 -427.371071) (xy 34.763514 -427.301724)
			(xy 34.717767 -427.22784) (xy 34.679033 -427.150051) (xy 34.647641 -427.069019) (xy 34.62386 -426.985437)
			(xy 34.607892 -426.900017) (xy 34.599874 -426.813488) (xy 31.399486 -426.813488) (xy 31.391468 -426.900017)
			(xy 31.3755 -426.985437) (xy 31.351719 -427.069019) (xy 31.320327 -427.150051) (xy 31.281593 -427.22784)
			(xy 31.235846 -427.301724) (xy 31.183477 -427.371071) (xy 31.124933 -427.435291) (xy 31.060713 -427.493835)
			(xy 30.991366 -427.546204) (xy 30.917482 -427.591951) (xy 30.839693 -427.630685) (xy 30.758661 -427.662077)
			(xy 30.675079 -427.685858) (xy 30.589659 -427.701826) (xy 30.50313 -427.709844) (xy 30.41623 -427.709844)
			(xy 30.329701 -427.701826) (xy 30.244281 -427.685858) (xy 30.160699 -427.662077) (xy 30.079667 -427.630685)
			(xy 30.001878 -427.591951) (xy 29.927994 -427.546204) (xy 29.858647 -427.493835) (xy 29.794427 -427.435291)
			(xy 29.735883 -427.371071) (xy 29.683514 -427.301724) (xy 29.637767 -427.22784) (xy 29.599033 -427.150051)
			(xy 29.567641 -427.069019) (xy 29.54386 -426.985437) (xy 29.527892 -426.900017) (xy 29.519874 -426.813488)
			(xy 28.353512 -426.813488) (xy 28.353512 -429.353488) (xy 29.519874 -429.353488) (xy 29.519874 -429.266588)
			(xy 29.527892 -429.180059) (xy 29.54386 -429.094639) (xy 29.567641 -429.011057) (xy 29.599033 -428.930025)
			(xy 29.637767 -428.852236) (xy 29.683514 -428.778352) (xy 29.735883 -428.709005) (xy 29.794427 -428.644785)
			(xy 29.858647 -428.586241) (xy 29.927994 -428.533872) (xy 30.001878 -428.488125) (xy 30.079667 -428.449391)
			(xy 30.160699 -428.417999) (xy 30.244281 -428.394218) (xy 30.329701 -428.37825) (xy 30.41623 -428.370232)
			(xy 30.50313 -428.370232) (xy 30.589659 -428.37825) (xy 30.675079 -428.394218) (xy 30.758661 -428.417999)
			(xy 30.839693 -428.449391) (xy 30.917482 -428.488125) (xy 30.991366 -428.533872) (xy 31.060713 -428.586241)
			(xy 31.124933 -428.644785) (xy 31.183477 -428.709005) (xy 31.235846 -428.778352) (xy 31.281593 -428.852236)
			(xy 31.320327 -428.930025) (xy 31.351719 -429.011057) (xy 31.3755 -429.094639) (xy 31.391468 -429.180059)
			(xy 31.399486 -429.266588) (xy 31.399988 -429.310038) (xy 31.399486 -429.353488) (xy 34.599874 -429.353488)
			(xy 34.599874 -429.266588) (xy 34.607892 -429.180059) (xy 34.62386 -429.094639) (xy 34.647641 -429.011057)
			(xy 34.679033 -428.930025) (xy 34.717767 -428.852236) (xy 34.763514 -428.778352) (xy 34.815883 -428.709005)
			(xy 34.874427 -428.644785) (xy 34.938647 -428.586241) (xy 35.007994 -428.533872) (xy 35.081878 -428.488125)
			(xy 35.159667 -428.449391) (xy 35.240699 -428.417999) (xy 35.324281 -428.394218) (xy 35.409701 -428.37825)
			(xy 35.49623 -428.370232) (xy 35.58313 -428.370232) (xy 35.669659 -428.37825) (xy 35.755079 -428.394218)
			(xy 35.838661 -428.417999) (xy 35.919693 -428.449391) (xy 35.997482 -428.488125) (xy 36.071366 -428.533872)
			(xy 36.140713 -428.586241) (xy 36.204933 -428.644785) (xy 36.211253 -428.651718) (xy 39.875079 -428.651718)
			(xy 39.878964 -428.597364) (xy 39.890545 -428.544116) (xy 39.909586 -428.493058) (xy 39.9357 -428.44523)
			(xy 39.968354 -428.401605) (xy 40.006885 -428.363071) (xy 40.050508 -428.330414) (xy 40.098334 -428.304297)
			(xy 40.149391 -428.285252) (xy 40.202638 -428.273667) (xy 40.256992 -428.269779) (xy 40.311346 -428.273665)
			(xy 40.364594 -428.285247) (xy 40.415651 -428.30429) (xy 40.463478 -428.330405) (xy 40.485568 -428.346362)
			(xy 40.50458 -428.359958) (xy 40.546463 -428.38069) (xy 40.591431 -428.393416) (xy 40.637968 -428.397706)
			(xy 40.684505 -428.393416) (xy 40.729473 -428.38069) (xy 40.771356 -428.359958) (xy 40.790368 -428.346362)
			(xy 40.812485 -428.33044) (xy 40.860311 -428.304318) (xy 40.911368 -428.285269) (xy 40.964616 -428.27368)
			(xy 41.018972 -428.269788) (xy 41.073328 -428.273672) (xy 41.126578 -428.285253) (xy 41.177638 -428.304294)
			(xy 41.225467 -428.330409) (xy 41.269094 -428.363066) (xy 41.307628 -428.401599) (xy 41.340285 -428.445224)
			(xy 41.366401 -428.493053) (xy 41.378458 -428.525381) (xy 63.554526 -428.525381) (xy 63.558416 -428.471034)
			(xy 63.57 -428.417793) (xy 63.589044 -428.366743) (xy 63.61516 -428.318923) (xy 63.647815 -428.275307)
			(xy 63.686345 -428.236782) (xy 63.729966 -428.204132) (xy 63.777789 -428.178023) (xy 63.828842 -428.158986)
			(xy 63.882084 -428.147409) (xy 63.936431 -428.143526) (xy 63.990778 -428.147417) (xy 64.044019 -428.159004)
			(xy 64.095068 -428.178049) (xy 64.142887 -428.204166) (xy 64.164972 -428.220124) (xy 64.183984 -428.23372)
			(xy 64.225867 -428.254452) (xy 64.270835 -428.267178) (xy 64.317372 -428.271468) (xy 64.363909 -428.267178)
			(xy 64.408877 -428.254452) (xy 64.45076 -428.23372) (xy 64.469772 -428.220124) (xy 64.491831 -428.204119)
			(xy 64.53966 -428.177989) (xy 64.590721 -428.158933) (xy 64.643975 -428.147338) (xy 64.698337 -428.143441)
			(xy 64.7527 -428.14732) (xy 64.805957 -428.158898) (xy 64.857025 -428.177937) (xy 64.904863 -428.20405)
			(xy 64.948497 -428.236706) (xy 64.98704 -428.27524) (xy 65.019705 -428.318868) (xy 65.045829 -428.3667)
			(xy 65.064879 -428.417764) (xy 65.076468 -428.471019) (xy 65.080359 -428.525381) (xy 66.358917 -428.525381)
			(xy 66.362807 -428.471032) (xy 66.374393 -428.417789) (xy 66.393438 -428.366738) (xy 66.419554 -428.318916)
			(xy 66.452211 -428.275299) (xy 66.490743 -428.236773) (xy 66.534366 -428.204123) (xy 66.582191 -428.178013)
			(xy 66.633245 -428.158976) (xy 66.68649 -428.147399) (xy 66.740839 -428.143517) (xy 66.795188 -428.14741)
			(xy 66.84843 -428.158999) (xy 66.89948 -428.178046) (xy 66.9473 -428.204165) (xy 66.969386 -428.220124)
			(xy 66.988398 -428.23372) (xy 67.030281 -428.254452) (xy 67.075249 -428.267178) (xy 67.121786 -428.271468)
			(xy 67.168323 -428.267178) (xy 67.213291 -428.254452) (xy 67.255174 -428.23372) (xy 67.274186 -428.220124)
			(xy 67.296244 -428.20412) (xy 67.344073 -428.177993) (xy 67.395133 -428.158939) (xy 67.448385 -428.147346)
			(xy 67.502745 -428.143449) (xy 67.557106 -428.14733) (xy 67.610361 -428.158907) (xy 67.661427 -428.177947)
			(xy 67.709263 -428.20406) (xy 67.752895 -428.236716) (xy 67.791436 -428.275249) (xy 67.8241 -428.318875)
			(xy 67.850222 -428.366706) (xy 67.869272 -428.417767) (xy 67.88086 -428.471021) (xy 67.884751 -428.525381)
			(xy 67.880865 -428.579741) (xy 67.869282 -428.632996) (xy 67.850238 -428.684059) (xy 67.824121 -428.731893)
			(xy 67.791461 -428.775522) (xy 67.752924 -428.814059) (xy 67.709295 -428.846719) (xy 67.661462 -428.872837)
			(xy 67.610398 -428.891882) (xy 67.557144 -428.903465) (xy 67.502783 -428.907351) (xy 67.448423 -428.90346)
			(xy 67.39517 -428.891872) (xy 67.344108 -428.872823) (xy 67.296277 -428.846701) (xy 67.274186 -428.83074)
			(xy 67.255174 -428.817144) (xy 67.213291 -428.796412) (xy 67.168323 -428.783686) (xy 67.121786 -428.779396)
			(xy 67.075249 -428.783686) (xy 67.030281 -428.796412) (xy 66.988398 -428.817144) (xy 66.969386 -428.83074)
			(xy 66.947268 -428.846656) (xy 66.899446 -428.87277) (xy 66.848393 -428.891812) (xy 66.79515 -428.903395)
			(xy 66.740801 -428.907283) (xy 66.686452 -428.903395) (xy 66.633209 -428.891813) (xy 66.582156 -428.872771)
			(xy 66.534333 -428.846657) (xy 66.490714 -428.814002) (xy 66.452186 -428.775472) (xy 66.419534 -428.731851)
			(xy 66.393422 -428.684027) (xy 66.374382 -428.632974) (xy 66.362802 -428.57973) (xy 66.358917 -428.525381)
			(xy 65.080359 -428.525381) (xy 65.076473 -428.579743) (xy 65.06489 -428.633) (xy 65.045845 -428.684065)
			(xy 65.019726 -428.7319) (xy 64.987065 -428.77553) (xy 64.948526 -428.814068) (xy 64.904895 -428.846729)
			(xy 64.85706 -428.872847) (xy 64.805994 -428.891892) (xy 64.752738 -428.903474) (xy 64.698375 -428.907359)
			(xy 64.644013 -428.903467) (xy 64.590758 -428.891878) (xy 64.539695 -428.872827) (xy 64.491863 -428.846702)
			(xy 64.469772 -428.83074) (xy 64.45076 -428.817144) (xy 64.408877 -428.796412) (xy 64.363909 -428.783686)
			(xy 64.317372 -428.779396) (xy 64.270835 -428.783686) (xy 64.225867 -428.796412) (xy 64.183984 -428.817144)
			(xy 64.164972 -428.83074) (xy 64.142854 -428.846654) (xy 64.095033 -428.872766) (xy 64.043982 -428.891807)
			(xy 63.99074 -428.903388) (xy 63.936393 -428.907274) (xy 63.882046 -428.903386) (xy 63.828805 -428.891803)
			(xy 63.777754 -428.872761) (xy 63.729934 -428.846647) (xy 63.686316 -428.813993) (xy 63.64779 -428.775464)
			(xy 63.615139 -428.731844) (xy 63.589028 -428.684022) (xy 63.56999 -428.63297) (xy 63.55841 -428.579728)
			(xy 63.554526 -428.525381) (xy 41.378458 -428.525381) (xy 41.385444 -428.544112) (xy 41.397026 -428.597362)
			(xy 41.400912 -428.651718) (xy 41.397021 -428.706074) (xy 41.385434 -428.759322) (xy 41.366386 -428.81038)
			(xy 41.340266 -428.858206) (xy 41.307604 -428.901828) (xy 41.269066 -428.940358) (xy 41.225437 -428.97301)
			(xy 41.177605 -428.999121) (xy 41.126543 -429.018157) (xy 41.073292 -429.029733) (xy 41.018936 -429.033612)
			(xy 40.964581 -429.029715) (xy 40.911333 -429.018121) (xy 40.860278 -428.999067) (xy 40.812455 -428.972941)
			(xy 40.790368 -428.956978) (xy 40.771356 -428.943382) (xy 40.729473 -428.92265) (xy 40.684505 -428.909924)
			(xy 40.637968 -428.905634) (xy 40.591431 -428.909924) (xy 40.546463 -428.92265) (xy 40.50458 -428.943382)
			(xy 40.485568 -428.956978) (xy 40.463509 -428.972976) (xy 40.415684 -428.999095) (xy 40.364628 -429.018143)
			(xy 40.311382 -429.02973) (xy 40.257028 -429.033621) (xy 40.202674 -429.029738) (xy 40.149425 -429.018158)
			(xy 40.098367 -428.999118) (xy 40.050538 -428.973006) (xy 40.006912 -428.940352) (xy 39.968378 -428.901822)
			(xy 39.935719 -428.8582) (xy 39.909601 -428.810375) (xy 39.890555 -428.759319) (xy 39.878969 -428.706072)
			(xy 39.875079 -428.651718) (xy 36.211253 -428.651718) (xy 36.263477 -428.709005) (xy 36.315846 -428.778352)
			(xy 36.361593 -428.852236) (xy 36.400327 -428.930025) (xy 36.431719 -429.011057) (xy 36.4555 -429.094639)
			(xy 36.471468 -429.180059) (xy 36.479486 -429.266588) (xy 36.479988 -429.310038) (xy 36.479486 -429.353488)
			(xy 36.471468 -429.440017) (xy 36.4555 -429.525437) (xy 36.431719 -429.609019) (xy 36.400327 -429.690051)
			(xy 36.361593 -429.76784) (xy 36.315846 -429.841724) (xy 36.263477 -429.911071) (xy 36.204933 -429.975291)
			(xy 36.140713 -430.033835) (xy 36.071366 -430.086204) (xy 35.997482 -430.131951) (xy 35.961202 -430.150016)
			(xy 72.998846 -430.150016) (xy 73.00285 -429.949918) (xy 73.014857 -429.75014) (xy 73.034848 -429.551003)
			(xy 73.06279 -429.352825) (xy 73.098638 -429.155923) (xy 73.142336 -428.960614) (xy 73.193813 -428.767209)
			(xy 73.252987 -428.576019) (xy 73.319763 -428.387349) (xy 73.394035 -428.201502) (xy 73.475682 -428.018775)
			(xy 73.564575 -427.839462) (xy 73.660571 -427.663848) (xy 73.763516 -427.492216) (xy 73.873246 -427.32484)
			(xy 73.989584 -427.161989) (xy 74.112345 -427.003922) (xy 74.241332 -426.850894) (xy 74.376339 -426.703149)
			(xy 74.517148 -426.560923) (xy 74.663535 -426.424446) (xy 74.815265 -426.293934) (xy 74.972096 -426.169598)
			(xy 75.133775 -426.051636) (xy 75.300045 -425.940237) (xy 75.470638 -425.83558) (xy 75.645282 -425.737832)
			(xy 75.823698 -425.647149) (xy 76.005598 -425.563678) (xy 76.190693 -425.487551) (xy 76.378685 -425.418891)
			(xy 76.569274 -425.357807) (xy 76.762154 -425.304397) (xy 76.957016 -425.258748) (xy 77.153549 -425.220931)
			(xy 77.351438 -425.191007) (xy 77.550365 -425.169025) (xy 77.750013 -425.15502) (xy 77.950061 -425.149014)
			(xy 78.150189 -425.151016) (xy 78.350077 -425.161024) (xy 78.549404 -425.179021) (xy 78.747852 -425.204979)
			(xy 78.945102 -425.238856) (xy 79.140839 -425.280598) (xy 79.334749 -425.330137) (xy 79.526522 -425.387395)
			(xy 79.715851 -425.45228) (xy 79.902431 -425.524688) (xy 80.085966 -425.604504) (xy 80.26616 -425.691598)
			(xy 80.442725 -425.785832) (xy 80.615378 -425.887055) (xy 80.783843 -425.995105) (xy 80.947851 -426.109808)
			(xy 81.107138 -426.230982) (xy 81.261449 -426.358431) (xy 81.410537 -426.491952) (xy 81.554164 -426.631332)
			(xy 81.6921 -426.776346) (xy 81.824123 -426.926763) (xy 81.950022 -427.082341) (xy 82.069596 -427.242833)
			(xy 82.182652 -427.407979) (xy 82.289011 -427.577517) (xy 82.388502 -427.751175) (xy 82.480965 -427.928674)
			(xy 82.566252 -428.10973) (xy 82.644227 -428.294054) (xy 82.714764 -428.48135) (xy 82.777752 -428.671318)
			(xy 82.833089 -428.863654) (xy 82.880686 -429.05805) (xy 82.920467 -429.254195) (xy 82.952369 -429.451774)
			(xy 82.97634 -429.650471) (xy 82.992342 -429.849969) (xy 83.000349 -430.049947) (xy 83.00085 -430.150016)
			(xy 83.000349 -430.250085) (xy 82.992342 -430.450063) (xy 82.97634 -430.649561) (xy 82.952369 -430.848258)
			(xy 82.920467 -431.045837) (xy 82.880686 -431.241982) (xy 82.833089 -431.436378) (xy 82.777752 -431.628714)
			(xy 82.714764 -431.818682) (xy 82.644227 -432.005978) (xy 82.566252 -432.190302) (xy 82.480965 -432.371358)
			(xy 82.388502 -432.548857) (xy 82.289011 -432.722515) (xy 82.182652 -432.892053) (xy 82.069596 -433.057199)
			(xy 81.950022 -433.217691) (xy 81.824123 -433.373269) (xy 81.6921 -433.523686) (xy 81.554164 -433.6687)
			(xy 81.410537 -433.80808) (xy 81.261449 -433.941601) (xy 81.107138 -434.06905) (xy 80.947851 -434.190224)
			(xy 80.783843 -434.304927) (xy 80.615378 -434.412977) (xy 80.442725 -434.5142) (xy 80.26616 -434.608434)
			(xy 80.085966 -434.695528) (xy 79.902431 -434.775344) (xy 79.715851 -434.847752) (xy 79.526522 -434.912637)
			(xy 79.334749 -434.969895) (xy 79.140839 -435.019434) (xy 78.945102 -435.061176) (xy 78.747852 -435.095053)
			(xy 78.549404 -435.121011) (xy 78.350077 -435.139008) (xy 78.150189 -435.149016) (xy 77.950061 -435.151018)
			(xy 77.750013 -435.145012) (xy 77.550365 -435.131007) (xy 77.351438 -435.109025) (xy 77.153549 -435.079101)
			(xy 76.957016 -435.041284) (xy 76.762154 -434.995635) (xy 76.569274 -434.942225) (xy 76.378685 -434.881141)
			(xy 76.190693 -434.812481) (xy 76.005598 -434.736354) (xy 75.823698 -434.652883) (xy 75.645282 -434.5622)
			(xy 75.470638 -434.464452) (xy 75.300045 -434.359795) (xy 75.133775 -434.248396) (xy 74.972096 -434.130434)
			(xy 74.815265 -434.006098) (xy 74.663535 -433.875586) (xy 74.517148 -433.739109) (xy 74.376339 -433.596883)
			(xy 74.241332 -433.449138) (xy 74.112345 -433.29611) (xy 73.989584 -433.138043) (xy 73.873246 -432.975192)
			(xy 73.763516 -432.807816) (xy 73.660571 -432.636184) (xy 73.564575 -432.46057) (xy 73.475682 -432.281257)
			(xy 73.394035 -432.09853) (xy 73.319763 -431.912683) (xy 73.252987 -431.724013) (xy 73.193813 -431.532823)
			(xy 73.142336 -431.339418) (xy 73.098638 -431.144109) (xy 73.06279 -430.947207) (xy 73.034848 -430.749029)
			(xy 73.014857 -430.549892) (xy 73.00285 -430.350114) (xy 72.998846 -430.150016) (xy 35.961202 -430.150016)
			(xy 35.919693 -430.170685) (xy 35.838661 -430.202077) (xy 35.755079 -430.225858) (xy 35.669659 -430.241826)
			(xy 35.58313 -430.249844) (xy 35.49623 -430.249844) (xy 35.409701 -430.241826) (xy 35.324281 -430.225858)
			(xy 35.240699 -430.202077) (xy 35.159667 -430.170685) (xy 35.081878 -430.131951) (xy 35.007994 -430.086204)
			(xy 34.938647 -430.033835) (xy 34.874427 -429.975291) (xy 34.815883 -429.911071) (xy 34.763514 -429.841724)
			(xy 34.717767 -429.76784) (xy 34.679033 -429.690051) (xy 34.647641 -429.609019) (xy 34.62386 -429.525437)
			(xy 34.607892 -429.440017) (xy 34.599874 -429.353488) (xy 31.399486 -429.353488) (xy 31.391468 -429.440017)
			(xy 31.3755 -429.525437) (xy 31.351719 -429.609019) (xy 31.320327 -429.690051) (xy 31.281593 -429.76784)
			(xy 31.235846 -429.841724) (xy 31.183477 -429.911071) (xy 31.124933 -429.975291) (xy 31.060713 -430.033835)
			(xy 30.991366 -430.086204) (xy 30.917482 -430.131951) (xy 30.839693 -430.170685) (xy 30.758661 -430.202077)
			(xy 30.675079 -430.225858) (xy 30.589659 -430.241826) (xy 30.50313 -430.249844) (xy 30.41623 -430.249844)
			(xy 30.329701 -430.241826) (xy 30.244281 -430.225858) (xy 30.160699 -430.202077) (xy 30.079667 -430.170685)
			(xy 30.001878 -430.131951) (xy 29.927994 -430.086204) (xy 29.858647 -430.033835) (xy 29.794427 -429.975291)
			(xy 29.735883 -429.911071) (xy 29.683514 -429.841724) (xy 29.637767 -429.76784) (xy 29.599033 -429.690051)
			(xy 29.567641 -429.609019) (xy 29.54386 -429.525437) (xy 29.527892 -429.440017) (xy 29.519874 -429.353488)
			(xy 28.353512 -429.353488) (xy 28.353512 -430.614611) (xy 39.875088 -430.614611) (xy 39.878974 -430.560258)
			(xy 39.890556 -430.507012) (xy 39.909597 -430.455956) (xy 39.935711 -430.408129) (xy 39.968366 -430.364506)
			(xy 40.006897 -430.325974) (xy 40.050519 -430.293318) (xy 40.098345 -430.267202) (xy 40.1494 -430.248159)
			(xy 40.202646 -430.236576) (xy 40.256999 -430.232688) (xy 40.311352 -430.236576) (xy 40.364598 -430.248159)
			(xy 40.415653 -430.267202) (xy 40.463479 -430.293317) (xy 40.485568 -430.309274) (xy 40.50458 -430.32287)
			(xy 40.546463 -430.343602) (xy 40.591431 -430.356328) (xy 40.637968 -430.360618) (xy 40.684505 -430.356328)
			(xy 40.729473 -430.343602) (xy 40.771356 -430.32287) (xy 40.790368 -430.309274) (xy 40.812474 -430.293336)
			(xy 40.8603 -430.267212) (xy 40.911358 -430.248162) (xy 40.964608 -430.236572) (xy 41.018965 -430.232679)
			(xy 41.073322 -430.236562) (xy 41.126574 -430.248142) (xy 41.177635 -430.267183) (xy 41.225467 -430.293297)
			(xy 41.269094 -430.325954) (xy 41.30763 -430.364487) (xy 41.340289 -430.408113) (xy 41.366407 -430.455943)
			(xy 41.385451 -430.507003) (xy 41.397035 -430.560253) (xy 41.400921 -430.614611) (xy 41.397032 -430.668968)
			(xy 41.385445 -430.722218) (xy 41.366398 -430.773277) (xy 41.340278 -430.821105) (xy 41.307616 -430.864729)
			(xy 41.269078 -430.90326) (xy 41.225448 -430.935914) (xy 41.177615 -430.962026) (xy 41.126553 -430.981064)
			(xy 41.073301 -430.992641) (xy 41.018943 -430.996521) (xy 40.964586 -430.992625) (xy 40.911338 -430.981032)
			(xy 40.860281 -430.961979) (xy 40.812456 -430.935853) (xy 40.790368 -430.91989) (xy 40.771356 -430.906294)
			(xy 40.729473 -430.885562) (xy 40.684505 -430.872836) (xy 40.637968 -430.868546) (xy 40.591431 -430.872836)
			(xy 40.546463 -430.885562) (xy 40.50458 -430.906294) (xy 40.485568 -430.91989) (xy 40.463497 -430.935872)
			(xy 40.415673 -430.961989) (xy 40.364618 -430.981035) (xy 40.311373 -430.992621) (xy 40.257021 -430.996512)
			(xy 40.202668 -430.992627) (xy 40.149421 -430.981047) (xy 40.098364 -430.962007) (xy 40.050537 -430.935894)
			(xy 40.006913 -430.90324) (xy 39.96838 -430.864711) (xy 39.935723 -430.821089) (xy 39.909606 -430.773264)
			(xy 39.890562 -430.722209) (xy 39.878977 -430.668963) (xy 39.875088 -430.614611) (xy 28.353512 -430.614611)
			(xy 28.353512 -431.893488) (xy 29.519874 -431.893488) (xy 29.519874 -431.806588) (xy 29.527892 -431.720059)
			(xy 29.54386 -431.634639) (xy 29.567641 -431.551057) (xy 29.599033 -431.470025) (xy 29.637767 -431.392236)
			(xy 29.683514 -431.318352) (xy 29.735883 -431.249005) (xy 29.794427 -431.184785) (xy 29.858647 -431.126241)
			(xy 29.927994 -431.073872) (xy 30.001878 -431.028125) (xy 30.079667 -430.989391) (xy 30.160699 -430.957999)
			(xy 30.244281 -430.934218) (xy 30.329701 -430.91825) (xy 30.41623 -430.910232) (xy 30.50313 -430.910232)
			(xy 30.589659 -430.91825) (xy 30.675079 -430.934218) (xy 30.758661 -430.957999) (xy 30.839693 -430.989391)
			(xy 30.917482 -431.028125) (xy 30.991366 -431.073872) (xy 31.060713 -431.126241) (xy 31.124933 -431.184785)
			(xy 31.183477 -431.249005) (xy 31.235846 -431.318352) (xy 31.281593 -431.392236) (xy 31.320327 -431.470025)
			(xy 31.351719 -431.551057) (xy 31.3755 -431.634639) (xy 31.391468 -431.720059) (xy 31.399486 -431.806588)
			(xy 31.399988 -431.850038) (xy 31.399486 -431.893488) (xy 34.599874 -431.893488) (xy 34.599874 -431.806588)
			(xy 34.607892 -431.720059) (xy 34.62386 -431.634639) (xy 34.647641 -431.551057) (xy 34.679033 -431.470025)
			(xy 34.717767 -431.392236) (xy 34.763514 -431.318352) (xy 34.815883 -431.249005) (xy 34.874427 -431.184785)
			(xy 34.938647 -431.126241) (xy 35.007994 -431.073872) (xy 35.081878 -431.028125) (xy 35.159667 -430.989391)
			(xy 35.240699 -430.957999) (xy 35.324281 -430.934218) (xy 35.409701 -430.91825) (xy 35.49623 -430.910232)
			(xy 35.58313 -430.910232) (xy 35.669659 -430.91825) (xy 35.755079 -430.934218) (xy 35.838661 -430.957999)
			(xy 35.919693 -430.989391) (xy 35.997482 -431.028125) (xy 36.071366 -431.073872) (xy 36.140713 -431.126241)
			(xy 36.204933 -431.184785) (xy 36.213059 -431.193699) (xy 63.554502 -431.193699) (xy 63.558389 -431.139348)
			(xy 63.569972 -431.086104) (xy 63.589015 -431.03505) (xy 63.61513 -430.987226) (xy 63.647785 -430.943605)
			(xy 63.686316 -430.905076) (xy 63.729938 -430.872422) (xy 63.777763 -430.846309) (xy 63.828818 -430.827268)
			(xy 63.882062 -430.815687) (xy 63.936413 -430.811802) (xy 63.990764 -430.815691) (xy 64.044008 -430.827276)
			(xy 64.095061 -430.84632) (xy 64.142885 -430.872436) (xy 64.164972 -430.888394) (xy 64.183984 -430.90199)
			(xy 64.225867 -430.922722) (xy 64.270835 -430.935448) (xy 64.317372 -430.939738) (xy 64.363909 -430.935448)
			(xy 64.408877 -430.922722) (xy 64.45076 -430.90199) (xy 64.469772 -430.888394) (xy 64.491859 -430.872429)
			(xy 64.539687 -430.846304) (xy 64.590745 -430.827251) (xy 64.643996 -430.81566) (xy 64.698355 -430.811765)
			(xy 64.752714 -430.815647) (xy 64.805968 -430.827226) (xy 64.857031 -430.846266) (xy 64.904865 -430.87238)
			(xy 64.948495 -430.905036) (xy 64.987033 -430.94357) (xy 65.019695 -430.987196) (xy 65.045815 -431.035027)
			(xy 65.064861 -431.086088) (xy 65.076447 -431.13934) (xy 65.080335 -431.193699) (xy 66.358893 -431.193699)
			(xy 66.362781 -431.139346) (xy 66.374365 -431.0861) (xy 66.393408 -431.035044) (xy 66.419524 -430.987219)
			(xy 66.452181 -430.943597) (xy 66.490714 -430.905066) (xy 66.534338 -430.872412) (xy 66.582165 -430.846299)
			(xy 66.633221 -430.827258) (xy 66.686468 -430.815678) (xy 66.740821 -430.811793) (xy 66.795174 -430.815684)
			(xy 66.848419 -430.82727) (xy 66.899474 -430.846317) (xy 66.947298 -430.872435) (xy 66.969386 -430.888394)
			(xy 66.988398 -430.90199) (xy 67.030281 -430.922722) (xy 67.075249 -430.935448) (xy 67.121786 -430.939738)
			(xy 67.168323 -430.935448) (xy 67.213291 -430.922722) (xy 67.255174 -430.90199) (xy 67.274186 -430.888394)
			(xy 67.296273 -430.87243) (xy 67.344099 -430.846307) (xy 67.395157 -430.827257) (xy 67.448406 -430.815667)
			(xy 67.502763 -430.811773) (xy 67.55712 -430.815656) (xy 67.610372 -430.827236) (xy 67.661433 -430.846276)
			(xy 67.709265 -430.87239) (xy 67.752893 -430.905046) (xy 67.791429 -430.943578) (xy 67.824089 -430.987203)
			(xy 67.850208 -431.035032) (xy 67.869254 -431.086091) (xy 67.880838 -431.139342) (xy 67.884727 -431.193699)
			(xy 67.880839 -431.248056) (xy 67.869254 -431.301306) (xy 67.850209 -431.352366) (xy 67.824091 -431.400195)
			(xy 67.791431 -431.44382) (xy 67.752895 -431.482353) (xy 67.709267 -431.515009) (xy 67.661435 -431.541123)
			(xy 67.610374 -431.560164) (xy 67.557123 -431.571744) (xy 67.502765 -431.575627) (xy 67.448408 -431.571734)
			(xy 67.395159 -431.560144) (xy 67.344101 -431.541094) (xy 67.296275 -431.514971) (xy 67.274186 -431.49901)
			(xy 67.255174 -431.485414) (xy 67.213291 -431.464682) (xy 67.168323 -431.451956) (xy 67.121786 -431.447666)
			(xy 67.075249 -431.451956) (xy 67.030281 -431.464682) (xy 66.988398 -431.485414) (xy 66.969386 -431.49901)
			(xy 66.947296 -431.514966) (xy 66.899472 -431.541084) (xy 66.848417 -431.56013) (xy 66.795171 -431.571716)
			(xy 66.740819 -431.575607) (xy 66.686466 -431.571722) (xy 66.633219 -431.560141) (xy 66.582162 -431.5411)
			(xy 66.534335 -431.514986) (xy 66.490712 -431.482332) (xy 66.452179 -431.443802) (xy 66.419523 -431.400179)
			(xy 66.393407 -431.352354) (xy 66.374364 -431.301298) (xy 66.362781 -431.248052) (xy 66.358893 -431.193699)
			(xy 65.080335 -431.193699) (xy 65.076447 -431.248058) (xy 65.064862 -431.30131) (xy 65.045816 -431.352371)
			(xy 65.019696 -431.400202) (xy 64.987035 -431.443828) (xy 64.948497 -431.482362) (xy 64.904867 -431.515019)
			(xy 64.857033 -431.541133) (xy 64.80597 -431.560174) (xy 64.752717 -431.571753) (xy 64.698357 -431.575635)
			(xy 64.643999 -431.571741) (xy 64.590748 -431.56015) (xy 64.539689 -431.541097) (xy 64.491861 -431.514972)
			(xy 64.469772 -431.49901) (xy 64.45076 -431.485414) (xy 64.408877 -431.464682) (xy 64.363909 -431.451956)
			(xy 64.317372 -431.447666) (xy 64.270835 -431.451956) (xy 64.225867 -431.464682) (xy 64.183984 -431.485414)
			(xy 64.164972 -431.49901) (xy 64.142883 -431.514965) (xy 64.095059 -431.541081) (xy 64.044006 -431.560125)
			(xy 63.990762 -431.571709) (xy 63.936411 -431.575598) (xy 63.88206 -431.571712) (xy 63.828815 -431.560131)
			(xy 63.777761 -431.54109) (xy 63.729936 -431.514977) (xy 63.686314 -431.482323) (xy 63.647783 -431.443793)
			(xy 63.615129 -431.400172) (xy 63.589014 -431.352348) (xy 63.569972 -431.301294) (xy 63.558389 -431.24805)
			(xy 63.554502 -431.193699) (xy 36.213059 -431.193699) (xy 36.263477 -431.249005) (xy 36.315846 -431.318352)
			(xy 36.361593 -431.392236) (xy 36.400327 -431.470025) (xy 36.431719 -431.551057) (xy 36.4555 -431.634639)
			(xy 36.471468 -431.720059) (xy 36.479486 -431.806588) (xy 36.479988 -431.850038) (xy 36.479486 -431.893488)
			(xy 36.471468 -431.980017) (xy 36.4555 -432.065437) (xy 36.431719 -432.149019) (xy 36.400327 -432.230051)
			(xy 36.361593 -432.30784) (xy 36.315846 -432.381724) (xy 36.263477 -432.451071) (xy 36.204933 -432.515291)
			(xy 36.140713 -432.573835) (xy 36.071366 -432.626204) (xy 35.997482 -432.671951) (xy 35.919693 -432.710685)
			(xy 35.838661 -432.742077) (xy 35.782321 -432.758107) (xy 39.875093 -432.758107) (xy 39.878979 -432.703755)
			(xy 39.890561 -432.65051) (xy 39.909603 -432.599454) (xy 39.935717 -432.551629) (xy 39.968372 -432.508006)
			(xy 40.006903 -432.469475) (xy 40.050525 -432.43682) (xy 40.09835 -432.410705) (xy 40.149405 -432.391663)
			(xy 40.202651 -432.38008) (xy 40.257003 -432.376193) (xy 40.311355 -432.380081) (xy 40.3646 -432.391664)
			(xy 40.415655 -432.410707) (xy 40.46348 -432.436823) (xy 40.485568 -432.45278) (xy 40.50458 -432.466376)
			(xy 40.546463 -432.487108) (xy 40.591431 -432.499834) (xy 40.637968 -432.504124) (xy 40.684505 -432.499834)
			(xy 40.729473 -432.487108) (xy 40.771356 -432.466376) (xy 40.790368 -432.45278) (xy 40.812468 -432.436834)
			(xy 40.860295 -432.410709) (xy 40.911353 -432.391658) (xy 40.964603 -432.380068) (xy 41.018961 -432.376174)
			(xy 41.073319 -432.380056) (xy 41.126572 -432.391636) (xy 41.177634 -432.410677) (xy 41.225466 -432.436791)
			(xy 41.269095 -432.469448) (xy 41.307631 -432.507981) (xy 41.340291 -432.551607) (xy 41.36641 -432.599437)
			(xy 41.385455 -432.650498) (xy 41.397039 -432.703749) (xy 41.400926 -432.758107) (xy 41.397037 -432.812465)
			(xy 41.385451 -432.865716) (xy 41.366404 -432.916776) (xy 41.340284 -432.964605) (xy 41.307622 -433.00823)
			(xy 41.269084 -433.046762) (xy 41.225454 -433.079416) (xy 41.177621 -433.105529) (xy 41.126558 -433.124568)
			(xy 41.073305 -433.136146) (xy 41.018947 -433.140026) (xy 40.964589 -433.13613) (xy 40.91134 -433.124538)
			(xy 40.860282 -433.105485) (xy 40.812456 -433.079359) (xy 40.790368 -433.063396) (xy 40.771356 -433.0498)
			(xy 40.729473 -433.029068) (xy 40.684505 -433.016342) (xy 40.637968 -433.012052) (xy 40.591431 -433.016342)
			(xy 40.546463 -433.029068) (xy 40.50458 -433.0498) (xy 40.485568 -433.063396) (xy 40.463492 -433.079369)
			(xy 40.415668 -433.105487) (xy 40.364614 -433.124532) (xy 40.311369 -433.136117) (xy 40.257017 -433.140007)
			(xy 40.202665 -433.136122) (xy 40.149419 -433.124541) (xy 40.098363 -433.105501) (xy 40.050537 -433.079388)
			(xy 40.006914 -433.046734) (xy 39.968382 -433.008205) (xy 39.935725 -432.964584) (xy 39.909609 -432.916759)
			(xy 39.890565 -432.865704) (xy 39.878981 -432.812459) (xy 39.875093 -432.758107) (xy 35.782321 -432.758107)
			(xy 35.755079 -432.765858) (xy 35.669659 -432.781826) (xy 35.58313 -432.789844) (xy 35.49623 -432.789844)
			(xy 35.409701 -432.781826) (xy 35.324281 -432.765858) (xy 35.240699 -432.742077) (xy 35.159667 -432.710685)
			(xy 35.081878 -432.671951) (xy 35.007994 -432.626204) (xy 34.938647 -432.573835) (xy 34.874427 -432.515291)
			(xy 34.815883 -432.451071) (xy 34.763514 -432.381724) (xy 34.717767 -432.30784) (xy 34.679033 -432.230051)
			(xy 34.647641 -432.149019) (xy 34.62386 -432.065437) (xy 34.607892 -431.980017) (xy 34.599874 -431.893488)
			(xy 31.399486 -431.893488) (xy 31.391468 -431.980017) (xy 31.3755 -432.065437) (xy 31.351719 -432.149019)
			(xy 31.320327 -432.230051) (xy 31.281593 -432.30784) (xy 31.235846 -432.381724) (xy 31.183477 -432.451071)
			(xy 31.124933 -432.515291) (xy 31.060713 -432.573835) (xy 30.991366 -432.626204) (xy 30.917482 -432.671951)
			(xy 30.839693 -432.710685) (xy 30.758661 -432.742077) (xy 30.675079 -432.765858) (xy 30.589659 -432.781826)
			(xy 30.50313 -432.789844) (xy 30.41623 -432.789844) (xy 30.329701 -432.781826) (xy 30.244281 -432.765858)
			(xy 30.160699 -432.742077) (xy 30.079667 -432.710685) (xy 30.001878 -432.671951) (xy 29.927994 -432.626204)
			(xy 29.858647 -432.573835) (xy 29.794427 -432.515291) (xy 29.735883 -432.451071) (xy 29.683514 -432.381724)
			(xy 29.637767 -432.30784) (xy 29.599033 -432.230051) (xy 29.567641 -432.149019) (xy 29.54386 -432.065437)
			(xy 29.527892 -431.980017) (xy 29.519874 -431.893488) (xy 28.353512 -431.893488) (xy 28.353512 -434.433488)
			(xy 29.519874 -434.433488) (xy 29.519874 -434.346588) (xy 29.527892 -434.260059) (xy 29.54386 -434.174639)
			(xy 29.567641 -434.091057) (xy 29.599033 -434.010025) (xy 29.637767 -433.932236) (xy 29.683514 -433.858352)
			(xy 29.735883 -433.789005) (xy 29.794427 -433.724785) (xy 29.858647 -433.666241) (xy 29.927994 -433.613872)
			(xy 30.001878 -433.568125) (xy 30.079667 -433.529391) (xy 30.160699 -433.497999) (xy 30.244281 -433.474218)
			(xy 30.329701 -433.45825) (xy 30.41623 -433.450232) (xy 30.50313 -433.450232) (xy 30.589659 -433.45825)
			(xy 30.675079 -433.474218) (xy 30.758661 -433.497999) (xy 30.839693 -433.529391) (xy 30.917482 -433.568125)
			(xy 30.991366 -433.613872) (xy 31.060713 -433.666241) (xy 31.124933 -433.724785) (xy 31.183477 -433.789005)
			(xy 31.235846 -433.858352) (xy 31.281593 -433.932236) (xy 31.320327 -434.010025) (xy 31.351719 -434.091057)
			(xy 31.3755 -434.174639) (xy 31.391468 -434.260059) (xy 31.399486 -434.346588) (xy 31.399988 -434.390038)
			(xy 31.399486 -434.433488) (xy 34.599874 -434.433488) (xy 34.599874 -434.346588) (xy 34.607892 -434.260059)
			(xy 34.62386 -434.174639) (xy 34.647641 -434.091057) (xy 34.679033 -434.010025) (xy 34.717767 -433.932236)
			(xy 34.763514 -433.858352) (xy 34.815883 -433.789005) (xy 34.874427 -433.724785) (xy 34.938647 -433.666241)
			(xy 35.007994 -433.613872) (xy 35.081878 -433.568125) (xy 35.159667 -433.529391) (xy 35.240699 -433.497999)
			(xy 35.324281 -433.474218) (xy 35.409701 -433.45825) (xy 35.49623 -433.450232) (xy 35.58313 -433.450232)
			(xy 35.669659 -433.45825) (xy 35.755079 -433.474218) (xy 35.838661 -433.497999) (xy 35.919693 -433.529391)
			(xy 35.991809 -433.5653) (xy 63.5545 -433.5653) (xy 63.558388 -433.510949) (xy 63.569971 -433.457704)
			(xy 63.589013 -433.40665) (xy 63.615128 -433.358826) (xy 63.647783 -433.315205) (xy 63.686314 -433.276675)
			(xy 63.729936 -433.244021) (xy 63.777761 -433.217908) (xy 63.828816 -433.198867) (xy 63.882061 -433.187286)
			(xy 63.936412 -433.1834) (xy 63.990763 -433.187289) (xy 64.044007 -433.198874) (xy 64.095061 -433.217918)
			(xy 64.142884 -433.244034) (xy 64.164972 -433.259992) (xy 64.183984 -433.273588) (xy 64.225867 -433.29432)
			(xy 64.270835 -433.307046) (xy 64.317372 -433.311336) (xy 64.363909 -433.307046) (xy 64.408877 -433.29432)
			(xy 64.45076 -433.273588) (xy 64.469772 -433.259992) (xy 64.491861 -433.24403) (xy 64.539688 -433.217904)
			(xy 64.590747 -433.198852) (xy 64.643998 -433.187261) (xy 64.698356 -433.183367) (xy 64.752715 -433.187249)
			(xy 64.805969 -433.198828) (xy 64.857032 -433.217868) (xy 64.904865 -433.243982) (xy 64.948495 -433.276638)
			(xy 64.987033 -433.315172) (xy 65.019694 -433.358798) (xy 65.045814 -433.406628) (xy 65.06486 -433.457689)
			(xy 65.076445 -433.510941) (xy 65.080333 -433.5653) (xy 66.358892 -433.5653) (xy 66.362779 -433.510947)
			(xy 66.374363 -433.457701) (xy 66.393406 -433.406645) (xy 66.419522 -433.358819) (xy 66.452179 -433.315196)
			(xy 66.490712 -433.276666) (xy 66.534336 -433.244012) (xy 66.582163 -433.217898) (xy 66.63322 -433.198857)
			(xy 66.686467 -433.187277) (xy 66.74082 -433.183392) (xy 66.795173 -433.187282) (xy 66.848419 -433.198869)
			(xy 66.899474 -433.217915) (xy 66.947298 -433.244033) (xy 66.969386 -433.259992) (xy 66.988398 -433.273588)
			(xy 67.030281 -433.29432) (xy 67.075249 -433.307046) (xy 67.121786 -433.311336) (xy 67.168323 -433.307046)
			(xy 67.213291 -433.29432) (xy 67.255174 -433.273588) (xy 67.274186 -433.259992) (xy 67.296274 -433.244031)
			(xy 67.344101 -433.217908) (xy 67.395158 -433.198858) (xy 67.448408 -433.187268) (xy 67.502764 -433.183375)
			(xy 67.557121 -433.187258) (xy 67.610372 -433.198837) (xy 67.661434 -433.217878) (xy 67.709265 -433.243992)
			(xy 67.752893 -433.276648) (xy 67.791429 -433.31518) (xy 67.824089 -433.358805) (xy 67.850207 -433.406634)
			(xy 67.869252 -433.457693) (xy 67.880837 -433.510943) (xy 67.884725 -433.5653) (xy 67.880837 -433.619657)
			(xy 67.869252 -433.672907) (xy 67.850207 -433.723966) (xy 67.824089 -433.771795) (xy 67.791429 -433.81542)
			(xy 67.752893 -433.853952) (xy 67.709265 -433.886608) (xy 67.661434 -433.912722) (xy 67.610372 -433.931763)
			(xy 67.557121 -433.943342) (xy 67.502764 -433.947225) (xy 67.448408 -433.943332) (xy 67.395158 -433.931742)
			(xy 67.344101 -433.912692) (xy 67.296274 -433.886569) (xy 67.274186 -433.870608) (xy 67.255174 -433.857012)
			(xy 67.213291 -433.83628) (xy 67.168323 -433.823554) (xy 67.121786 -433.819264) (xy 67.075249 -433.823554)
			(xy 67.030281 -433.83628) (xy 66.988398 -433.857012) (xy 66.969386 -433.870608) (xy 66.947298 -433.886567)
			(xy 66.899474 -433.912685) (xy 66.848419 -433.931731) (xy 66.795173 -433.943318) (xy 66.74082 -433.947208)
			(xy 66.686467 -433.943323) (xy 66.63322 -433.931743) (xy 66.582163 -433.912702) (xy 66.534336 -433.886588)
			(xy 66.490712 -433.853934) (xy 66.452179 -433.815404) (xy 66.419522 -433.771781) (xy 66.393406 -433.723955)
			(xy 66.374363 -433.672899) (xy 66.362779 -433.619653) (xy 66.358892 -433.5653) (xy 65.080333 -433.5653)
			(xy 65.076445 -433.619659) (xy 65.06486 -433.672911) (xy 65.045814 -433.723972) (xy 65.019694 -433.771802)
			(xy 64.987033 -433.815428) (xy 64.948495 -433.853962) (xy 64.904865 -433.886618) (xy 64.857032 -433.912732)
			(xy 64.805969 -433.931772) (xy 64.752715 -433.943351) (xy 64.698356 -433.947233) (xy 64.643998 -433.943339)
			(xy 64.590747 -433.931748) (xy 64.539688 -433.912696) (xy 64.491861 -433.88657) (xy 64.469772 -433.870608)
			(xy 64.45076 -433.857012) (xy 64.408877 -433.83628) (xy 64.363909 -433.823554) (xy 64.317372 -433.819264)
			(xy 64.270835 -433.823554) (xy 64.225867 -433.83628) (xy 64.183984 -433.857012) (xy 64.164972 -433.870608)
			(xy 64.142884 -433.886566) (xy 64.095061 -433.912682) (xy 64.044007 -433.931726) (xy 63.990763 -433.943311)
			(xy 63.936412 -433.9472) (xy 63.882061 -433.943314) (xy 63.828816 -433.931733) (xy 63.777761 -433.912692)
			(xy 63.729936 -433.886579) (xy 63.686314 -433.853925) (xy 63.647783 -433.815395) (xy 63.615128 -433.771774)
			(xy 63.589013 -433.72395) (xy 63.569971 -433.672896) (xy 63.558388 -433.619651) (xy 63.5545 -433.5653)
			(xy 35.991809 -433.5653) (xy 35.997482 -433.568125) (xy 36.071366 -433.613872) (xy 36.140713 -433.666241)
			(xy 36.204933 -433.724785) (xy 36.263477 -433.789005) (xy 36.315846 -433.858352) (xy 36.361593 -433.932236)
			(xy 36.400327 -434.010025) (xy 36.431719 -434.091057) (xy 36.4555 -434.174639) (xy 36.471468 -434.260059)
			(xy 36.479486 -434.346588) (xy 36.479988 -434.390038) (xy 36.479486 -434.433488) (xy 36.471468 -434.520017)
			(xy 36.4555 -434.605437) (xy 36.431719 -434.689019) (xy 36.400327 -434.770051) (xy 36.361593 -434.84784)
			(xy 36.315846 -434.921724) (xy 36.263477 -434.991071) (xy 36.204933 -435.055291) (xy 36.140713 -435.113835)
			(xy 36.071366 -435.166204) (xy 35.997482 -435.211951) (xy 35.919693 -435.250685) (xy 35.838661 -435.282077)
			(xy 35.755079 -435.305858) (xy 35.669659 -435.321826) (xy 35.58313 -435.329844) (xy 35.49623 -435.329844)
			(xy 35.409701 -435.321826) (xy 35.324281 -435.305858) (xy 35.240699 -435.282077) (xy 35.159667 -435.250685)
			(xy 35.081878 -435.211951) (xy 35.007994 -435.166204) (xy 34.938647 -435.113835) (xy 34.874427 -435.055291)
			(xy 34.815883 -434.991071) (xy 34.763514 -434.921724) (xy 34.717767 -434.84784) (xy 34.679033 -434.770051)
			(xy 34.647641 -434.689019) (xy 34.62386 -434.605437) (xy 34.607892 -434.520017) (xy 34.599874 -434.433488)
			(xy 31.399486 -434.433488) (xy 31.391468 -434.520017) (xy 31.3755 -434.605437) (xy 31.351719 -434.689019)
			(xy 31.320327 -434.770051) (xy 31.281593 -434.84784) (xy 31.235846 -434.921724) (xy 31.183477 -434.991071)
			(xy 31.124933 -435.055291) (xy 31.060713 -435.113835) (xy 30.991366 -435.166204) (xy 30.917482 -435.211951)
			(xy 30.839693 -435.250685) (xy 30.758661 -435.282077) (xy 30.675079 -435.305858) (xy 30.589659 -435.321826)
			(xy 30.50313 -435.329844) (xy 30.41623 -435.329844) (xy 30.329701 -435.321826) (xy 30.244281 -435.305858)
			(xy 30.160699 -435.282077) (xy 30.079667 -435.250685) (xy 30.001878 -435.211951) (xy 29.927994 -435.166204)
			(xy 29.858647 -435.113835) (xy 29.794427 -435.055291) (xy 29.735883 -434.991071) (xy 29.683514 -434.921724)
			(xy 29.637767 -434.84784) (xy 29.599033 -434.770051) (xy 29.567641 -434.689019) (xy 29.54386 -434.605437)
			(xy 29.527892 -434.520017) (xy 29.519874 -434.433488) (xy 28.353512 -434.433488) (xy 28.353512 -435.528193)
			(xy 63.55451 -435.528193) (xy 63.558398 -435.473843) (xy 63.569982 -435.4206) (xy 63.589025 -435.369548)
			(xy 63.61514 -435.321725) (xy 63.647795 -435.278106) (xy 63.686326 -435.239578) (xy 63.729947 -435.206926)
			(xy 63.777772 -435.180814) (xy 63.828826 -435.161774) (xy 63.882069 -435.150194) (xy 63.936419 -435.14631)
			(xy 63.990769 -435.1502) (xy 64.044012 -435.161785) (xy 64.095063 -435.18083) (xy 64.142885 -435.206946)
			(xy 64.164972 -435.222904) (xy 64.183984 -435.2365) (xy 64.225867 -435.257232) (xy 64.270835 -435.269958)
			(xy 64.317372 -435.274248) (xy 64.363909 -435.269958) (xy 64.408877 -435.257232) (xy 64.45076 -435.2365)
			(xy 64.469772 -435.222904) (xy 64.49185 -435.206925) (xy 64.539678 -435.180799) (xy 64.590737 -435.161745)
			(xy 64.643989 -435.150153) (xy 64.698349 -435.146257) (xy 64.752709 -435.150138) (xy 64.805964 -435.161716)
			(xy 64.857029 -435.180756) (xy 64.904864 -435.20687) (xy 64.948496 -435.239526) (xy 64.987035 -435.27806)
			(xy 65.019698 -435.321687) (xy 65.04582 -435.369518) (xy 65.064867 -435.42058) (xy 65.076454 -435.473833)
			(xy 65.080343 -435.528193) (xy 66.358901 -435.528193) (xy 66.36279 -435.473841) (xy 66.374374 -435.420596)
			(xy 66.393418 -435.369542) (xy 66.419534 -435.321718) (xy 66.452191 -435.278097) (xy 66.490723 -435.239568)
			(xy 66.534347 -435.206916) (xy 66.582173 -435.180804) (xy 66.633229 -435.161764) (xy 66.686475 -435.150185)
			(xy 66.740827 -435.146301) (xy 66.795179 -435.150193) (xy 66.848423 -435.16178) (xy 66.899476 -435.180826)
			(xy 66.947299 -435.206945) (xy 66.969386 -435.222904) (xy 66.988398 -435.2365) (xy 67.030281 -435.257232)
			(xy 67.075249 -435.269958) (xy 67.121786 -435.274248) (xy 67.168323 -435.269958) (xy 67.213291 -435.257232)
			(xy 67.255174 -435.2365) (xy 67.274186 -435.222904) (xy 67.296263 -435.206927) (xy 67.34409 -435.180802)
			(xy 67.395149 -435.161751) (xy 67.448399 -435.15016) (xy 67.502757 -435.146265) (xy 67.557115 -435.150147)
			(xy 67.610368 -435.161726) (xy 67.661431 -435.180766) (xy 67.709264 -435.20688) (xy 67.752894 -435.239536)
			(xy 67.791431 -435.278068) (xy 67.824093 -435.321694) (xy 67.850213 -435.369523) (xy 67.86926 -435.420583)
			(xy 67.880845 -435.473835) (xy 67.884735 -435.528193) (xy 67.880848 -435.582551) (xy 67.869264 -435.635803)
			(xy 67.850219 -435.686864) (xy 67.824101 -435.734694) (xy 67.791441 -435.778321) (xy 67.752905 -435.816855)
			(xy 67.709276 -435.849512) (xy 67.661444 -435.875628) (xy 67.610382 -435.89467) (xy 67.55713 -435.906251)
			(xy 67.502771 -435.910135) (xy 67.448413 -435.906242) (xy 67.395163 -435.894654) (xy 67.344104 -435.875604)
			(xy 67.296275 -435.849481) (xy 67.274186 -435.83352) (xy 67.255174 -435.819924) (xy 67.213291 -435.799192)
			(xy 67.168323 -435.786466) (xy 67.121786 -435.782176) (xy 67.075249 -435.786466) (xy 67.030281 -435.799192)
			(xy 66.988398 -435.819924) (xy 66.969386 -435.83352) (xy 66.947287 -435.849463) (xy 66.899463 -435.875579)
			(xy 66.848409 -435.894624) (xy 66.795164 -435.906209) (xy 66.740813 -435.910099) (xy 66.686461 -435.906213)
			(xy 66.633216 -435.894632) (xy 66.58216 -435.87559) (xy 66.534335 -435.849476) (xy 66.490712 -435.816822)
			(xy 66.452182 -435.778292) (xy 66.419527 -435.73467) (xy 66.393412 -435.686845) (xy 66.37437 -435.63579)
			(xy 66.362788 -435.582545) (xy 66.358901 -435.528193) (xy 65.080343 -435.528193) (xy 65.076456 -435.582553)
			(xy 65.064871 -435.635807) (xy 65.045826 -435.686869) (xy 65.019706 -435.734701) (xy 64.987045 -435.778329)
			(xy 64.948507 -435.816864) (xy 64.904876 -435.849522) (xy 64.857042 -435.875638) (xy 64.805978 -435.89468)
			(xy 64.752724 -435.90626) (xy 64.698363 -435.910143) (xy 64.644004 -435.906249) (xy 64.590751 -435.894659)
			(xy 64.539691 -435.875607) (xy 64.491862 -435.849482) (xy 64.469772 -435.83352) (xy 64.45076 -435.819924)
			(xy 64.408877 -435.799192) (xy 64.363909 -435.786466) (xy 64.317372 -435.782176) (xy 64.270835 -435.786466)
			(xy 64.225867 -435.799192) (xy 64.183984 -435.819924) (xy 64.164972 -435.83352) (xy 64.142873 -435.849461)
			(xy 64.09505 -435.875576) (xy 64.043998 -435.894619) (xy 63.990755 -435.906202) (xy 63.936405 -435.91009)
			(xy 63.882055 -435.906204) (xy 63.828812 -435.894622) (xy 63.777759 -435.87558) (xy 63.729935 -435.849467)
			(xy 63.686315 -435.816813) (xy 63.647786 -435.778284) (xy 63.615132 -435.734663) (xy 63.589019 -435.686839)
			(xy 63.569978 -435.635786) (xy 63.558396 -435.582543) (xy 63.55451 -435.528193) (xy 28.353512 -435.528193)
			(xy 28.353512 -435.989984) (xy 29.519372 -435.989984) (xy 31.399988 -435.989984) (xy 31.399988 -436.973488)
			(xy 34.599874 -436.973488) (xy 34.599874 -436.886588) (xy 34.607892 -436.800059) (xy 34.62386 -436.714639)
			(xy 34.647641 -436.631057) (xy 34.679033 -436.550025) (xy 34.717767 -436.472236) (xy 34.763514 -436.398352)
			(xy 34.815883 -436.329005) (xy 34.874427 -436.264785) (xy 34.938647 -436.206241) (xy 35.007994 -436.153872)
			(xy 35.081878 -436.108125) (xy 35.159667 -436.069391) (xy 35.240699 -436.037999) (xy 35.324281 -436.014218)
			(xy 35.409701 -435.99825) (xy 35.49623 -435.990232) (xy 35.58313 -435.990232) (xy 35.669659 -435.99825)
			(xy 35.755079 -436.014218) (xy 35.838661 -436.037999) (xy 35.919693 -436.069391) (xy 35.997482 -436.108125)
			(xy 36.071366 -436.153872) (xy 36.140713 -436.206241) (xy 36.204933 -436.264785) (xy 36.263477 -436.329005)
			(xy 36.315846 -436.398352) (xy 36.361593 -436.472236) (xy 36.400327 -436.550025) (xy 36.431719 -436.631057)
			(xy 36.4555 -436.714639) (xy 36.471468 -436.800059) (xy 36.479486 -436.886588) (xy 36.479988 -436.930038)
			(xy 36.479486 -436.973488) (xy 36.471468 -437.060017) (xy 36.4555 -437.145437) (xy 36.431719 -437.229019)
			(xy 36.400327 -437.310051) (xy 36.361593 -437.38784) (xy 36.339437 -437.423624) (xy 63.488165 -437.423624)
			(xy 63.492049 -437.369267) (xy 63.50363 -437.316017) (xy 63.522671 -437.264956) (xy 63.548786 -437.217126)
			(xy 63.581441 -437.173498) (xy 63.619974 -437.134963) (xy 63.663598 -437.102303) (xy 63.711427 -437.076185)
			(xy 63.762486 -437.057139) (xy 63.815735 -437.045554) (xy 63.870092 -437.041665) (xy 63.924448 -437.045551)
			(xy 63.977698 -437.057134) (xy 64.028758 -437.076178) (xy 64.076587 -437.102294) (xy 64.098678 -437.118252)
			(xy 64.11769 -437.131848) (xy 64.159573 -437.15258) (xy 64.204541 -437.165306) (xy 64.251078 -437.169596)
			(xy 64.297615 -437.165306) (xy 64.342583 -437.15258) (xy 64.384466 -437.131848) (xy 64.403478 -437.118252)
			(xy 64.425604 -437.102344) (xy 64.473429 -437.076225) (xy 64.524484 -437.057179) (xy 64.57773 -437.045592)
			(xy 64.632083 -437.041702) (xy 64.686437 -437.045588) (xy 64.739684 -437.057169) (xy 64.790741 -437.076211)
			(xy 64.838568 -437.102326) (xy 64.882191 -437.134982) (xy 64.920723 -437.173514) (xy 64.953378 -437.217138)
			(xy 64.979492 -437.264966) (xy 64.998533 -437.316023) (xy 65.010113 -437.36927) (xy 65.013998 -437.423624)
			(xy 66.292556 -437.423624) (xy 66.296441 -437.369265) (xy 66.308022 -437.316013) (xy 66.327064 -437.264951)
			(xy 66.35318 -437.217119) (xy 66.385837 -437.17349) (xy 66.424372 -437.134954) (xy 66.467998 -437.102293)
			(xy 66.515829 -437.076175) (xy 66.566889 -437.057129) (xy 66.620141 -437.045544) (xy 66.674499 -437.041656)
			(xy 66.728858 -437.045544) (xy 66.78211 -437.057129) (xy 66.833171 -437.076174) (xy 66.881001 -437.102293)
			(xy 66.903092 -437.118252) (xy 66.922104 -437.131848) (xy 66.963987 -437.15258) (xy 67.008955 -437.165306)
			(xy 67.055492 -437.169596) (xy 67.102029 -437.165306) (xy 67.146997 -437.15258) (xy 67.18888 -437.131848)
			(xy 67.207892 -437.118252) (xy 67.230018 -437.102345) (xy 67.277842 -437.076229) (xy 67.328895 -437.057184)
			(xy 67.38214 -437.045599) (xy 67.436491 -437.041711) (xy 67.490843 -437.045597) (xy 67.544088 -437.057179)
			(xy 67.595143 -437.076221) (xy 67.642968 -437.102336) (xy 67.686589 -437.134991) (xy 67.725119 -437.173523)
			(xy 67.757772 -437.217145) (xy 67.783885 -437.264971) (xy 67.802925 -437.316027) (xy 67.814505 -437.369272)
			(xy 67.818389 -437.423624) (xy 67.814498 -437.477975) (xy 67.802912 -437.531219) (xy 67.783865 -437.582272)
			(xy 67.757746 -437.630095) (xy 67.725087 -437.673714) (xy 67.686553 -437.71224) (xy 67.642927 -437.74489)
			(xy 67.595099 -437.770999) (xy 67.544042 -437.790034) (xy 67.490795 -437.80161) (xy 67.436443 -437.805489)
			(xy 67.382093 -437.801594) (xy 67.328849 -437.790002) (xy 67.277798 -437.770952) (xy 67.229977 -437.744829)
			(xy 67.207892 -437.728868) (xy 67.18888 -437.715272) (xy 67.146997 -437.69454) (xy 67.102029 -437.681814)
			(xy 67.055492 -437.677524) (xy 67.008955 -437.681814) (xy 66.963987 -437.69454) (xy 66.922104 -437.715272)
			(xy 66.903092 -437.728868) (xy 66.881042 -437.744881) (xy 66.833214 -437.771006) (xy 66.782156 -437.790058)
			(xy 66.728905 -437.801649) (xy 66.674548 -437.805544) (xy 66.620189 -437.801663) (xy 66.566935 -437.790085)
			(xy 66.515872 -437.771045) (xy 66.468038 -437.744933) (xy 66.424408 -437.712278) (xy 66.385869 -437.673746)
			(xy 66.353206 -437.630122) (xy 66.327084 -437.582293) (xy 66.308036 -437.531233) (xy 66.296448 -437.477982)
			(xy 66.292556 -437.423624) (xy 65.013998 -437.423624) (xy 65.010107 -437.477977) (xy 64.998519 -437.531223)
			(xy 64.979472 -437.582278) (xy 64.953352 -437.630102) (xy 64.920691 -437.673722) (xy 64.882155 -437.712249)
			(xy 64.838528 -437.7449) (xy 64.790697 -437.771009) (xy 64.739638 -437.790044) (xy 64.686389 -437.801619)
			(xy 64.632035 -437.805498) (xy 64.577683 -437.801601) (xy 64.524438 -437.790008) (xy 64.473385 -437.770955)
			(xy 64.425564 -437.74483) (xy 64.403478 -437.728868) (xy 64.384466 -437.715272) (xy 64.342583 -437.69454)
			(xy 64.297615 -437.681814) (xy 64.251078 -437.677524) (xy 64.204541 -437.681814) (xy 64.159573 -437.69454)
			(xy 64.11769 -437.715272) (xy 64.098678 -437.728868) (xy 64.076628 -437.74488) (xy 64.028801 -437.771002)
			(xy 63.977744 -437.790052) (xy 63.924496 -437.801642) (xy 63.87014 -437.805535) (xy 63.815783 -437.801653)
			(xy 63.762532 -437.790075) (xy 63.71147 -437.771035) (xy 63.663639 -437.744923) (xy 63.62001 -437.712269)
			(xy 63.581473 -437.673738) (xy 63.548812 -437.630115) (xy 63.522691 -437.582287) (xy 63.503643 -437.531229)
			(xy 63.492056 -437.47798) (xy 63.488165 -437.423624) (xy 36.339437 -437.423624) (xy 36.315846 -437.461724)
			(xy 36.263477 -437.531071) (xy 36.204933 -437.595291) (xy 36.140713 -437.653835) (xy 36.071366 -437.706204)
			(xy 35.997482 -437.751951) (xy 35.919693 -437.790685) (xy 35.838661 -437.822077) (xy 35.755079 -437.845858)
			(xy 35.669659 -437.861826) (xy 35.58313 -437.869844) (xy 35.49623 -437.869844) (xy 35.409701 -437.861826)
			(xy 35.324281 -437.845858) (xy 35.240699 -437.822077) (xy 35.159667 -437.790685) (xy 35.081878 -437.751951)
			(xy 35.007994 -437.706204) (xy 34.938647 -437.653835) (xy 34.874427 -437.595291) (xy 34.815883 -437.531071)
			(xy 34.763514 -437.461724) (xy 34.717767 -437.38784) (xy 34.679033 -437.310051) (xy 34.647641 -437.229019)
			(xy 34.62386 -437.145437) (xy 34.607892 -437.060017) (xy 34.599874 -436.973488) (xy 31.399988 -436.973488)
			(xy 31.399988 -437.870092) (xy 29.519372 -437.870092) (xy 29.519372 -435.989984) (xy 28.353512 -435.989984)
			(xy 28.353512 -437.24576) (xy 28.354048 -437.262379) (xy 28.362633 -437.294489) (xy 28.379229 -437.323287)
			(xy 28.390596 -437.335422) (xy 29.992822 -438.9374) (xy 51.342544 -438.9374) (xy 52.994052 -438.9374)
			(xy 52.994052 -440.588908) (xy 51.342544 -440.588908) (xy 51.342544 -438.9374) (xy 29.992822 -438.9374)
			(xy 31.242946 -440.18733) (xy 41.65141 -440.18733) (xy 41.65141 -440.127394) (xy 41.659233 -440.067972)
			(xy 41.674746 -440.010079) (xy 41.697682 -439.954706) (xy 41.727649 -439.9028) (xy 41.764136 -439.85525)
			(xy 41.806516 -439.81287) (xy 41.854066 -439.776383) (xy 41.905972 -439.746416) (xy 41.961345 -439.72348)
			(xy 42.019238 -439.707967) (xy 42.07866 -439.700144) (xy 42.138596 -439.700144) (xy 42.198018 -439.707967)
			(xy 42.255911 -439.72348) (xy 42.311284 -439.746416) (xy 42.36319 -439.776383) (xy 42.398801 -439.803709)
			(xy 47.842668 -439.803709) (xy 47.842668 -439.722599) (xy 47.850618 -439.64188) (xy 47.866441 -439.562329)
			(xy 47.889986 -439.484713) (xy 47.921025 -439.409777) (xy 47.95926 -439.338245) (xy 48.004322 -439.270805)
			(xy 48.055777 -439.208106) (xy 48.11313 -439.150753) (xy 48.175829 -439.099298) (xy 48.243269 -439.054236)
			(xy 48.314801 -439.016001) (xy 48.389737 -438.984962) (xy 48.467353 -438.961417) (xy 48.546904 -438.945594)
			(xy 48.627623 -438.937644) (xy 48.708733 -438.937644) (xy 48.789452 -438.945594) (xy 48.869003 -438.961417)
			(xy 48.946619 -438.984962) (xy 49.021555 -439.016001) (xy 49.093087 -439.054236) (xy 49.160527 -439.099298)
			(xy 49.223226 -439.150753) (xy 49.280579 -439.208106) (xy 49.332034 -439.270805) (xy 49.377096 -439.338245)
			(xy 49.415331 -439.409777) (xy 49.44637 -439.484713) (xy 49.469915 -439.562329) (xy 49.485738 -439.64188)
			(xy 49.493688 -439.722599) (xy 49.494186 -439.763154) (xy 49.493688 -439.803709) (xy 49.485738 -439.884428)
			(xy 49.469915 -439.963979) (xy 49.44637 -440.041595) (xy 49.415331 -440.116531) (xy 49.377096 -440.188063)
			(xy 49.332034 -440.255503) (xy 49.280579 -440.318202) (xy 49.223226 -440.375555) (xy 49.160527 -440.42701)
			(xy 49.093087 -440.472072) (xy 49.021555 -440.510307) (xy 48.946619 -440.541346) (xy 48.869003 -440.564891)
			(xy 48.789452 -440.580714) (xy 48.708733 -440.588664) (xy 48.627623 -440.588664) (xy 48.546904 -440.580714)
			(xy 48.467353 -440.564891) (xy 48.389737 -440.541346) (xy 48.314801 -440.510307) (xy 48.243269 -440.472072)
			(xy 48.175829 -440.42701) (xy 48.11313 -440.375555) (xy 48.055777 -440.318202) (xy 48.004322 -440.255503)
			(xy 47.95926 -440.188063) (xy 47.921025 -440.116531) (xy 47.889986 -440.041595) (xy 47.866441 -439.963979)
			(xy 47.850618 -439.884428) (xy 47.842668 -439.803709) (xy 42.398801 -439.803709) (xy 42.41074 -439.81287)
			(xy 42.45312 -439.85525) (xy 42.489607 -439.9028) (xy 42.519574 -439.954706) (xy 42.54251 -440.010079)
			(xy 42.558023 -440.067972) (xy 42.565846 -440.127394) (xy 42.566336 -440.157362) (xy 42.565846 -440.18733)
			(xy 42.558023 -440.246752) (xy 42.54251 -440.304645) (xy 42.519574 -440.360018) (xy 42.489607 -440.411924)
			(xy 42.45312 -440.459474) (xy 42.41074 -440.501854) (xy 42.36319 -440.538341) (xy 42.311284 -440.568308)
			(xy 42.255911 -440.591244) (xy 42.198018 -440.606757) (xy 42.138596 -440.61458) (xy 42.07866 -440.61458)
			(xy 42.019238 -440.606757) (xy 41.961345 -440.591244) (xy 41.905972 -440.568308) (xy 41.854066 -440.538341)
			(xy 41.806516 -440.501854) (xy 41.764136 -440.459474) (xy 41.727649 -440.411924) (xy 41.697682 -440.360018)
			(xy 41.674746 -440.304645) (xy 41.659233 -440.246752) (xy 41.65141 -440.18733) (xy 31.242946 -440.18733)
			(xy 32.756513 -441.700662) (xy 36.341794 -441.700662) (xy 36.341794 -441.640726) (xy 36.349617 -441.581304)
			(xy 36.36513 -441.523411) (xy 36.388066 -441.468038) (xy 36.418033 -441.416132) (xy 36.45452 -441.368582)
			(xy 36.4969 -441.326202) (xy 36.54445 -441.289715) (xy 36.596356 -441.259748) (xy 36.651729 -441.236812)
			(xy 36.709622 -441.221299) (xy 36.769044 -441.213476) (xy 36.82898 -441.213476) (xy 36.888402 -441.221299)
			(xy 36.921821 -441.230254) (xy 37.721268 -441.230254) (xy 37.721268 -441.170318) (xy 37.729091 -441.110896)
			(xy 37.744604 -441.053003) (xy 37.76754 -440.99763) (xy 37.797507 -440.945724) (xy 37.833994 -440.898174)
			(xy 37.876374 -440.855794) (xy 37.923924 -440.819307) (xy 37.97583 -440.78934) (xy 38.031203 -440.766404)
			(xy 38.089096 -440.750891) (xy 38.148518 -440.743068) (xy 38.208454 -440.743068) (xy 38.267876 -440.750891)
			(xy 38.325769 -440.766404) (xy 38.360833 -440.780928) (xy 39.213264 -440.780928) (xy 39.213264 -440.720992)
			(xy 39.221087 -440.66157) (xy 39.2366 -440.603677) (xy 39.259536 -440.548304) (xy 39.289503 -440.496398)
			(xy 39.32599 -440.448848) (xy 39.36837 -440.406468) (xy 39.41592 -440.369981) (xy 39.467826 -440.340014)
			(xy 39.523199 -440.317078) (xy 39.581092 -440.301565) (xy 39.640514 -440.293742) (xy 39.70045 -440.293742)
			(xy 39.759872 -440.301565) (xy 39.817765 -440.317078) (xy 39.873138 -440.340014) (xy 39.925044 -440.369981)
			(xy 39.972594 -440.406468) (xy 40.014974 -440.448848) (xy 40.051461 -440.496398) (xy 40.081428 -440.548304)
			(xy 40.104364 -440.603677) (xy 40.119877 -440.66157) (xy 40.1277 -440.720992) (xy 40.12819 -440.75096)
			(xy 40.1277 -440.780928) (xy 40.119877 -440.84035) (xy 40.104364 -440.898243) (xy 40.081428 -440.953616)
			(xy 40.051461 -441.005522) (xy 40.014974 -441.053072) (xy 39.972594 -441.095452) (xy 39.925044 -441.131939)
			(xy 39.873138 -441.161906) (xy 39.817765 -441.184842) (xy 39.759872 -441.200355) (xy 39.70045 -441.208178)
			(xy 39.640514 -441.208178) (xy 39.581092 -441.200355) (xy 39.523199 -441.184842) (xy 39.467826 -441.161906)
			(xy 39.41592 -441.131939) (xy 39.36837 -441.095452) (xy 39.32599 -441.053072) (xy 39.289503 -441.005522)
			(xy 39.259536 -440.953616) (xy 39.2366 -440.898243) (xy 39.221087 -440.84035) (xy 39.213264 -440.780928)
			(xy 38.360833 -440.780928) (xy 38.381142 -440.78934) (xy 38.433048 -440.819307) (xy 38.480598 -440.855794)
			(xy 38.522978 -440.898174) (xy 38.559465 -440.945724) (xy 38.589432 -440.99763) (xy 38.612368 -441.053003)
			(xy 38.627881 -441.110896) (xy 38.635704 -441.170318) (xy 38.636194 -441.200286) (xy 38.635704 -441.230254)
			(xy 38.627881 -441.289676) (xy 38.612368 -441.347569) (xy 38.596783 -441.385194) (xy 41.01006 -441.385194)
			(xy 41.01006 -441.325258) (xy 41.017883 -441.265836) (xy 41.033396 -441.207943) (xy 41.056332 -441.15257)
			(xy 41.086299 -441.100664) (xy 41.122786 -441.053114) (xy 41.165166 -441.010734) (xy 41.212716 -440.974247)
			(xy 41.264622 -440.94428) (xy 41.319995 -440.921344) (xy 41.377888 -440.905831) (xy 41.43731 -440.898008)
			(xy 41.497246 -440.898008) (xy 41.556668 -440.905831) (xy 41.614561 -440.921344) (xy 41.669934 -440.94428)
			(xy 41.72184 -440.974247) (xy 41.738358 -440.986922) (xy 43.584858 -440.986922) (xy 43.584858 -440.926986)
			(xy 43.592681 -440.867564) (xy 43.608194 -440.809671) (xy 43.63113 -440.754298) (xy 43.661097 -440.702392)
			(xy 43.697584 -440.654842) (xy 43.739964 -440.612462) (xy 43.787514 -440.575975) (xy 43.83942 -440.546008)
			(xy 43.894793 -440.523072) (xy 43.952686 -440.507559) (xy 44.012108 -440.499736) (xy 44.072044 -440.499736)
			(xy 44.131466 -440.507559) (xy 44.189359 -440.523072) (xy 44.244732 -440.546008) (xy 44.296638 -440.575975)
			(xy 44.344188 -440.612462) (xy 44.386568 -440.654842) (xy 44.423055 -440.702392) (xy 44.453022 -440.754298)
			(xy 44.475958 -440.809671) (xy 44.491471 -440.867564) (xy 44.499294 -440.926986) (xy 44.499784 -440.956954)
			(xy 44.499294 -440.986922) (xy 44.491471 -441.046344) (xy 44.475958 -441.104237) (xy 44.453022 -441.15961)
			(xy 44.423055 -441.211516) (xy 44.386568 -441.259066) (xy 44.344188 -441.301446) (xy 44.296638 -441.337933)
			(xy 44.244732 -441.3679) (xy 44.189359 -441.390836) (xy 44.131466 -441.406349) (xy 44.072044 -441.414172)
			(xy 44.012108 -441.414172) (xy 43.952686 -441.406349) (xy 43.894793 -441.390836) (xy 43.83942 -441.3679)
			(xy 43.787514 -441.337933) (xy 43.739964 -441.301446) (xy 43.697584 -441.259066) (xy 43.661097 -441.211516)
			(xy 43.63113 -441.15961) (xy 43.608194 -441.104237) (xy 43.592681 -441.046344) (xy 43.584858 -440.986922)
			(xy 41.738358 -440.986922) (xy 41.76939 -441.010734) (xy 41.81177 -441.053114) (xy 41.848257 -441.100664)
			(xy 41.878224 -441.15257) (xy 41.90116 -441.207943) (xy 41.916673 -441.265836) (xy 41.924496 -441.325258)
			(xy 41.924986 -441.355226) (xy 41.924496 -441.385194) (xy 41.916673 -441.444616) (xy 41.90116 -441.502509)
			(xy 41.878224 -441.557882) (xy 41.848257 -441.609788) (xy 41.81177 -441.657338) (xy 41.76939 -441.699718)
			(xy 41.72184 -441.736205) (xy 41.669934 -441.766172) (xy 41.615305 -441.7888) (xy 42.253136 -441.7888)
			(xy 42.253136 -441.728864) (xy 42.260959 -441.669442) (xy 42.276472 -441.611549) (xy 42.299408 -441.556176)
			(xy 42.329375 -441.50427) (xy 42.365862 -441.45672) (xy 42.408242 -441.41434) (xy 42.455792 -441.377853)
			(xy 42.507698 -441.347886) (xy 42.563071 -441.32495) (xy 42.620964 -441.309437) (xy 42.680386 -441.301614)
			(xy 42.740322 -441.301614) (xy 42.799744 -441.309437) (xy 42.857637 -441.32495) (xy 42.91301 -441.347886)
			(xy 42.964916 -441.377853) (xy 43.012466 -441.41434) (xy 43.054846 -441.45672) (xy 43.091333 -441.50427)
			(xy 43.1213 -441.556176) (xy 43.144236 -441.611549) (xy 43.159749 -441.669442) (xy 43.167572 -441.728864)
			(xy 43.168062 -441.758832) (xy 43.167572 -441.7888) (xy 43.159749 -441.848222) (xy 43.144236 -441.906115)
			(xy 43.1213 -441.961488) (xy 43.091333 -442.013394) (xy 43.054846 -442.060944) (xy 43.012466 -442.103324)
			(xy 42.964916 -442.139811) (xy 42.91301 -442.169778) (xy 42.857637 -442.192714) (xy 42.799744 -442.208227)
			(xy 42.740322 -442.21605) (xy 42.680386 -442.21605) (xy 42.620964 -442.208227) (xy 42.563071 -442.192714)
			(xy 42.507698 -442.169778) (xy 42.455792 -442.139811) (xy 42.408242 -442.103324) (xy 42.365862 -442.060944)
			(xy 42.329375 -442.013394) (xy 42.299408 -441.961488) (xy 42.276472 -441.906115) (xy 42.260959 -441.848222)
			(xy 42.253136 -441.7888) (xy 41.615305 -441.7888) (xy 41.614561 -441.789108) (xy 41.556668 -441.804621)
			(xy 41.497246 -441.812444) (xy 41.43731 -441.812444) (xy 41.377888 -441.804621) (xy 41.319995 -441.789108)
			(xy 41.264622 -441.766172) (xy 41.212716 -441.736205) (xy 41.165166 -441.699718) (xy 41.122786 -441.657338)
			(xy 41.086299 -441.609788) (xy 41.056332 -441.557882) (xy 41.033396 -441.502509) (xy 41.017883 -441.444616)
			(xy 41.01006 -441.385194) (xy 38.596783 -441.385194) (xy 38.589432 -441.402942) (xy 38.559465 -441.454848)
			(xy 38.522978 -441.502398) (xy 38.480598 -441.544778) (xy 38.433048 -441.581265) (xy 38.381142 -441.611232)
			(xy 38.325769 -441.634168) (xy 38.267876 -441.649681) (xy 38.208454 -441.657504) (xy 38.148518 -441.657504)
			(xy 38.089096 -441.649681) (xy 38.031203 -441.634168) (xy 37.97583 -441.611232) (xy 37.923924 -441.581265)
			(xy 37.876374 -441.544778) (xy 37.833994 -441.502398) (xy 37.797507 -441.454848) (xy 37.76754 -441.402942)
			(xy 37.744604 -441.347569) (xy 37.729091 -441.289676) (xy 37.721268 -441.230254) (xy 36.921821 -441.230254)
			(xy 36.946295 -441.236812) (xy 37.001668 -441.259748) (xy 37.053574 -441.289715) (xy 37.101124 -441.326202)
			(xy 37.143504 -441.368582) (xy 37.179991 -441.416132) (xy 37.209958 -441.468038) (xy 37.232894 -441.523411)
			(xy 37.248407 -441.581304) (xy 37.25623 -441.640726) (xy 37.25672 -441.670694) (xy 37.25623 -441.700662)
			(xy 37.248407 -441.760084) (xy 37.232894 -441.817977) (xy 37.209958 -441.87335) (xy 37.179991 -441.925256)
			(xy 37.143504 -441.972806) (xy 37.101124 -442.015186) (xy 37.053574 -442.051673) (xy 37.001668 -442.08164)
			(xy 36.946295 -442.104576) (xy 36.888402 -442.120089) (xy 36.82898 -442.127912) (xy 36.769044 -442.127912)
			(xy 36.709622 -442.120089) (xy 36.651729 -442.104576) (xy 36.596356 -442.08164) (xy 36.54445 -442.051673)
			(xy 36.4969 -442.015186) (xy 36.45452 -441.972806) (xy 36.418033 -441.925256) (xy 36.388066 -441.87335)
			(xy 36.36513 -441.817977) (xy 36.349617 -441.760084) (xy 36.341794 -441.700662) (xy 32.756513 -441.700662)
			(xy 34.94405 -443.88786) (xy 37.615114 -443.88786) (xy 39.077896 -445.350642) (xy 81.791284 -445.350642)
			(xy 81.791284 -445.290706) (xy 81.799107 -445.231284) (xy 81.81462 -445.173391) (xy 81.837556 -445.118018)
			(xy 81.867523 -445.066112) (xy 81.90401 -445.018562) (xy 81.94639 -444.976182) (xy 81.99394 -444.939695)
			(xy 82.045846 -444.909728) (xy 82.101219 -444.886792) (xy 82.159112 -444.871279) (xy 82.218534 -444.863456)
			(xy 82.27847 -444.863456) (xy 82.337892 -444.871279) (xy 82.395785 -444.886792) (xy 82.451158 -444.909728)
			(xy 82.503064 -444.939695) (xy 82.550614 -444.976182) (xy 82.592994 -445.018562) (xy 82.623672 -445.058542)
			(xy 83.33408 -445.058542) (xy 83.33408 -444.998606) (xy 83.341903 -444.939184) (xy 83.357416 -444.881291)
			(xy 83.380352 -444.825918) (xy 83.410319 -444.774012) (xy 83.446806 -444.726462) (xy 83.489186 -444.684082)
			(xy 83.536736 -444.647595) (xy 83.588642 -444.617628) (xy 83.644015 -444.594692) (xy 83.701908 -444.579179)
			(xy 83.76133 -444.571356) (xy 83.821266 -444.571356) (xy 83.880688 -444.579179) (xy 83.938581 -444.594692)
			(xy 83.993954 -444.617628) (xy 84.04586 -444.647595) (xy 84.09341 -444.684082) (xy 84.13579 -444.726462)
			(xy 84.172277 -444.774012) (xy 84.202244 -444.825918) (xy 84.22518 -444.881291) (xy 84.240693 -444.939184)
			(xy 84.248516 -444.998606) (xy 84.249006 -445.028574) (xy 84.248516 -445.058542) (xy 84.240693 -445.117964)
			(xy 84.22518 -445.175857) (xy 84.202244 -445.23123) (xy 84.172277 -445.283136) (xy 84.13579 -445.330686)
			(xy 84.09341 -445.373066) (xy 84.04586 -445.409553) (xy 83.993954 -445.43952) (xy 83.938581 -445.462456)
			(xy 83.880688 -445.477969) (xy 83.821266 -445.485792) (xy 83.76133 -445.485792) (xy 83.701908 -445.477969)
			(xy 83.644015 -445.462456) (xy 83.588642 -445.43952) (xy 83.536736 -445.409553) (xy 83.489186 -445.373066)
			(xy 83.446806 -445.330686) (xy 83.410319 -445.283136) (xy 83.380352 -445.23123) (xy 83.357416 -445.175857)
			(xy 83.341903 -445.117964) (xy 83.33408 -445.058542) (xy 82.623672 -445.058542) (xy 82.629481 -445.066112)
			(xy 82.659448 -445.118018) (xy 82.682384 -445.173391) (xy 82.697897 -445.231284) (xy 82.70572 -445.290706)
			(xy 82.70621 -445.320674) (xy 82.70572 -445.350642) (xy 82.697897 -445.410064) (xy 82.682384 -445.467957)
			(xy 82.659448 -445.52333) (xy 82.629481 -445.575236) (xy 82.592994 -445.622786) (xy 82.550614 -445.665166)
			(xy 82.503064 -445.701653) (xy 82.451158 -445.73162) (xy 82.395785 -445.754556) (xy 82.337892 -445.770069)
			(xy 82.27847 -445.777892) (xy 82.218534 -445.777892) (xy 82.159112 -445.770069) (xy 82.101219 -445.754556)
			(xy 82.045846 -445.73162) (xy 81.99394 -445.701653) (xy 81.94639 -445.665166) (xy 81.90401 -445.622786)
			(xy 81.867523 -445.575236) (xy 81.837556 -445.52333) (xy 81.81462 -445.467957) (xy 81.799107 -445.410064)
			(xy 81.791284 -445.350642) (xy 39.077896 -445.350642) (xy 39.754556 -446.027302) (xy 39.754556 -450.176646)
			(xy 39.755037 -450.198878) (xy 39.762817 -450.242658) (xy 39.778096 -450.284416) (xy 39.800409 -450.322879)
			(xy 39.829074 -450.356871) (xy 39.863217 -450.385358) (xy 39.901796 -450.407468) (xy 39.943633 -450.422528)
			(xy 39.987453 -450.430078) (xy 40.031919 -450.429887) (xy 40.075672 -450.421962) (xy 40.11738 -450.406545)
			(xy 40.155768 -450.384105) (xy 40.189665 -450.355327) (xy 40.204136 -450.338444) (xy 40.240984 -450.29466)
			(xy 40.319765 -450.211643) (xy 40.404009 -450.134175) (xy 40.493327 -450.062617) (xy 40.587306 -449.9973)
			(xy 40.685509 -449.938526) (xy 40.787483 -449.886568) (xy 40.892754 -449.841665) (xy 41.000836 -449.804026)
			(xy 41.111227 -449.773826) (xy 41.223417 -449.751204) (xy 41.336885 -449.736265) (xy 41.451107 -449.729078)
			(xy 41.565554 -449.729677) (xy 41.679694 -449.738058) (xy 41.793 -449.754183) (xy 41.904947 -449.777977)
			(xy 42.015016 -449.809331) (xy 42.122698 -449.848098) (xy 42.227494 -449.894099) (xy 42.328919 -449.947121)
			(xy 42.426502 -450.006919) (xy 42.501279 -450.06006) (xy 63.647577 -450.06006) (xy 63.651612 -449.984356)
			(xy 63.663671 -449.909511) (xy 63.683617 -449.83637) (xy 63.711224 -449.765765) (xy 63.74618 -449.698494)
			(xy 63.788088 -449.635319) (xy 63.836474 -449.576957) (xy 63.89079 -449.524069) (xy 63.950419 -449.477254)
			(xy 64.014687 -449.437042) (xy 64.082864 -449.40389) (xy 64.15418 -449.378172) (xy 64.227825 -449.36018)
			(xy 64.302965 -449.350118) (xy 64.378749 -449.348099) (xy 64.454319 -449.354148) (xy 64.528817 -449.368195)
			(xy 64.6014 -449.390081) (xy 64.671246 -449.419558) (xy 64.737563 -449.456293) (xy 64.799599 -449.499868)
			(xy 64.856652 -449.54979) (xy 64.908076 -449.605494) (xy 64.953287 -449.666349) (xy 64.991774 -449.731664)
			(xy 65.0231 -449.8007) (xy 65.04691 -449.872675) (xy 65.062935 -449.946773) (xy 65.070994 -450.022154)
			(xy 65.071498 -450.06006) (xy 66.187577 -450.06006) (xy 66.191612 -449.984356) (xy 66.203671 -449.909511)
			(xy 66.223617 -449.83637) (xy 66.251224 -449.765765) (xy 66.28618 -449.698494) (xy 66.328088 -449.635319)
			(xy 66.376474 -449.576957) (xy 66.43079 -449.524069) (xy 66.490419 -449.477254) (xy 66.554687 -449.437042)
			(xy 66.622864 -449.40389) (xy 66.69418 -449.378172) (xy 66.767825 -449.36018) (xy 66.842965 -449.350118)
			(xy 66.918749 -449.348099) (xy 66.994319 -449.354148) (xy 67.068817 -449.368195) (xy 67.1414 -449.390081)
			(xy 67.211246 -449.419558) (xy 67.277563 -449.456293) (xy 67.339599 -449.499868) (xy 67.396652 -449.54979)
			(xy 67.448076 -449.605494) (xy 67.493287 -449.666349) (xy 67.531774 -449.731664) (xy 67.5631 -449.8007)
			(xy 67.58691 -449.872675) (xy 67.602935 -449.946773) (xy 67.610994 -450.022154) (xy 67.611498 -450.06006)
			(xy 68.727577 -450.06006) (xy 68.731612 -449.984356) (xy 68.743671 -449.909511) (xy 68.763617 -449.83637)
			(xy 68.791224 -449.765765) (xy 68.82618 -449.698494) (xy 68.868088 -449.635319) (xy 68.916474 -449.576957)
			(xy 68.97079 -449.524069) (xy 69.030419 -449.477254) (xy 69.094687 -449.437042) (xy 69.162864 -449.40389)
			(xy 69.23418 -449.378172) (xy 69.307825 -449.36018) (xy 69.382965 -449.350118) (xy 69.458749 -449.348099)
			(xy 69.534319 -449.354148) (xy 69.608817 -449.368195) (xy 69.6814 -449.390081) (xy 69.751246 -449.419558)
			(xy 69.817563 -449.456293) (xy 69.879599 -449.499868) (xy 69.936652 -449.54979) (xy 69.988076 -449.605494)
			(xy 70.033287 -449.666349) (xy 70.071774 -449.731664) (xy 70.1031 -449.8007) (xy 70.12691 -449.872675)
			(xy 70.142935 -449.946773) (xy 70.150994 -450.022154) (xy 70.151498 -450.06006) (xy 71.267577 -450.06006)
			(xy 71.271612 -449.984356) (xy 71.283671 -449.909511) (xy 71.303617 -449.83637) (xy 71.331224 -449.765765)
			(xy 71.36618 -449.698494) (xy 71.408088 -449.635319) (xy 71.456474 -449.576957) (xy 71.51079 -449.524069)
			(xy 71.570419 -449.477254) (xy 71.634687 -449.437042) (xy 71.702864 -449.40389) (xy 71.77418 -449.378172)
			(xy 71.847825 -449.36018) (xy 71.922965 -449.350118) (xy 71.998749 -449.348099) (xy 72.074319 -449.354148)
			(xy 72.148817 -449.368195) (xy 72.2214 -449.390081) (xy 72.291246 -449.419558) (xy 72.357563 -449.456293)
			(xy 72.419599 -449.499868) (xy 72.476652 -449.54979) (xy 72.528076 -449.605494) (xy 72.573287 -449.666349)
			(xy 72.611774 -449.731664) (xy 72.6431 -449.8007) (xy 72.66691 -449.872675) (xy 72.682935 -449.946773)
			(xy 72.690994 -450.022154) (xy 72.691498 -450.06006) (xy 73.807577 -450.06006) (xy 73.811612 -449.984356)
			(xy 73.823671 -449.909511) (xy 73.843617 -449.83637) (xy 73.871224 -449.765765) (xy 73.90618 -449.698494)
			(xy 73.948088 -449.635319) (xy 73.996474 -449.576957) (xy 74.05079 -449.524069) (xy 74.110419 -449.477254)
			(xy 74.174687 -449.437042) (xy 74.242864 -449.40389) (xy 74.31418 -449.378172) (xy 74.387825 -449.36018)
			(xy 74.462965 -449.350118) (xy 74.538749 -449.348099) (xy 74.614319 -449.354148) (xy 74.688817 -449.368195)
			(xy 74.7614 -449.390081) (xy 74.831246 -449.419558) (xy 74.897563 -449.456293) (xy 74.959599 -449.499868)
			(xy 75.016652 -449.54979) (xy 75.068076 -449.605494) (xy 75.113287 -449.666349) (xy 75.151774 -449.731664)
			(xy 75.1831 -449.8007) (xy 75.20691 -449.872675) (xy 75.222935 -449.946773) (xy 75.230994 -450.022154)
			(xy 75.231498 -450.06006) (xy 76.347577 -450.06006) (xy 76.351612 -449.984356) (xy 76.363671 -449.909511)
			(xy 76.383617 -449.83637) (xy 76.411224 -449.765765) (xy 76.44618 -449.698494) (xy 76.488088 -449.635319)
			(xy 76.536474 -449.576957) (xy 76.59079 -449.524069) (xy 76.650419 -449.477254) (xy 76.714687 -449.437042)
			(xy 76.782864 -449.40389) (xy 76.85418 -449.378172) (xy 76.927825 -449.36018) (xy 77.002965 -449.350118)
			(xy 77.078749 -449.348099) (xy 77.154319 -449.354148) (xy 77.228817 -449.368195) (xy 77.3014 -449.390081)
			(xy 77.371246 -449.419558) (xy 77.437563 -449.456293) (xy 77.499599 -449.499868) (xy 77.556652 -449.54979)
			(xy 77.608076 -449.605494) (xy 77.653287 -449.666349) (xy 77.691774 -449.731664) (xy 77.7231 -449.8007)
			(xy 77.74691 -449.872675) (xy 77.762935 -449.946773) (xy 77.770994 -450.022154) (xy 77.771498 -450.06006)
			(xy 78.887577 -450.06006) (xy 78.891612 -449.984356) (xy 78.903671 -449.909511) (xy 78.923617 -449.83637)
			(xy 78.951224 -449.765765) (xy 78.98618 -449.698494) (xy 79.028088 -449.635319) (xy 79.076474 -449.576957)
			(xy 79.13079 -449.524069) (xy 79.190419 -449.477254) (xy 79.254687 -449.437042) (xy 79.322864 -449.40389)
			(xy 79.39418 -449.378172) (xy 79.467825 -449.36018) (xy 79.542965 -449.350118) (xy 79.618749 -449.348099)
			(xy 79.694319 -449.354148) (xy 79.768817 -449.368195) (xy 79.8414 -449.390081) (xy 79.911246 -449.419558)
			(xy 79.977563 -449.456293) (xy 80.039599 -449.499868) (xy 80.096652 -449.54979) (xy 80.148076 -449.605494)
			(xy 80.193287 -449.666349) (xy 80.231774 -449.731664) (xy 80.2631 -449.8007) (xy 80.28691 -449.872675)
			(xy 80.302935 -449.946773) (xy 80.310994 -450.022154) (xy 80.311498 -450.06006) (xy 81.427577 -450.06006)
			(xy 81.431612 -449.984356) (xy 81.443671 -449.909511) (xy 81.463617 -449.83637) (xy 81.491224 -449.765765)
			(xy 81.52618 -449.698494) (xy 81.568088 -449.635319) (xy 81.616474 -449.576957) (xy 81.67079 -449.524069)
			(xy 81.730419 -449.477254) (xy 81.794687 -449.437042) (xy 81.862864 -449.40389) (xy 81.93418 -449.378172)
			(xy 82.007825 -449.36018) (xy 82.082965 -449.350118) (xy 82.158749 -449.348099) (xy 82.234319 -449.354148)
			(xy 82.308817 -449.368195) (xy 82.3814 -449.390081) (xy 82.451246 -449.419558) (xy 82.517563 -449.456293)
			(xy 82.579599 -449.499868) (xy 82.585544 -449.50507) (xy 86.197697 -449.50507) (xy 86.201732 -449.429366)
			(xy 86.213791 -449.354521) (xy 86.233737 -449.28138) (xy 86.261344 -449.210775) (xy 86.2963 -449.143504)
			(xy 86.338208 -449.080329) (xy 86.386594 -449.021967) (xy 86.44091 -448.969079) (xy 86.500539 -448.922264)
			(xy 86.564807 -448.882052) (xy 86.632984 -448.8489) (xy 86.7043 -448.823182) (xy 86.777945 -448.80519)
			(xy 86.853085 -448.795128) (xy 86.928869 -448.793109) (xy 87.004439 -448.799158) (xy 87.078937 -448.813205)
			(xy 87.15152 -448.835091) (xy 87.221366 -448.864568) (xy 87.287683 -448.901303) (xy 87.349719 -448.944878)
			(xy 87.406772 -448.9948) (xy 87.458196 -449.050504) (xy 87.503407 -449.111359) (xy 87.541894 -449.176674)
			(xy 87.57322 -449.24571) (xy 87.59703 -449.317685) (xy 87.613055 -449.391783) (xy 87.621114 -449.467164)
			(xy 87.621618 -449.50507) (xy 87.621114 -449.542976) (xy 87.613055 -449.618357) (xy 87.59703 -449.692455)
			(xy 87.57322 -449.76443) (xy 87.541894 -449.833466) (xy 87.503407 -449.898781) (xy 87.458196 -449.959636)
			(xy 87.406772 -450.01534) (xy 87.349719 -450.065262) (xy 87.287683 -450.108837) (xy 87.221366 -450.145572)
			(xy 87.15152 -450.175049) (xy 87.078937 -450.196935) (xy 87.004439 -450.210982) (xy 86.928869 -450.217031)
			(xy 86.853085 -450.215012) (xy 86.777945 -450.20495) (xy 86.7043 -450.186958) (xy 86.632984 -450.16124)
			(xy 86.564807 -450.128088) (xy 86.500539 -450.087876) (xy 86.44091 -450.041061) (xy 86.386594 -449.988173)
			(xy 86.338208 -449.929811) (xy 86.2963 -449.866636) (xy 86.261344 -449.799365) (xy 86.233737 -449.72876)
			(xy 86.213791 -449.655619) (xy 86.201732 -449.580774) (xy 86.197697 -449.50507) (xy 82.585544 -449.50507)
			(xy 82.636652 -449.54979) (xy 82.688076 -449.605494) (xy 82.733287 -449.666349) (xy 82.771774 -449.731664)
			(xy 82.8031 -449.8007) (xy 82.82691 -449.872675) (xy 82.842935 -449.946773) (xy 82.850994 -450.022154)
			(xy 82.851498 -450.06006) (xy 82.850994 -450.097966) (xy 82.842935 -450.173347) (xy 82.82691 -450.247445)
			(xy 82.8031 -450.31942) (xy 82.771774 -450.388456) (xy 82.733287 -450.453771) (xy 82.688076 -450.514626)
			(xy 82.636652 -450.57033) (xy 82.579599 -450.620252) (xy 82.517563 -450.663827) (xy 82.451246 -450.700562)
			(xy 82.3814 -450.730039) (xy 82.308817 -450.751925) (xy 82.234319 -450.765972) (xy 82.158749 -450.772021)
			(xy 82.082965 -450.770002) (xy 82.007825 -450.75994) (xy 81.93418 -450.741948) (xy 81.862864 -450.71623)
			(xy 81.794687 -450.683078) (xy 81.730419 -450.642866) (xy 81.67079 -450.596051) (xy 81.616474 -450.543163)
			(xy 81.568088 -450.484801) (xy 81.52618 -450.421626) (xy 81.491224 -450.354355) (xy 81.463617 -450.28375)
			(xy 81.443671 -450.210609) (xy 81.431612 -450.135764) (xy 81.427577 -450.06006) (xy 80.311498 -450.06006)
			(xy 80.310994 -450.097966) (xy 80.302935 -450.173347) (xy 80.28691 -450.247445) (xy 80.2631 -450.31942)
			(xy 80.231774 -450.388456) (xy 80.193287 -450.453771) (xy 80.148076 -450.514626) (xy 80.096652 -450.57033)
			(xy 80.039599 -450.620252) (xy 79.977563 -450.663827) (xy 79.911246 -450.700562) (xy 79.8414 -450.730039)
			(xy 79.768817 -450.751925) (xy 79.694319 -450.765972) (xy 79.618749 -450.772021) (xy 79.542965 -450.770002)
			(xy 79.467825 -450.75994) (xy 79.39418 -450.741948) (xy 79.322864 -450.71623) (xy 79.254687 -450.683078)
			(xy 79.190419 -450.642866) (xy 79.13079 -450.596051) (xy 79.076474 -450.543163) (xy 79.028088 -450.484801)
			(xy 78.98618 -450.421626) (xy 78.951224 -450.354355) (xy 78.923617 -450.28375) (xy 78.903671 -450.210609)
			(xy 78.891612 -450.135764) (xy 78.887577 -450.06006) (xy 77.771498 -450.06006) (xy 77.770994 -450.097966)
			(xy 77.762935 -450.173347) (xy 77.74691 -450.247445) (xy 77.7231 -450.31942) (xy 77.691774 -450.388456)
			(xy 77.653287 -450.453771) (xy 77.608076 -450.514626) (xy 77.556652 -450.57033) (xy 77.499599 -450.620252)
			(xy 77.437563 -450.663827) (xy 77.371246 -450.700562) (xy 77.3014 -450.730039) (xy 77.228817 -450.751925)
			(xy 77.154319 -450.765972) (xy 77.078749 -450.772021) (xy 77.002965 -450.770002) (xy 76.927825 -450.75994)
			(xy 76.85418 -450.741948) (xy 76.782864 -450.71623) (xy 76.714687 -450.683078) (xy 76.650419 -450.642866)
			(xy 76.59079 -450.596051) (xy 76.536474 -450.543163) (xy 76.488088 -450.484801) (xy 76.44618 -450.421626)
			(xy 76.411224 -450.354355) (xy 76.383617 -450.28375) (xy 76.363671 -450.210609) (xy 76.351612 -450.135764)
			(xy 76.347577 -450.06006) (xy 75.231498 -450.06006) (xy 75.230994 -450.097966) (xy 75.222935 -450.173347)
			(xy 75.20691 -450.247445) (xy 75.1831 -450.31942) (xy 75.151774 -450.388456) (xy 75.113287 -450.453771)
			(xy 75.068076 -450.514626) (xy 75.016652 -450.57033) (xy 74.959599 -450.620252) (xy 74.897563 -450.663827)
			(xy 74.831246 -450.700562) (xy 74.7614 -450.730039) (xy 74.688817 -450.751925) (xy 74.614319 -450.765972)
			(xy 74.538749 -450.772021) (xy 74.462965 -450.770002) (xy 74.387825 -450.75994) (xy 74.31418 -450.741948)
			(xy 74.242864 -450.71623) (xy 74.174687 -450.683078) (xy 74.110419 -450.642866) (xy 74.05079 -450.596051)
			(xy 73.996474 -450.543163) (xy 73.948088 -450.484801) (xy 73.90618 -450.421626) (xy 73.871224 -450.354355)
			(xy 73.843617 -450.28375) (xy 73.823671 -450.210609) (xy 73.811612 -450.135764) (xy 73.807577 -450.06006)
			(xy 72.691498 -450.06006) (xy 72.690994 -450.097966) (xy 72.682935 -450.173347) (xy 72.66691 -450.247445)
			(xy 72.6431 -450.31942) (xy 72.611774 -450.388456) (xy 72.573287 -450.453771) (xy 72.528076 -450.514626)
			(xy 72.476652 -450.57033) (xy 72.419599 -450.620252) (xy 72.357563 -450.663827) (xy 72.291246 -450.700562)
			(xy 72.2214 -450.730039) (xy 72.148817 -450.751925) (xy 72.074319 -450.765972) (xy 71.998749 -450.772021)
			(xy 71.922965 -450.770002) (xy 71.847825 -450.75994) (xy 71.77418 -450.741948) (xy 71.702864 -450.71623)
			(xy 71.634687 -450.683078) (xy 71.570419 -450.642866) (xy 71.51079 -450.596051) (xy 71.456474 -450.543163)
			(xy 71.408088 -450.484801) (xy 71.36618 -450.421626) (xy 71.331224 -450.354355) (xy 71.303617 -450.28375)
			(xy 71.283671 -450.210609) (xy 71.271612 -450.135764) (xy 71.267577 -450.06006) (xy 70.151498 -450.06006)
			(xy 70.150994 -450.097966) (xy 70.142935 -450.173347) (xy 70.12691 -450.247445) (xy 70.1031 -450.31942)
			(xy 70.071774 -450.388456) (xy 70.033287 -450.453771) (xy 69.988076 -450.514626) (xy 69.936652 -450.57033)
			(xy 69.879599 -450.620252) (xy 69.817563 -450.663827) (xy 69.751246 -450.700562) (xy 69.6814 -450.730039)
			(xy 69.608817 -450.751925) (xy 69.534319 -450.765972) (xy 69.458749 -450.772021) (xy 69.382965 -450.770002)
			(xy 69.307825 -450.75994) (xy 69.23418 -450.741948) (xy 69.162864 -450.71623) (xy 69.094687 -450.683078)
			(xy 69.030419 -450.642866) (xy 68.97079 -450.596051) (xy 68.916474 -450.543163) (xy 68.868088 -450.484801)
			(xy 68.82618 -450.421626) (xy 68.791224 -450.354355) (xy 68.763617 -450.28375) (xy 68.743671 -450.210609)
			(xy 68.731612 -450.135764) (xy 68.727577 -450.06006) (xy 67.611498 -450.06006) (xy 67.610994 -450.097966)
			(xy 67.602935 -450.173347) (xy 67.58691 -450.247445) (xy 67.5631 -450.31942) (xy 67.531774 -450.388456)
			(xy 67.493287 -450.453771) (xy 67.448076 -450.514626) (xy 67.396652 -450.57033) (xy 67.339599 -450.620252)
			(xy 67.277563 -450.663827) (xy 67.211246 -450.700562) (xy 67.1414 -450.730039) (xy 67.068817 -450.751925)
			(xy 66.994319 -450.765972) (xy 66.918749 -450.772021) (xy 66.842965 -450.770002) (xy 66.767825 -450.75994)
			(xy 66.69418 -450.741948) (xy 66.622864 -450.71623) (xy 66.554687 -450.683078) (xy 66.490419 -450.642866)
			(xy 66.43079 -450.596051) (xy 66.376474 -450.543163) (xy 66.328088 -450.484801) (xy 66.28618 -450.421626)
			(xy 66.251224 -450.354355) (xy 66.223617 -450.28375) (xy 66.203671 -450.210609) (xy 66.191612 -450.135764)
			(xy 66.187577 -450.06006) (xy 65.071498 -450.06006) (xy 65.070994 -450.097966) (xy 65.062935 -450.173347)
			(xy 65.04691 -450.247445) (xy 65.0231 -450.31942) (xy 64.991774 -450.388456) (xy 64.953287 -450.453771)
			(xy 64.908076 -450.514626) (xy 64.856652 -450.57033) (xy 64.799599 -450.620252) (xy 64.737563 -450.663827)
			(xy 64.671246 -450.700562) (xy 64.6014 -450.730039) (xy 64.528817 -450.751925) (xy 64.454319 -450.765972)
			(xy 64.378749 -450.772021) (xy 64.302965 -450.770002) (xy 64.227825 -450.75994) (xy 64.15418 -450.741948)
			(xy 64.082864 -450.71623) (xy 64.014687 -450.683078) (xy 63.950419 -450.642866) (xy 63.89079 -450.596051)
			(xy 63.836474 -450.543163) (xy 63.788088 -450.484801) (xy 63.74618 -450.421626) (xy 63.711224 -450.354355)
			(xy 63.683617 -450.28375) (xy 63.663671 -450.210609) (xy 63.651612 -450.135764) (xy 63.647577 -450.06006)
			(xy 42.501279 -450.06006) (xy 42.519792 -450.073216) (xy 42.608357 -450.145704) (xy 42.691787 -450.224049)
			(xy 42.769694 -450.307886) (xy 42.84172 -450.396828) (xy 42.907528 -450.490463) (xy 42.966816 -450.588357)
			(xy 43.019309 -450.690056) (xy 43.056099 -450.77507) (xy 84.927697 -450.77507) (xy 84.931732 -450.699366)
			(xy 84.943791 -450.624521) (xy 84.963737 -450.55138) (xy 84.991344 -450.480775) (xy 85.0263 -450.413504)
			(xy 85.068208 -450.350329) (xy 85.116594 -450.291967) (xy 85.17091 -450.239079) (xy 85.230539 -450.192264)
			(xy 85.294807 -450.152052) (xy 85.362984 -450.1189) (xy 85.4343 -450.093182) (xy 85.507945 -450.07519)
			(xy 85.583085 -450.065128) (xy 85.658869 -450.063109) (xy 85.734439 -450.069158) (xy 85.808937 -450.083205)
			(xy 85.88152 -450.105091) (xy 85.951366 -450.134568) (xy 86.017683 -450.171303) (xy 86.079719 -450.214878)
			(xy 86.136772 -450.2648) (xy 86.188196 -450.320504) (xy 86.233407 -450.381359) (xy 86.271894 -450.446674)
			(xy 86.30322 -450.51571) (xy 86.32703 -450.587685) (xy 86.343055 -450.661783) (xy 86.351114 -450.737164)
			(xy 86.351618 -450.77507) (xy 86.351114 -450.812976) (xy 86.343055 -450.888357) (xy 86.32703 -450.962455)
			(xy 86.30322 -451.03443) (xy 86.271894 -451.103466) (xy 86.233407 -451.168781) (xy 86.188196 -451.229636)
			(xy 86.136772 -451.28534) (xy 86.079719 -451.335262) (xy 86.017683 -451.378837) (xy 85.951366 -451.415572)
			(xy 85.88152 -451.445049) (xy 85.808937 -451.466935) (xy 85.734439 -451.480982) (xy 85.658869 -451.487031)
			(xy 85.583085 -451.485012) (xy 85.507945 -451.47495) (xy 85.4343 -451.456958) (xy 85.362984 -451.43124)
			(xy 85.294807 -451.398088) (xy 85.230539 -451.357876) (xy 85.17091 -451.311061) (xy 85.116594 -451.258173)
			(xy 85.068208 -451.199811) (xy 85.0263 -451.136636) (xy 84.991344 -451.069365) (xy 84.963737 -450.99876)
			(xy 84.943791 -450.925619) (xy 84.931732 -450.850774) (xy 84.927697 -450.77507) (xy 43.056099 -450.77507)
			(xy 43.064763 -450.795091) (xy 43.102967 -450.902974) (xy 43.133746 -451.013205) (xy 43.156956 -451.125275)
			(xy 43.172489 -451.238663) (xy 43.180275 -451.352846) (xy 43.180762 -451.41007) (xy 43.180574 -451.443253)
			(xy 43.177908 -451.509567) (xy 43.175428 -451.542658) (xy 43.170294 -451.601071) (xy 43.152917 -451.717048)
			(xy 43.127501 -451.831533) (xy 43.094167 -451.943968) (xy 43.056346 -452.04507) (xy 86.197697 -452.04507)
			(xy 86.201732 -451.969366) (xy 86.213791 -451.894521) (xy 86.233737 -451.82138) (xy 86.261344 -451.750775)
			(xy 86.2963 -451.683504) (xy 86.338208 -451.620329) (xy 86.386594 -451.561967) (xy 86.44091 -451.509079)
			(xy 86.500539 -451.462264) (xy 86.564807 -451.422052) (xy 86.632984 -451.3889) (xy 86.7043 -451.363182)
			(xy 86.777945 -451.34519) (xy 86.853085 -451.335128) (xy 86.928869 -451.333109) (xy 87.004439 -451.339158)
			(xy 87.078937 -451.353205) (xy 87.15152 -451.375091) (xy 87.221366 -451.404568) (xy 87.287683 -451.441303)
			(xy 87.349719 -451.484878) (xy 87.406772 -451.5348) (xy 87.458196 -451.590504) (xy 87.503407 -451.651359)
			(xy 87.541894 -451.716674) (xy 87.57322 -451.78571) (xy 87.59703 -451.857685) (xy 87.613055 -451.931783)
			(xy 87.621114 -452.007164) (xy 87.621618 -452.04507) (xy 87.621114 -452.082976) (xy 87.613055 -452.158357)
			(xy 87.59703 -452.232455) (xy 87.57322 -452.30443) (xy 87.541894 -452.373466) (xy 87.503407 -452.438781)
			(xy 87.458196 -452.499636) (xy 87.406772 -452.55534) (xy 87.349719 -452.605262) (xy 87.287683 -452.648837)
			(xy 87.221366 -452.685572) (xy 87.15152 -452.715049) (xy 87.078937 -452.736935) (xy 87.004439 -452.750982)
			(xy 86.928869 -452.757031) (xy 86.853085 -452.755012) (xy 86.777945 -452.74495) (xy 86.7043 -452.726958)
			(xy 86.632984 -452.70124) (xy 86.564807 -452.668088) (xy 86.500539 -452.627876) (xy 86.44091 -452.581061)
			(xy 86.386594 -452.528173) (xy 86.338208 -452.469811) (xy 86.2963 -452.406636) (xy 86.261344 -452.339365)
			(xy 86.233737 -452.26876) (xy 86.213791 -452.195619) (xy 86.201732 -452.120774) (xy 86.197697 -452.04507)
			(xy 43.056346 -452.04507) (xy 43.053078 -452.053806) (xy 43.004435 -452.160513) (xy 42.948473 -452.263572)
			(xy 42.885466 -452.362479) (xy 42.815718 -452.456755) (xy 42.739569 -452.545941) (xy 42.657391 -452.629603)
			(xy 42.569581 -452.707335) (xy 42.500891 -452.76008) (xy 63.647577 -452.76008) (xy 63.651612 -452.684376)
			(xy 63.663671 -452.609531) (xy 63.683617 -452.53639) (xy 63.711224 -452.465785) (xy 63.74618 -452.398514)
			(xy 63.788088 -452.335339) (xy 63.836474 -452.276977) (xy 63.89079 -452.224089) (xy 63.950419 -452.177274)
			(xy 64.014687 -452.137062) (xy 64.082864 -452.10391) (xy 64.15418 -452.078192) (xy 64.227825 -452.0602)
			(xy 64.302965 -452.050138) (xy 64.378749 -452.048119) (xy 64.454319 -452.054168) (xy 64.528817 -452.068215)
			(xy 64.6014 -452.090101) (xy 64.671246 -452.119578) (xy 64.737563 -452.156313) (xy 64.799599 -452.199888)
			(xy 64.856652 -452.24981) (xy 64.908076 -452.305514) (xy 64.953287 -452.366369) (xy 64.991774 -452.431684)
			(xy 65.0231 -452.50072) (xy 65.04691 -452.572695) (xy 65.062935 -452.646793) (xy 65.070994 -452.722174)
			(xy 65.071498 -452.76008) (xy 66.187577 -452.76008) (xy 66.191612 -452.684376) (xy 66.203671 -452.609531)
			(xy 66.223617 -452.53639) (xy 66.251224 -452.465785) (xy 66.28618 -452.398514) (xy 66.328088 -452.335339)
			(xy 66.376474 -452.276977) (xy 66.43079 -452.224089) (xy 66.490419 -452.177274) (xy 66.554687 -452.137062)
			(xy 66.622864 -452.10391) (xy 66.69418 -452.078192) (xy 66.767825 -452.0602) (xy 66.842965 -452.050138)
			(xy 66.918749 -452.048119) (xy 66.994319 -452.054168) (xy 67.068817 -452.068215) (xy 67.1414 -452.090101)
			(xy 67.211246 -452.119578) (xy 67.277563 -452.156313) (xy 67.339599 -452.199888) (xy 67.396652 -452.24981)
			(xy 67.448076 -452.305514) (xy 67.493287 -452.366369) (xy 67.531774 -452.431684) (xy 67.5631 -452.50072)
			(xy 67.58691 -452.572695) (xy 67.602935 -452.646793) (xy 67.610994 -452.722174) (xy 67.611498 -452.76008)
			(xy 68.727577 -452.76008) (xy 68.731612 -452.684376) (xy 68.743671 -452.609531) (xy 68.763617 -452.53639)
			(xy 68.791224 -452.465785) (xy 68.82618 -452.398514) (xy 68.868088 -452.335339) (xy 68.916474 -452.276977)
			(xy 68.97079 -452.224089) (xy 69.030419 -452.177274) (xy 69.094687 -452.137062) (xy 69.162864 -452.10391)
			(xy 69.23418 -452.078192) (xy 69.307825 -452.0602) (xy 69.382965 -452.050138) (xy 69.458749 -452.048119)
			(xy 69.534319 -452.054168) (xy 69.608817 -452.068215) (xy 69.6814 -452.090101) (xy 69.751246 -452.119578)
			(xy 69.817563 -452.156313) (xy 69.879599 -452.199888) (xy 69.936652 -452.24981) (xy 69.988076 -452.305514)
			(xy 70.033287 -452.366369) (xy 70.071774 -452.431684) (xy 70.1031 -452.50072) (xy 70.12691 -452.572695)
			(xy 70.142935 -452.646793) (xy 70.150994 -452.722174) (xy 70.151498 -452.76008) (xy 71.267577 -452.76008)
			(xy 71.271612 -452.684376) (xy 71.283671 -452.609531) (xy 71.303617 -452.53639) (xy 71.331224 -452.465785)
			(xy 71.36618 -452.398514) (xy 71.408088 -452.335339) (xy 71.456474 -452.276977) (xy 71.51079 -452.224089)
			(xy 71.570419 -452.177274) (xy 71.634687 -452.137062) (xy 71.702864 -452.10391) (xy 71.77418 -452.078192)
			(xy 71.847825 -452.0602) (xy 71.922965 -452.050138) (xy 71.998749 -452.048119) (xy 72.074319 -452.054168)
			(xy 72.148817 -452.068215) (xy 72.2214 -452.090101) (xy 72.291246 -452.119578) (xy 72.357563 -452.156313)
			(xy 72.419599 -452.199888) (xy 72.476652 -452.24981) (xy 72.528076 -452.305514) (xy 72.573287 -452.366369)
			(xy 72.611774 -452.431684) (xy 72.6431 -452.50072) (xy 72.66691 -452.572695) (xy 72.682935 -452.646793)
			(xy 72.690994 -452.722174) (xy 72.691498 -452.76008) (xy 73.807577 -452.76008) (xy 73.811612 -452.684376)
			(xy 73.823671 -452.609531) (xy 73.843617 -452.53639) (xy 73.871224 -452.465785) (xy 73.90618 -452.398514)
			(xy 73.948088 -452.335339) (xy 73.996474 -452.276977) (xy 74.05079 -452.224089) (xy 74.110419 -452.177274)
			(xy 74.174687 -452.137062) (xy 74.242864 -452.10391) (xy 74.31418 -452.078192) (xy 74.387825 -452.0602)
			(xy 74.462965 -452.050138) (xy 74.538749 -452.048119) (xy 74.614319 -452.054168) (xy 74.688817 -452.068215)
			(xy 74.7614 -452.090101) (xy 74.831246 -452.119578) (xy 74.897563 -452.156313) (xy 74.959599 -452.199888)
			(xy 75.016652 -452.24981) (xy 75.068076 -452.305514) (xy 75.113287 -452.366369) (xy 75.151774 -452.431684)
			(xy 75.1831 -452.50072) (xy 75.20691 -452.572695) (xy 75.222935 -452.646793) (xy 75.230994 -452.722174)
			(xy 75.231498 -452.76008) (xy 76.347577 -452.76008) (xy 76.351612 -452.684376) (xy 76.363671 -452.609531)
			(xy 76.383617 -452.53639) (xy 76.411224 -452.465785) (xy 76.44618 -452.398514) (xy 76.488088 -452.335339)
			(xy 76.536474 -452.276977) (xy 76.59079 -452.224089) (xy 76.650419 -452.177274) (xy 76.714687 -452.137062)
			(xy 76.782864 -452.10391) (xy 76.85418 -452.078192) (xy 76.927825 -452.0602) (xy 77.002965 -452.050138)
			(xy 77.078749 -452.048119) (xy 77.154319 -452.054168) (xy 77.228817 -452.068215) (xy 77.3014 -452.090101)
			(xy 77.371246 -452.119578) (xy 77.437563 -452.156313) (xy 77.499599 -452.199888) (xy 77.556652 -452.24981)
			(xy 77.608076 -452.305514) (xy 77.653287 -452.366369) (xy 77.691774 -452.431684) (xy 77.7231 -452.50072)
			(xy 77.74691 -452.572695) (xy 77.762935 -452.646793) (xy 77.770994 -452.722174) (xy 77.771498 -452.76008)
			(xy 78.887577 -452.76008) (xy 78.891612 -452.684376) (xy 78.903671 -452.609531) (xy 78.923617 -452.53639)
			(xy 78.951224 -452.465785) (xy 78.98618 -452.398514) (xy 79.028088 -452.335339) (xy 79.076474 -452.276977)
			(xy 79.13079 -452.224089) (xy 79.190419 -452.177274) (xy 79.254687 -452.137062) (xy 79.322864 -452.10391)
			(xy 79.39418 -452.078192) (xy 79.467825 -452.0602) (xy 79.542965 -452.050138) (xy 79.618749 -452.048119)
			(xy 79.694319 -452.054168) (xy 79.768817 -452.068215) (xy 79.8414 -452.090101) (xy 79.911246 -452.119578)
			(xy 79.977563 -452.156313) (xy 80.039599 -452.199888) (xy 80.096652 -452.24981) (xy 80.148076 -452.305514)
			(xy 80.193287 -452.366369) (xy 80.231774 -452.431684) (xy 80.2631 -452.50072) (xy 80.28691 -452.572695)
			(xy 80.302935 -452.646793) (xy 80.310994 -452.722174) (xy 80.311498 -452.76008) (xy 81.427577 -452.76008)
			(xy 81.431612 -452.684376) (xy 81.443671 -452.609531) (xy 81.463617 -452.53639) (xy 81.491224 -452.465785)
			(xy 81.52618 -452.398514) (xy 81.568088 -452.335339) (xy 81.616474 -452.276977) (xy 81.67079 -452.224089)
			(xy 81.730419 -452.177274) (xy 81.794687 -452.137062) (xy 81.862864 -452.10391) (xy 81.93418 -452.078192)
			(xy 82.007825 -452.0602) (xy 82.082965 -452.050138) (xy 82.158749 -452.048119) (xy 82.234319 -452.054168)
			(xy 82.308817 -452.068215) (xy 82.3814 -452.090101) (xy 82.451246 -452.119578) (xy 82.517563 -452.156313)
			(xy 82.579599 -452.199888) (xy 82.636652 -452.24981) (xy 82.688076 -452.305514) (xy 82.733287 -452.366369)
			(xy 82.771774 -452.431684) (xy 82.8031 -452.50072) (xy 82.82691 -452.572695) (xy 82.842935 -452.646793)
			(xy 82.850994 -452.722174) (xy 82.851498 -452.76008) (xy 82.850994 -452.797986) (xy 82.842935 -452.873367)
			(xy 82.82691 -452.947465) (xy 82.8031 -453.01944) (xy 82.771774 -453.088476) (xy 82.733287 -453.153791)
			(xy 82.688076 -453.214646) (xy 82.636652 -453.27035) (xy 82.585544 -453.31507) (xy 84.927697 -453.31507)
			(xy 84.931732 -453.239366) (xy 84.943791 -453.164521) (xy 84.963737 -453.09138) (xy 84.991344 -453.020775)
			(xy 85.0263 -452.953504) (xy 85.068208 -452.890329) (xy 85.116594 -452.831967) (xy 85.17091 -452.779079)
			(xy 85.230539 -452.732264) (xy 85.294807 -452.692052) (xy 85.362984 -452.6589) (xy 85.4343 -452.633182)
			(xy 85.507945 -452.61519) (xy 85.583085 -452.605128) (xy 85.658869 -452.603109) (xy 85.734439 -452.609158)
			(xy 85.808937 -452.623205) (xy 85.88152 -452.645091) (xy 85.951366 -452.674568) (xy 86.017683 -452.711303)
			(xy 86.079719 -452.754878) (xy 86.136772 -452.8048) (xy 86.188196 -452.860504) (xy 86.233407 -452.921359)
			(xy 86.271894 -452.986674) (xy 86.30322 -453.05571) (xy 86.32703 -453.127685) (xy 86.343055 -453.201783)
			(xy 86.351114 -453.277164) (xy 86.351618 -453.31507) (xy 86.351114 -453.352976) (xy 86.343055 -453.428357)
			(xy 86.32703 -453.502455) (xy 86.30322 -453.57443) (xy 86.271894 -453.643466) (xy 86.233407 -453.708781)
			(xy 86.188196 -453.769636) (xy 86.136772 -453.82534) (xy 86.079719 -453.875262) (xy 86.017683 -453.918837)
			(xy 85.951366 -453.955572) (xy 85.88152 -453.985049) (xy 85.808937 -454.006935) (xy 85.734439 -454.020982)
			(xy 85.658869 -454.027031) (xy 85.583085 -454.025012) (xy 85.507945 -454.01495) (xy 85.4343 -453.996958)
			(xy 85.362984 -453.97124) (xy 85.294807 -453.938088) (xy 85.230539 -453.897876) (xy 85.17091 -453.851061)
			(xy 85.116594 -453.798173) (xy 85.068208 -453.739811) (xy 85.0263 -453.676636) (xy 84.991344 -453.609365)
			(xy 84.963737 -453.53876) (xy 84.943791 -453.465619) (xy 84.931732 -453.390774) (xy 84.927697 -453.31507)
			(xy 82.585544 -453.31507) (xy 82.579599 -453.320272) (xy 82.517563 -453.363847) (xy 82.451246 -453.400582)
			(xy 82.3814 -453.430059) (xy 82.308817 -453.451945) (xy 82.234319 -453.465992) (xy 82.158749 -453.472041)
			(xy 82.082965 -453.470022) (xy 82.007825 -453.45996) (xy 81.93418 -453.441968) (xy 81.862864 -453.41625)
			(xy 81.794687 -453.383098) (xy 81.730419 -453.342886) (xy 81.67079 -453.296071) (xy 81.616474 -453.243183)
			(xy 81.568088 -453.184821) (xy 81.52618 -453.121646) (xy 81.491224 -453.054375) (xy 81.463617 -452.98377)
			(xy 81.443671 -452.910629) (xy 81.431612 -452.835784) (xy 81.427577 -452.76008) (xy 80.311498 -452.76008)
			(xy 80.310994 -452.797986) (xy 80.302935 -452.873367) (xy 80.28691 -452.947465) (xy 80.2631 -453.01944)
			(xy 80.231774 -453.088476) (xy 80.193287 -453.153791) (xy 80.148076 -453.214646) (xy 80.096652 -453.27035)
			(xy 80.039599 -453.320272) (xy 79.977563 -453.363847) (xy 79.911246 -453.400582) (xy 79.8414 -453.430059)
			(xy 79.768817 -453.451945) (xy 79.694319 -453.465992) (xy 79.618749 -453.472041) (xy 79.542965 -453.470022)
			(xy 79.467825 -453.45996) (xy 79.39418 -453.441968) (xy 79.322864 -453.41625) (xy 79.254687 -453.383098)
			(xy 79.190419 -453.342886) (xy 79.13079 -453.296071) (xy 79.076474 -453.243183) (xy 79.028088 -453.184821)
			(xy 78.98618 -453.121646) (xy 78.951224 -453.054375) (xy 78.923617 -452.98377) (xy 78.903671 -452.910629)
			(xy 78.891612 -452.835784) (xy 78.887577 -452.76008) (xy 77.771498 -452.76008) (xy 77.770994 -452.797986)
			(xy 77.762935 -452.873367) (xy 77.74691 -452.947465) (xy 77.7231 -453.01944) (xy 77.691774 -453.088476)
			(xy 77.653287 -453.153791) (xy 77.608076 -453.214646) (xy 77.556652 -453.27035) (xy 77.499599 -453.320272)
			(xy 77.437563 -453.363847) (xy 77.371246 -453.400582) (xy 77.3014 -453.430059) (xy 77.228817 -453.451945)
			(xy 77.154319 -453.465992) (xy 77.078749 -453.472041) (xy 77.002965 -453.470022) (xy 76.927825 -453.45996)
			(xy 76.85418 -453.441968) (xy 76.782864 -453.41625) (xy 76.714687 -453.383098) (xy 76.650419 -453.342886)
			(xy 76.59079 -453.296071) (xy 76.536474 -453.243183) (xy 76.488088 -453.184821) (xy 76.44618 -453.121646)
			(xy 76.411224 -453.054375) (xy 76.383617 -452.98377) (xy 76.363671 -452.910629) (xy 76.351612 -452.835784)
			(xy 76.347577 -452.76008) (xy 75.231498 -452.76008) (xy 75.230994 -452.797986) (xy 75.222935 -452.873367)
			(xy 75.20691 -452.947465) (xy 75.1831 -453.01944) (xy 75.151774 -453.088476) (xy 75.113287 -453.153791)
			(xy 75.068076 -453.214646) (xy 75.016652 -453.27035) (xy 74.959599 -453.320272) (xy 74.897563 -453.363847)
			(xy 74.831246 -453.400582) (xy 74.7614 -453.430059) (xy 74.688817 -453.451945) (xy 74.614319 -453.465992)
			(xy 74.538749 -453.472041) (xy 74.462965 -453.470022) (xy 74.387825 -453.45996) (xy 74.31418 -453.441968)
			(xy 74.242864 -453.41625) (xy 74.174687 -453.383098) (xy 74.110419 -453.342886) (xy 74.05079 -453.296071)
			(xy 73.996474 -453.243183) (xy 73.948088 -453.184821) (xy 73.90618 -453.121646) (xy 73.871224 -453.054375)
			(xy 73.843617 -452.98377) (xy 73.823671 -452.910629) (xy 73.811612 -452.835784) (xy 73.807577 -452.76008)
			(xy 72.691498 -452.76008) (xy 72.690994 -452.797986) (xy 72.682935 -452.873367) (xy 72.66691 -452.947465)
			(xy 72.6431 -453.01944) (xy 72.611774 -453.088476) (xy 72.573287 -453.153791) (xy 72.528076 -453.214646)
			(xy 72.476652 -453.27035) (xy 72.419599 -453.320272) (xy 72.357563 -453.363847) (xy 72.291246 -453.400582)
			(xy 72.2214 -453.430059) (xy 72.148817 -453.451945) (xy 72.074319 -453.465992) (xy 71.998749 -453.472041)
			(xy 71.922965 -453.470022) (xy 71.847825 -453.45996) (xy 71.77418 -453.441968) (xy 71.702864 -453.41625)
			(xy 71.634687 -453.383098) (xy 71.570419 -453.342886) (xy 71.51079 -453.296071) (xy 71.456474 -453.243183)
			(xy 71.408088 -453.184821) (xy 71.36618 -453.121646) (xy 71.331224 -453.054375) (xy 71.303617 -452.98377)
			(xy 71.283671 -452.910629) (xy 71.271612 -452.835784) (xy 71.267577 -452.76008) (xy 70.151498 -452.76008)
			(xy 70.150994 -452.797986) (xy 70.142935 -452.873367) (xy 70.12691 -452.947465) (xy 70.1031 -453.01944)
			(xy 70.071774 -453.088476) (xy 70.033287 -453.153791) (xy 69.988076 -453.214646) (xy 69.936652 -453.27035)
			(xy 69.879599 -453.320272) (xy 69.817563 -453.363847) (xy 69.751246 -453.400582) (xy 69.6814 -453.430059)
			(xy 69.608817 -453.451945) (xy 69.534319 -453.465992) (xy 69.458749 -453.472041) (xy 69.382965 -453.470022)
			(xy 69.307825 -453.45996) (xy 69.23418 -453.441968) (xy 69.162864 -453.41625) (xy 69.094687 -453.383098)
			(xy 69.030419 -453.342886) (xy 68.97079 -453.296071) (xy 68.916474 -453.243183) (xy 68.868088 -453.184821)
			(xy 68.82618 -453.121646) (xy 68.791224 -453.054375) (xy 68.763617 -452.98377) (xy 68.743671 -452.910629)
			(xy 68.731612 -452.835784) (xy 68.727577 -452.76008) (xy 67.611498 -452.76008) (xy 67.610994 -452.797986)
			(xy 67.602935 -452.873367) (xy 67.58691 -452.947465) (xy 67.5631 -453.01944) (xy 67.531774 -453.088476)
			(xy 67.493287 -453.153791) (xy 67.448076 -453.214646) (xy 67.396652 -453.27035) (xy 67.339599 -453.320272)
			(xy 67.277563 -453.363847) (xy 67.211246 -453.400582) (xy 67.1414 -453.430059) (xy 67.068817 -453.451945)
			(xy 66.994319 -453.465992) (xy 66.918749 -453.472041) (xy 66.842965 -453.470022) (xy 66.767825 -453.45996)
			(xy 66.69418 -453.441968) (xy 66.622864 -453.41625) (xy 66.554687 -453.383098) (xy 66.490419 -453.342886)
			(xy 66.43079 -453.296071) (xy 66.376474 -453.243183) (xy 66.328088 -453.184821) (xy 66.28618 -453.121646)
			(xy 66.251224 -453.054375) (xy 66.223617 -452.98377) (xy 66.203671 -452.910629) (xy 66.191612 -452.835784)
			(xy 66.187577 -452.76008) (xy 65.071498 -452.76008) (xy 65.070994 -452.797986) (xy 65.062935 -452.873367)
			(xy 65.04691 -452.947465) (xy 65.0231 -453.01944) (xy 64.991774 -453.088476) (xy 64.953287 -453.153791)
			(xy 64.908076 -453.214646) (xy 64.856652 -453.27035) (xy 64.799599 -453.320272) (xy 64.737563 -453.363847)
			(xy 64.671246 -453.400582) (xy 64.6014 -453.430059) (xy 64.528817 -453.451945) (xy 64.454319 -453.465992)
			(xy 64.378749 -453.472041) (xy 64.302965 -453.470022) (xy 64.227825 -453.45996) (xy 64.15418 -453.441968)
			(xy 64.082864 -453.41625) (xy 64.014687 -453.383098) (xy 63.950419 -453.342886) (xy 63.89079 -453.296071)
			(xy 63.836474 -453.243183) (xy 63.788088 -453.184821) (xy 63.74618 -453.121646) (xy 63.711224 -453.054375)
			(xy 63.683617 -452.98377) (xy 63.663671 -452.910629) (xy 63.651612 -452.835784) (xy 63.647577 -452.76008)
			(xy 42.500891 -452.76008) (xy 42.476568 -452.778757) (xy 42.378803 -452.843524) (xy 42.276762 -452.901321)
			(xy 42.170942 -452.951865) (xy 42.061856 -452.994911) (xy 41.950036 -453.030251) (xy 41.836024 -453.057711)
			(xy 41.720376 -453.077159) (xy 41.603654 -453.0885) (xy 41.486425 -453.091679) (xy 41.36926 -453.086681)
			(xy 41.252728 -453.073529) (xy 41.137395 -453.052288) (xy 41.023824 -453.02306) (xy 40.912566 -452.985989)
			(xy 40.804161 -452.941254) (xy 40.699138 -452.889073) (xy 40.598007 -452.8297) (xy 40.50126 -452.763423)
			(xy 40.409367 -452.690564) (xy 40.322774 -452.611479) (xy 40.241904 -452.526551) (xy 40.204136 -452.481696)
			(xy 40.189599 -452.464879) (xy 40.155709 -452.436118) (xy 40.117333 -452.413691) (xy 40.07564 -452.398283)
			(xy 40.031902 -452.390363) (xy 39.987453 -452.390174) (xy 39.94365 -452.397722) (xy 39.901827 -452.412775)
			(xy 39.863261 -452.434875) (xy 39.829129 -452.463347) (xy 39.80047 -452.497324) (xy 39.778161 -452.535768)
			(xy 39.76288 -452.577508) (xy 39.755093 -452.62127) (xy 39.754556 -452.643494) (xy 39.754556 -456.841606)
			(xy 39.755084 -456.858431) (xy 39.763892 -456.890909) (xy 39.780869 -456.919963) (xy 39.804839 -456.943581)
			(xy 39.834141 -456.960126) (xy 39.850314 -456.964796) (xy 39.850568 -456.964796) (xy 39.879834 -456.972675)
			(xy 39.936136 -456.995108) (xy 39.988984 -457.024779) (xy 40.037453 -457.061166) (xy 40.080693 -457.103634)
			(xy 40.117949 -457.151439) (xy 40.148567 -457.203744) (xy 40.172012 -457.259633) (xy 40.187873 -457.318128)
			(xy 40.195874 -457.378205) (xy 40.195873 -457.438812) (xy 40.18787 -457.498889) (xy 40.172007 -457.557383)
			(xy 40.14856 -457.613271) (xy 40.117939 -457.665575) (xy 40.080682 -457.713378) (xy 40.03744 -457.755844)
			(xy 39.98897 -457.79223) (xy 39.936121 -457.821899) (xy 39.879818 -457.84433) (xy 39.850568 -457.852272)
			(xy 39.850314 -457.852272) (xy 39.834117 -457.856901) (xy 39.804766 -457.873412) (xy 39.780762 -457.897031)
			(xy 39.76378 -457.926111) (xy 39.755004 -457.958624) (xy 39.754556 -457.975462) (xy 39.754556 -458.521623)
			(xy 63.23697 -458.521623) (xy 63.240854 -458.467267) (xy 63.252435 -458.414018) (xy 63.271476 -458.362958)
			(xy 63.29759 -458.315128) (xy 63.330245 -458.271502) (xy 63.368777 -458.232967) (xy 63.4124 -458.200308)
			(xy 63.460228 -458.17419) (xy 63.511285 -458.155144) (xy 63.564534 -458.143559) (xy 63.618889 -458.13967)
			(xy 63.673245 -458.143556) (xy 63.726494 -458.155138) (xy 63.777553 -458.174181) (xy 63.825382 -458.200297)
			(xy 63.847472 -458.216254) (xy 63.866484 -458.22985) (xy 63.908367 -458.250582) (xy 63.953335 -458.263308)
			(xy 63.999872 -458.267598) (xy 64.046409 -458.263308) (xy 64.091377 -458.250582) (xy 64.13326 -458.22985)
			(xy 64.152272 -458.216254) (xy 64.174396 -458.200343) (xy 64.222222 -458.174223) (xy 64.273278 -458.155175)
			(xy 64.326525 -458.143588) (xy 64.380879 -458.139697) (xy 64.435233 -458.143582) (xy 64.488482 -458.155163)
			(xy 64.53954 -458.174205) (xy 64.587368 -458.20032) (xy 64.630992 -458.232976) (xy 64.669525 -458.271509)
			(xy 64.702181 -458.315133) (xy 64.728296 -458.362962) (xy 64.747337 -458.41402) (xy 64.758918 -458.467268)
			(xy 64.762803 -458.521623) (xy 65.312349 -458.521623) (xy 65.316234 -458.467263) (xy 65.327816 -458.414008)
			(xy 65.34686 -458.362945) (xy 65.372977 -458.315112) (xy 65.405635 -458.271482) (xy 65.444171 -458.232945)
			(xy 65.4878 -458.200284) (xy 65.535632 -458.174166) (xy 65.586695 -458.15512) (xy 65.639949 -458.143536)
			(xy 65.694309 -458.139649) (xy 65.748669 -458.143539) (xy 65.801922 -458.155125) (xy 65.852984 -458.174173)
			(xy 65.900815 -458.200294) (xy 65.922906 -458.216254) (xy 65.941918 -458.22985) (xy 65.983801 -458.250582)
			(xy 66.028769 -458.263308) (xy 66.075306 -458.267598) (xy 66.121843 -458.263308) (xy 66.166811 -458.250582)
			(xy 66.208694 -458.22985) (xy 66.227706 -458.216254) (xy 66.24983 -458.200346) (xy 66.297653 -458.174231)
			(xy 66.348705 -458.155188) (xy 66.401948 -458.143605) (xy 66.456298 -458.139717) (xy 66.510648 -458.143605)
			(xy 66.563891 -458.155187) (xy 66.614944 -458.174229) (xy 66.662767 -458.200344) (xy 66.706387 -458.232999)
			(xy 66.744915 -458.271529) (xy 66.777567 -458.31515) (xy 66.803679 -458.362975) (xy 66.822719 -458.414029)
			(xy 66.834298 -458.467273) (xy 66.838183 -458.521623) (xy 66.838136 -458.522286) (xy 67.536712 -458.522286)
			(xy 67.540602 -458.467936) (xy 67.552186 -458.414693) (xy 67.571231 -458.36364) (xy 67.597347 -458.315818)
			(xy 67.630004 -458.272199) (xy 67.668535 -458.233672) (xy 67.712158 -458.201021) (xy 67.759984 -458.174911)
			(xy 67.811038 -458.155873) (xy 67.864283 -458.144295) (xy 67.918633 -458.140412) (xy 67.972983 -458.144304)
			(xy 68.026225 -458.155892) (xy 68.077277 -458.174939) (xy 68.125098 -458.201057) (xy 68.147184 -458.217016)
			(xy 68.166196 -458.230612) (xy 68.208079 -458.251344) (xy 68.253047 -458.26407) (xy 68.299584 -458.26836)
			(xy 68.346121 -458.26407) (xy 68.391089 -458.251344) (xy 68.432972 -458.230612) (xy 68.451984 -458.217016)
			(xy 68.47405 -458.201022) (xy 68.521878 -458.174896) (xy 68.572938 -458.155843) (xy 68.626189 -458.14425)
			(xy 68.680548 -458.140355) (xy 68.734909 -458.144235) (xy 68.788163 -458.155814) (xy 68.839228 -458.174853)
			(xy 68.887063 -458.200967) (xy 68.930695 -458.233622) (xy 68.969235 -458.272155) (xy 69.001898 -458.315781)
			(xy 69.028019 -458.363612) (xy 69.047068 -458.414673) (xy 69.058655 -458.467926) (xy 69.062545 -458.522286)
			(xy 69.058659 -458.576646) (xy 69.047076 -458.629899) (xy 69.028031 -458.680962) (xy 69.001913 -458.728794)
			(xy 68.969253 -458.772423) (xy 68.930717 -458.810959) (xy 68.887087 -458.843618) (xy 68.839254 -458.869735)
			(xy 68.788191 -458.888778) (xy 68.734937 -458.90036) (xy 68.680577 -458.904245) (xy 68.626218 -458.900354)
			(xy 68.572965 -458.888766) (xy 68.521904 -458.869716) (xy 68.474074 -458.843593) (xy 68.451984 -458.827632)
			(xy 68.432972 -458.814036) (xy 68.391089 -458.793304) (xy 68.346121 -458.780578) (xy 68.299584 -458.776288)
			(xy 68.253047 -458.780578) (xy 68.208079 -458.793304) (xy 68.166196 -458.814036) (xy 68.147184 -458.827632)
			(xy 68.125074 -458.843558) (xy 68.077251 -458.869673) (xy 68.026198 -458.888716) (xy 67.972954 -458.9003)
			(xy 67.918605 -458.904188) (xy 67.864254 -458.900301) (xy 67.811011 -458.888719) (xy 67.759958 -458.869677)
			(xy 67.712134 -458.843563) (xy 67.668514 -458.810909) (xy 67.629985 -458.772379) (xy 67.597332 -458.728758)
			(xy 67.571219 -458.680933) (xy 67.552178 -458.62988) (xy 67.540598 -458.576636) (xy 67.536712 -458.522286)
			(xy 66.838136 -458.522286) (xy 66.834292 -458.575972) (xy 66.822706 -458.629215) (xy 66.80366 -458.680267)
			(xy 66.777543 -458.728088) (xy 66.744885 -458.771706) (xy 66.706352 -458.810231) (xy 66.662729 -458.842881)
			(xy 66.614903 -458.868989) (xy 66.563848 -458.888026) (xy 66.510603 -458.899602) (xy 66.456253 -458.903483)
			(xy 66.401903 -458.899588) (xy 66.348661 -458.887999) (xy 66.297611 -458.86895) (xy 66.249791 -458.84283)
			(xy 66.227706 -458.82687) (xy 66.208694 -458.813274) (xy 66.166811 -458.792542) (xy 66.121843 -458.779816)
			(xy 66.075306 -458.775526) (xy 66.028769 -458.779816) (xy 65.983801 -458.792542) (xy 65.941918 -458.813274)
			(xy 65.922906 -458.82687) (xy 65.900853 -458.842882) (xy 65.853025 -458.869008) (xy 65.801965 -458.888062)
			(xy 65.748714 -458.899655) (xy 65.694354 -458.903551) (xy 65.639994 -458.89967) (xy 65.586739 -458.888093)
			(xy 65.535674 -458.869053) (xy 65.487838 -458.84294) (xy 65.444206 -458.810285) (xy 65.405665 -458.771752)
			(xy 65.373001 -458.728127) (xy 65.346879 -458.680297) (xy 65.327829 -458.629235) (xy 65.316241 -458.575983)
			(xy 65.312349 -458.521623) (xy 64.762803 -458.521623) (xy 64.758912 -458.575977) (xy 64.747324 -458.629224)
			(xy 64.728277 -458.68028) (xy 64.702156 -458.728105) (xy 64.669495 -458.771726) (xy 64.630958 -458.810254)
			(xy 64.58733 -458.842905) (xy 64.539498 -458.869014) (xy 64.488438 -458.88805) (xy 64.435188 -458.899625)
			(xy 64.380833 -458.903503) (xy 64.32648 -458.899606) (xy 64.273234 -458.888012) (xy 64.22218 -458.868958)
			(xy 64.174358 -458.842832) (xy 64.152272 -458.82687) (xy 64.13326 -458.813274) (xy 64.091377 -458.792542)
			(xy 64.046409 -458.779816) (xy 63.999872 -458.775526) (xy 63.953335 -458.779816) (xy 63.908367 -458.792542)
			(xy 63.866484 -458.813274) (xy 63.847472 -458.82687) (xy 63.82542 -458.842879) (xy 63.777594 -458.869)
			(xy 63.726538 -458.888049) (xy 63.67329 -458.899638) (xy 63.618935 -458.90353) (xy 63.564579 -458.899647)
			(xy 63.511329 -458.888069) (xy 63.460269 -458.869029) (xy 63.412439 -458.842917) (xy 63.368811 -458.810263)
			(xy 63.330275 -458.771732) (xy 63.297615 -458.72811) (xy 63.271495 -458.680283) (xy 63.252448 -458.629226)
			(xy 63.240861 -458.575978) (xy 63.23697 -458.521623) (xy 39.754556 -458.521623) (xy 39.754556 -460.278184)
			(xy 63.237021 -460.278184) (xy 63.24091 -460.223836) (xy 63.252495 -460.170595) (xy 63.271539 -460.119545)
			(xy 63.297654 -460.071724) (xy 63.330309 -460.028107) (xy 63.368839 -459.989581) (xy 63.41246 -459.95693)
			(xy 63.460284 -459.930821) (xy 63.511337 -459.911783) (xy 63.564579 -459.900204) (xy 63.618928 -459.896321)
			(xy 63.673276 -459.900212) (xy 63.726516 -459.911798) (xy 63.777566 -459.930844) (xy 63.825386 -459.95696)
			(xy 63.847472 -459.972918) (xy 63.866484 -459.986514) (xy 63.908367 -460.007246) (xy 63.953335 -460.019972)
			(xy 63.999872 -460.024262) (xy 64.046409 -460.019972) (xy 64.091377 -460.007246) (xy 64.13326 -459.986514)
			(xy 64.152272 -459.972918) (xy 64.174336 -459.956921) (xy 64.222165 -459.930792) (xy 64.273226 -459.911737)
			(xy 64.326479 -459.900143) (xy 64.38084 -459.896246) (xy 64.435203 -459.900126) (xy 64.488459 -459.911703)
			(xy 64.539526 -459.930743) (xy 64.587363 -459.956856) (xy 64.630997 -459.989512) (xy 64.669538 -460.028046)
			(xy 64.702203 -460.071673) (xy 64.728326 -460.119505) (xy 64.747376 -460.170568) (xy 64.758964 -460.223823)
			(xy 64.762854 -460.278184) (xy 65.312401 -460.278184) (xy 65.316291 -460.223832) (xy 65.327876 -460.170586)
			(xy 65.346922 -460.119531) (xy 65.37304 -460.071707) (xy 65.405699 -460.028087) (xy 65.444234 -459.989558)
			(xy 65.48786 -459.956907) (xy 65.535688 -459.930796) (xy 65.586746 -459.911759) (xy 65.639994 -459.900182)
			(xy 65.694347 -459.896301) (xy 65.748699 -459.900195) (xy 65.801944 -459.911785) (xy 65.852997 -459.930835)
			(xy 65.90082 -459.956957) (xy 65.922906 -459.972918) (xy 65.941918 -459.986514) (xy 65.983801 -460.007246)
			(xy 66.028769 -460.019972) (xy 66.075306 -460.024262) (xy 66.121843 -460.019972) (xy 66.166811 -460.007246)
			(xy 66.208694 -459.986514) (xy 66.227706 -459.972918) (xy 66.24977 -459.956923) (xy 66.297596 -459.9308)
			(xy 66.348654 -459.91175) (xy 66.401903 -459.90016) (xy 66.45626 -459.896266) (xy 66.510617 -459.900148)
			(xy 66.563869 -459.911727) (xy 66.614931 -459.930767) (xy 66.662763 -459.95688) (xy 66.706391 -459.989535)
			(xy 66.744929 -460.028066) (xy 66.77759 -460.07169) (xy 66.80371 -460.119519) (xy 66.822757 -460.170578)
			(xy 66.834344 -460.223827) (xy 66.838234 -460.278184) (xy 66.838175 -460.279007) (xy 67.536683 -460.279007)
			(xy 67.54057 -460.224653) (xy 67.552153 -460.171405) (xy 67.571196 -460.120348) (xy 67.597311 -460.072521)
			(xy 67.629968 -460.028897) (xy 67.6685 -459.990365) (xy 67.712124 -459.957709) (xy 67.759952 -459.931594)
			(xy 67.81101 -459.912551) (xy 67.864258 -459.900969) (xy 67.918612 -459.897083) (xy 67.972966 -459.900973)
			(xy 68.026213 -459.912558) (xy 68.077269 -459.931604) (xy 68.125095 -459.957721) (xy 68.147184 -459.97368)
			(xy 68.166196 -459.987276) (xy 68.208079 -460.008008) (xy 68.253047 -460.020734) (xy 68.299584 -460.025024)
			(xy 68.346121 -460.020734) (xy 68.391089 -460.008008) (xy 68.432972 -459.987276) (xy 68.451984 -459.97368)
			(xy 68.474084 -459.957735) (xy 68.52191 -459.931613) (xy 68.572966 -459.912564) (xy 68.626215 -459.900976)
			(xy 68.68057 -459.897083) (xy 68.734926 -459.900967) (xy 68.788176 -459.912547) (xy 68.839236 -459.931588)
			(xy 68.887066 -459.957703) (xy 68.930692 -459.990358) (xy 68.969227 -460.028891) (xy 69.001885 -460.072515)
			(xy 69.028002 -460.120343) (xy 69.047046 -460.171402) (xy 69.05863 -460.224651) (xy 69.062517 -460.279007)
			(xy 69.058628 -460.333363) (xy 69.047042 -460.386612) (xy 69.027996 -460.43767) (xy 69.001877 -460.485497)
			(xy 68.969217 -460.52912) (xy 68.930681 -460.567651) (xy 68.887054 -460.600305) (xy 68.839223 -460.626418)
			(xy 68.788162 -460.645457) (xy 68.734912 -460.657035) (xy 68.680556 -460.660917) (xy 68.6262 -460.657022)
			(xy 68.572953 -460.645432) (xy 68.521897 -460.626381) (xy 68.474072 -460.600257) (xy 68.451984 -460.584296)
			(xy 68.432972 -460.5707) (xy 68.391089 -460.549968) (xy 68.346121 -460.537242) (xy 68.299584 -460.532952)
			(xy 68.253047 -460.537242) (xy 68.208079 -460.549968) (xy 68.166196 -460.5707) (xy 68.147184 -460.584296)
			(xy 68.125107 -460.600271) (xy 68.077282 -460.62639) (xy 68.026227 -460.645438) (xy 67.97298 -460.657025)
			(xy 67.918626 -460.660917) (xy 67.864272 -460.657033) (xy 67.811023 -460.645453) (xy 67.759965 -460.626412)
			(xy 67.712137 -460.600299) (xy 67.668511 -460.567645) (xy 67.629977 -460.529114) (xy 67.597319 -460.485492)
			(xy 67.571202 -460.437665) (xy 67.552157 -460.386609) (xy 67.540572 -460.333361) (xy 67.536683 -460.279007)
			(xy 66.838175 -460.279007) (xy 66.834348 -460.332542) (xy 66.822766 -460.385792) (xy 66.803723 -460.436853)
			(xy 66.777607 -460.484683) (xy 66.744949 -460.52831) (xy 66.706415 -460.566845) (xy 66.662789 -460.599503)
			(xy 66.614959 -460.62562) (xy 66.563899 -460.644664) (xy 66.510648 -460.656247) (xy 66.456291 -460.660134)
			(xy 66.401934 -460.656245) (xy 66.348684 -460.644659) (xy 66.297625 -460.625613) (xy 66.249796 -460.599493)
			(xy 66.227706 -460.583534) (xy 66.208694 -460.569938) (xy 66.166811 -460.549206) (xy 66.121843 -460.53648)
			(xy 66.075306 -460.53219) (xy 66.028769 -460.53648) (xy 65.983801 -460.549206) (xy 65.941918 -460.569938)
			(xy 65.922906 -460.583534) (xy 65.900793 -460.599459) (xy 65.852969 -460.625578) (xy 65.801914 -460.644624)
			(xy 65.748668 -460.656209) (xy 65.694316 -460.660099) (xy 65.639963 -460.656214) (xy 65.586716 -460.644633)
			(xy 65.53566 -460.625591) (xy 65.487833 -460.599477) (xy 65.44421 -460.566821) (xy 65.405679 -460.52829)
			(xy 65.373024 -460.484667) (xy 65.346909 -460.43684) (xy 65.327868 -460.385784) (xy 65.316286 -460.332537)
			(xy 65.312401 -460.278184) (xy 64.762854 -460.278184) (xy 64.758968 -460.332546) (xy 64.747384 -460.385802)
			(xy 64.728339 -460.436866) (xy 64.70222 -460.4847) (xy 64.669559 -460.52833) (xy 64.63102 -460.566867)
			(xy 64.58739 -460.599527) (xy 64.539555 -460.625644) (xy 64.488489 -460.644688) (xy 64.435234 -460.65627)
			(xy 64.380872 -460.660154) (xy 64.32651 -460.656262) (xy 64.273256 -460.644672) (xy 64.222194 -460.625621)
			(xy 64.174363 -460.599496) (xy 64.152272 -460.583534) (xy 64.13326 -460.569938) (xy 64.091377 -460.549206)
			(xy 64.046409 -460.53648) (xy 63.999872 -460.53219) (xy 63.953335 -460.53648) (xy 63.908367 -460.549206)
			(xy 63.866484 -460.569938) (xy 63.847472 -460.583534) (xy 63.82536 -460.599457) (xy 63.777538 -460.625569)
			(xy 63.726486 -460.644611) (xy 63.673245 -460.656192) (xy 63.618897 -460.660079) (xy 63.564548 -460.656191)
			(xy 63.511307 -460.644609) (xy 63.460256 -460.625566) (xy 63.412434 -460.599453) (xy 63.368816 -460.566799)
			(xy 63.330289 -460.52827) (xy 63.297637 -460.48465) (xy 63.271526 -460.436827) (xy 63.252486 -460.385775)
			(xy 63.240906 -460.332533) (xy 63.237021 -460.278184) (xy 39.754556 -460.278184) (xy 39.754556 -461.723232)
			(xy 39.43304 -462.044802) (xy 63.236997 -462.044802) (xy 63.240884 -461.990451) (xy 63.252467 -461.937206)
			(xy 63.271509 -461.886151) (xy 63.297624 -461.838326) (xy 63.330279 -461.794704) (xy 63.36881 -461.756174)
			(xy 63.412432 -461.72352) (xy 63.460258 -461.697406) (xy 63.511313 -461.678365) (xy 63.564558 -461.666783)
			(xy 63.61891 -461.662897) (xy 63.673261 -461.666786) (xy 63.726506 -461.67837) (xy 63.77756 -461.697414)
			(xy 63.825384 -461.72353) (xy 63.847472 -461.739488) (xy 63.866484 -461.753084) (xy 63.908367 -461.773816)
			(xy 63.953335 -461.786542) (xy 63.999872 -461.790832) (xy 64.046409 -461.786542) (xy 64.091377 -461.773816)
			(xy 64.13326 -461.753084) (xy 64.152272 -461.739488) (xy 64.174365 -461.723531) (xy 64.222192 -461.697406)
			(xy 64.27325 -461.678355) (xy 64.326501 -461.666764) (xy 64.380858 -461.66287) (xy 64.435217 -461.666752)
			(xy 64.48847 -461.678331) (xy 64.539533 -461.697372) (xy 64.587365 -461.723486) (xy 64.630995 -461.756142)
			(xy 64.669532 -461.794676) (xy 64.702193 -461.838302) (xy 64.728312 -461.886132) (xy 64.747358 -461.937192)
			(xy 64.758942 -461.990444) (xy 64.76283 -462.044802) (xy 65.312377 -462.044802) (xy 65.316264 -461.990446)
			(xy 65.327848 -461.937197) (xy 65.346893 -461.886138) (xy 65.373011 -461.838309) (xy 65.405669 -461.794684)
			(xy 65.444205 -461.756152) (xy 65.487831 -461.723496) (xy 65.535662 -461.697382) (xy 65.586722 -461.678341)
			(xy 65.639973 -461.66676) (xy 65.694329 -461.662877) (xy 65.748685 -461.666769) (xy 65.801934 -461.678357)
			(xy 65.852991 -461.697406) (xy 65.900817 -461.723528) (xy 65.922906 -461.739488) (xy 65.941918 -461.753084)
			(xy 65.983801 -461.773816) (xy 66.028769 -461.786542) (xy 66.075306 -461.790832) (xy 66.121843 -461.786542)
			(xy 66.166811 -461.773816) (xy 66.208694 -461.753084) (xy 66.227706 -461.739488) (xy 66.249798 -461.723534)
			(xy 66.297623 -461.697415) (xy 66.348678 -461.678368) (xy 66.401924 -461.666781) (xy 66.456278 -461.66289)
			(xy 66.510632 -461.666775) (xy 66.563879 -461.678355) (xy 66.614937 -461.697396) (xy 66.662765 -461.72351)
			(xy 66.706389 -461.756165) (xy 66.744922 -461.794696) (xy 66.777579 -461.838318) (xy 66.803696 -461.886145)
			(xy 66.822739 -461.937202) (xy 66.834322 -461.990449) (xy 66.83821 -462.044802) (xy 66.838151 -462.045625)
			(xy 67.536659 -462.045625) (xy 67.540544 -461.991267) (xy 67.552125 -461.938016) (xy 67.571166 -461.886954)
			(xy 67.597281 -461.839123) (xy 67.629938 -461.795495) (xy 67.668471 -461.756958) (xy 67.712096 -461.724298)
			(xy 67.759926 -461.698179) (xy 67.810986 -461.679133) (xy 67.864236 -461.667548) (xy 67.918594 -461.663659)
			(xy 67.972951 -461.667546) (xy 68.026202 -461.67913) (xy 68.077263 -461.698174) (xy 68.125093 -461.724291)
			(xy 68.147184 -461.74025) (xy 68.166196 -461.753846) (xy 68.208079 -461.774578) (xy 68.253047 -461.787304)
			(xy 68.299584 -461.791594) (xy 68.346121 -461.787304) (xy 68.391089 -461.774578) (xy 68.432972 -461.753846)
			(xy 68.451984 -461.74025) (xy 68.474112 -461.724345) (xy 68.521936 -461.698228) (xy 68.572991 -461.679182)
			(xy 68.626236 -461.667597) (xy 68.680588 -461.663708) (xy 68.73494 -461.667593) (xy 68.788187 -461.679175)
			(xy 68.839242 -461.698218) (xy 68.887068 -461.724332) (xy 68.93069 -461.756988) (xy 68.969221 -461.79552)
			(xy 69.001875 -461.839143) (xy 69.027988 -461.88697) (xy 69.047028 -461.938026) (xy 69.058608 -461.991273)
			(xy 69.062492 -462.045625) (xy 69.058601 -462.099977) (xy 69.047014 -462.153222) (xy 69.027967 -462.204276)
			(xy 69.001847 -462.252099) (xy 68.969188 -462.295718) (xy 68.930652 -462.334245) (xy 68.887026 -462.366895)
			(xy 68.839196 -462.393003) (xy 68.788138 -462.412039) (xy 68.734891 -462.423614) (xy 68.680538 -462.427492)
			(xy 68.626186 -462.423596) (xy 68.572942 -462.412004) (xy 68.52189 -462.392952) (xy 68.47407 -462.366827)
			(xy 68.451984 -462.350866) (xy 68.432972 -462.33727) (xy 68.391089 -462.316538) (xy 68.346121 -462.303812)
			(xy 68.299584 -462.299522) (xy 68.253047 -462.303812) (xy 68.208079 -462.316538) (xy 68.166196 -462.33727)
			(xy 68.147184 -462.350866) (xy 68.125136 -462.366881) (xy 68.077309 -462.393005) (xy 68.026251 -462.412056)
			(xy 67.973001 -462.423646) (xy 67.918644 -462.427541) (xy 67.864286 -462.423659) (xy 67.811034 -462.412081)
			(xy 67.759972 -462.393042) (xy 67.712139 -462.366929) (xy 67.668509 -462.334275) (xy 67.629971 -462.295743)
			(xy 67.597309 -462.25212) (xy 67.571187 -462.204291) (xy 67.552139 -462.153233) (xy 67.540551 -462.099982)
			(xy 67.536659 -462.045625) (xy 66.838151 -462.045625) (xy 66.834322 -462.099156) (xy 66.822738 -462.152403)
			(xy 66.803694 -462.203459) (xy 66.777577 -462.251286) (xy 66.744919 -462.294908) (xy 66.706386 -462.333438)
			(xy 66.662761 -462.366093) (xy 66.614933 -462.392206) (xy 66.563875 -462.411246) (xy 66.510627 -462.422826)
			(xy 66.456273 -462.42671) (xy 66.40192 -462.422818) (xy 66.348673 -462.411231) (xy 66.297618 -462.392183)
			(xy 66.249794 -462.366063) (xy 66.227706 -462.350104) (xy 66.208694 -462.336508) (xy 66.166811 -462.315776)
			(xy 66.121843 -462.30305) (xy 66.075306 -462.29876) (xy 66.028769 -462.30305) (xy 65.983801 -462.315776)
			(xy 65.941918 -462.336508) (xy 65.922906 -462.350104) (xy 65.900821 -462.36607) (xy 65.852995 -462.392192)
			(xy 65.801938 -462.411242) (xy 65.74869 -462.422831) (xy 65.694334 -462.426723) (xy 65.639977 -462.42284)
			(xy 65.586727 -462.411261) (xy 65.535666 -462.39222) (xy 65.487836 -462.366106) (xy 65.444208 -462.333451)
			(xy 65.405673 -462.294919) (xy 65.373013 -462.251295) (xy 65.346895 -462.203467) (xy 65.32785 -462.152408)
			(xy 65.316265 -462.099159) (xy 65.312377 -462.044802) (xy 64.76283 -462.044802) (xy 64.758942 -462.099161)
			(xy 64.747356 -462.152412) (xy 64.72831 -462.203473) (xy 64.70219 -462.251302) (xy 64.669529 -462.294928)
			(xy 64.630991 -462.333461) (xy 64.587361 -462.366116) (xy 64.539528 -462.39223) (xy 64.488465 -462.41127)
			(xy 64.435212 -462.422849) (xy 64.380854 -462.42673) (xy 64.326496 -462.422835) (xy 64.273246 -462.411244)
			(xy 64.222187 -462.392192) (xy 64.174361 -462.366066) (xy 64.152272 -462.350104) (xy 64.13326 -462.336508)
			(xy 64.091377 -462.315776) (xy 64.046409 -462.30305) (xy 63.999872 -462.29876) (xy 63.953335 -462.30305)
			(xy 63.908367 -462.315776) (xy 63.866484 -462.336508) (xy 63.847472 -462.350104) (xy 63.825388 -462.366067)
			(xy 63.777564 -462.392184) (xy 63.726511 -462.411228) (xy 63.673266 -462.422813) (xy 63.618915 -462.426703)
			(xy 63.564563 -462.422818) (xy 63.511317 -462.411237) (xy 63.460262 -462.392196) (xy 63.412436 -462.366083)
			(xy 63.368814 -462.333429) (xy 63.330282 -462.294899) (xy 63.297626 -462.251278) (xy 63.271511 -462.203453)
			(xy 63.252468 -462.152399) (xy 63.240885 -462.099154) (xy 63.236997 -462.044802) (xy 39.43304 -462.044802)
			(xy 39.203976 -462.273904) (xy 51.322732 -462.273904) (xy 52.974748 -462.273904) (xy 52.974748 -463.859584)
			(xy 63.191333 -463.859584) (xy 63.195222 -463.805239) (xy 63.206806 -463.752001) (xy 63.225848 -463.700952)
			(xy 63.251962 -463.653134) (xy 63.284615 -463.609518) (xy 63.323142 -463.570994) (xy 63.366761 -463.538344)
			(xy 63.414581 -463.512235) (xy 63.465631 -463.493197) (xy 63.518871 -463.481618) (xy 63.573216 -463.477733)
			(xy 63.627562 -463.481622) (xy 63.6808 -463.493206) (xy 63.731848 -463.512248) (xy 63.779667 -463.538362)
			(xy 63.801752 -463.554318) (xy 63.820764 -463.567914) (xy 63.862647 -463.588646) (xy 63.907615 -463.601372)
			(xy 63.954152 -463.605662) (xy 64.000689 -463.601372) (xy 64.045657 -463.588646) (xy 64.08754 -463.567914)
			(xy 64.106552 -463.554318) (xy 64.128617 -463.538319) (xy 64.176447 -463.512187) (xy 64.22751 -463.493129)
			(xy 64.280765 -463.481533) (xy 64.335129 -463.477634) (xy 64.389494 -463.481512) (xy 64.442754 -463.493089)
			(xy 64.493824 -463.512128) (xy 64.541664 -463.538242) (xy 64.5853 -463.570899) (xy 64.623844 -463.609435)
			(xy 64.656511 -463.653063) (xy 64.682636 -463.700898) (xy 64.701687 -463.751963) (xy 64.713275 -463.80522)
			(xy 64.717166 -463.859584) (xy 65.266713 -463.859584) (xy 65.270602 -463.805235) (xy 65.282187 -463.751991)
			(xy 65.301232 -463.700939) (xy 65.327348 -463.653117) (xy 65.360005 -463.609498) (xy 65.398537 -463.570971)
			(xy 65.44216 -463.538321) (xy 65.489986 -463.512211) (xy 65.541041 -463.493173) (xy 65.594285 -463.481595)
			(xy 65.648636 -463.477713) (xy 65.702985 -463.481605) (xy 65.756228 -463.493193) (xy 65.807279 -463.51224)
			(xy 65.8551 -463.538359) (xy 65.877186 -463.554318) (xy 65.896198 -463.567914) (xy 65.938081 -463.588646)
			(xy 65.983049 -463.601372) (xy 66.029586 -463.605662) (xy 66.076123 -463.601372) (xy 66.121091 -463.588646)
			(xy 66.162974 -463.567914) (xy 66.181986 -463.554318) (xy 66.20405 -463.538322) (xy 66.251878 -463.512195)
			(xy 66.302938 -463.493142) (xy 66.356189 -463.48155) (xy 66.410548 -463.477654) (xy 66.464909 -463.481535)
			(xy 66.518163 -463.493113) (xy 66.569228 -463.512153) (xy 66.617063 -463.538266) (xy 66.660695 -463.570922)
			(xy 66.699234 -463.609455) (xy 66.731898 -463.65308) (xy 66.758019 -463.700911) (xy 66.777068 -463.751972)
			(xy 66.788655 -463.805225) (xy 66.792546 -463.859584) (xy 66.792487 -463.860407) (xy 67.445475 -463.860407)
			(xy 67.449362 -463.806051) (xy 67.460945 -463.752802) (xy 67.479989 -463.701743) (xy 67.506106 -463.653914)
			(xy 67.538764 -463.610289) (xy 67.577298 -463.571756) (xy 67.620924 -463.539099) (xy 67.668754 -463.512984)
			(xy 67.719814 -463.493942) (xy 67.773063 -463.48236) (xy 67.82742 -463.478475) (xy 67.881776 -463.482366)
			(xy 67.935024 -463.493953) (xy 67.986082 -463.513) (xy 68.033909 -463.53912) (xy 68.055998 -463.55508)
			(xy 68.07501 -463.568676) (xy 68.116893 -463.589408) (xy 68.161861 -463.602134) (xy 68.208398 -463.606424)
			(xy 68.254935 -463.602134) (xy 68.299903 -463.589408) (xy 68.341786 -463.568676) (xy 68.360798 -463.55508)
			(xy 68.382897 -463.539136) (xy 68.430722 -463.513017) (xy 68.481778 -463.49397) (xy 68.535024 -463.482383)
			(xy 68.589378 -463.478492) (xy 68.643732 -463.482376) (xy 68.69698 -463.493957) (xy 68.748038 -463.512998)
			(xy 68.795866 -463.539112) (xy 68.83949 -463.571767) (xy 68.878023 -463.610299) (xy 68.91068 -463.653922)
			(xy 68.936796 -463.701749) (xy 68.955839 -463.752806) (xy 68.967421 -463.806053) (xy 68.971308 -463.860407)
			(xy 68.967419 -463.914761) (xy 68.955835 -463.968008) (xy 68.93679 -464.019064) (xy 68.910672 -464.06689)
			(xy 68.878013 -464.110512) (xy 68.839479 -464.149042) (xy 68.795853 -464.181695) (xy 68.748025 -464.207808)
			(xy 68.696966 -464.226847) (xy 68.643718 -464.238426) (xy 68.589364 -464.242308) (xy 68.53501 -464.238415)
			(xy 68.481764 -464.226826) (xy 68.430709 -464.207777) (xy 68.382885 -464.181656) (xy 68.360798 -464.165696)
			(xy 68.341786 -464.1521) (xy 68.299903 -464.131368) (xy 68.254935 -464.118642) (xy 68.208398 -464.114352)
			(xy 68.161861 -464.118642) (xy 68.116893 -464.131368) (xy 68.07501 -464.1521) (xy 68.055998 -464.165696)
			(xy 68.033921 -464.181672) (xy 67.986095 -464.207794) (xy 67.935038 -464.226843) (xy 67.88179 -464.238432)
			(xy 67.827434 -464.242325) (xy 67.773078 -464.238442) (xy 67.719827 -464.226863) (xy 67.668767 -464.207822)
			(xy 67.620936 -464.181709) (xy 67.577309 -464.149054) (xy 67.538773 -464.110522) (xy 67.506113 -464.066898)
			(xy 67.479995 -464.019071) (xy 67.460949 -463.968012) (xy 67.449364 -463.914763) (xy 67.445475 -463.860407)
			(xy 66.792487 -463.860407) (xy 66.78866 -463.913944) (xy 66.777077 -463.967198) (xy 66.758032 -464.018261)
			(xy 66.731915 -464.066093) (xy 66.699255 -464.109722) (xy 66.660718 -464.148258) (xy 66.617089 -464.180917)
			(xy 66.569256 -464.207034) (xy 66.518193 -464.226078) (xy 66.46494 -464.237661) (xy 66.41058 -464.241546)
			(xy 66.35622 -464.237655) (xy 66.302968 -464.226067) (xy 66.251907 -464.207017) (xy 66.204076 -464.180895)
			(xy 66.181986 -464.164934) (xy 66.162974 -464.151338) (xy 66.121091 -464.130606) (xy 66.076123 -464.11788)
			(xy 66.029586 -464.11359) (xy 65.983049 -464.11788) (xy 65.938081 -464.130606) (xy 65.896198 -464.151338)
			(xy 65.877186 -464.164934) (xy 65.855074 -464.180858) (xy 65.807251 -464.206973) (xy 65.756198 -464.226016)
			(xy 65.702954 -464.237599) (xy 65.648604 -464.241487) (xy 65.594254 -464.237601) (xy 65.541011 -464.226018)
			(xy 65.489957 -464.206977) (xy 65.442134 -464.180863) (xy 65.398513 -464.148208) (xy 65.359985 -464.109678)
			(xy 65.327331 -464.066057) (xy 65.301219 -464.018233) (xy 65.282178 -463.967179) (xy 65.270598 -463.913935)
			(xy 65.266713 -463.859584) (xy 64.717166 -463.859584) (xy 64.71328 -463.913949) (xy 64.701695 -463.967207)
			(xy 64.682649 -464.018274) (xy 64.656528 -464.06611) (xy 64.623864 -464.109742) (xy 64.585324 -464.14828)
			(xy 64.54169 -464.180941) (xy 64.493852 -464.207059) (xy 64.442784 -464.226102) (xy 64.389525 -464.237683)
			(xy 64.33516 -464.241566) (xy 64.280796 -464.237672) (xy 64.22754 -464.22608) (xy 64.176476 -464.207026)
			(xy 64.128643 -464.180898) (xy 64.106552 -464.164934) (xy 64.08754 -464.151338) (xy 64.045657 -464.130606)
			(xy 64.000689 -464.11788) (xy 63.954152 -464.11359) (xy 63.907615 -464.11788) (xy 63.862647 -464.130606)
			(xy 63.820764 -464.151338) (xy 63.801752 -464.164934) (xy 63.779641 -464.180855) (xy 63.73182 -464.206964)
			(xy 63.68077 -464.226003) (xy 63.627531 -464.237582) (xy 63.573185 -464.241467) (xy 63.51884 -464.237578)
			(xy 63.465601 -464.225994) (xy 63.414553 -464.206952) (xy 63.366734 -464.180839) (xy 63.323119 -464.148186)
			(xy 63.284594 -464.109658) (xy 63.251945 -464.06604) (xy 63.225835 -464.018219) (xy 63.206797 -463.96717)
			(xy 63.195218 -463.91393) (xy 63.191333 -463.859584) (xy 52.974748 -463.859584) (xy 52.974748 -463.925412)
			(xy 51.322732 -463.925412) (xy 51.322732 -462.273904) (xy 39.203976 -462.273904) (xy 38.240208 -463.237834)
			(xy 38.224277 -463.254475) (xy 38.198113 -463.292385) (xy 38.179211 -463.334391) (xy 38.168189 -463.379115)
			(xy 38.165409 -463.425094) (xy 38.170963 -463.470821) (xy 38.184667 -463.514798) (xy 38.206074 -463.555584)
			(xy 38.234481 -463.591844) (xy 38.268959 -463.62239) (xy 38.308378 -463.646221) (xy 38.351447 -463.662556)
			(xy 38.396755 -463.670862) (xy 38.419786 -463.671412) (xy 39.826184 -463.671412) (xy 39.842078 -463.67096)
			(xy 39.872893 -463.663163) (xy 39.900816 -463.647976) (xy 39.924107 -463.626346) (xy 39.933118 -463.613246)
			(xy 39.957074 -463.576609) (xy 40.008928 -463.506072) (xy 40.03675 -463.472276) (xy 40.043682 -463.4482)
			(xy 40.063 -463.401971) (xy 40.088205 -463.35867) (xy 40.118863 -463.319042) (xy 40.154444 -463.283769)
			(xy 40.174164 -463.268314) (xy 40.193143 -463.254332) (xy 40.233902 -463.230643) (xy 40.255444 -463.22107)
			(xy 40.278662 -463.211646) (xy 40.326952 -463.198267) (xy 40.35171 -463.1944) (xy 40.395697 -463.166639)
			(xy 40.4871 -463.116971) (xy 40.581943 -463.074239) (xy 40.679702 -463.038679) (xy 40.779835 -463.010488)
			(xy 40.881787 -462.989822) (xy 40.984994 -462.976796) (xy 41.088883 -462.971481) (xy 41.192881 -462.973908)
			(xy 41.296409 -462.984062) (xy 41.398896 -463.001888) (xy 41.499774 -463.027286) (xy 41.598483 -463.060117)
			(xy 41.694476 -463.100198) (xy 41.74109 -463.12328) (xy 41.773684 -463.140213) (xy 47.82311 -463.140213)
			(xy 47.82311 -463.059103) (xy 47.83106 -462.978384) (xy 47.846883 -462.898833) (xy 47.870428 -462.821217)
			(xy 47.901467 -462.746281) (xy 47.939702 -462.674749) (xy 47.984764 -462.607309) (xy 48.036219 -462.54461)
			(xy 48.093572 -462.487257) (xy 48.156271 -462.435802) (xy 48.223711 -462.39074) (xy 48.295243 -462.352505)
			(xy 48.370179 -462.321466) (xy 48.447795 -462.297921) (xy 48.527346 -462.282098) (xy 48.608065 -462.274148)
			(xy 48.689175 -462.274148) (xy 48.769894 -462.282098) (xy 48.849445 -462.297921) (xy 48.927061 -462.321466)
			(xy 49.001997 -462.352505) (xy 49.073529 -462.39074) (xy 49.140969 -462.435802) (xy 49.203668 -462.487257)
			(xy 49.261021 -462.54461) (xy 49.312476 -462.607309) (xy 49.357538 -462.674749) (xy 49.395773 -462.746281)
			(xy 49.426812 -462.821217) (xy 49.450357 -462.898833) (xy 49.46618 -462.978384) (xy 49.47413 -463.059103)
			(xy 49.474628 -463.099658) (xy 49.47413 -463.140213) (xy 49.46618 -463.220932) (xy 49.450357 -463.300483)
			(xy 49.426812 -463.378099) (xy 49.395773 -463.453035) (xy 49.357538 -463.524567) (xy 49.312476 -463.592007)
			(xy 49.261021 -463.654706) (xy 49.203668 -463.712059) (xy 49.140969 -463.763514) (xy 49.073529 -463.808576)
			(xy 49.001997 -463.846811) (xy 48.927061 -463.87785) (xy 48.849445 -463.901395) (xy 48.769894 -463.917218)
			(xy 48.689175 -463.925168) (xy 48.608065 -463.925168) (xy 48.527346 -463.917218) (xy 48.447795 -463.901395)
			(xy 48.370179 -463.87785) (xy 48.295243 -463.846811) (xy 48.223711 -463.808576) (xy 48.156271 -463.763514)
			(xy 48.093572 -463.712059) (xy 48.036219 -463.654706) (xy 47.984764 -463.592007) (xy 47.939702 -463.524567)
			(xy 47.901467 -463.453035) (xy 47.870428 -463.378099) (xy 47.846883 -463.300483) (xy 47.83106 -463.220932)
			(xy 47.82311 -463.140213) (xy 41.773684 -463.140213) (xy 41.788296 -463.147804) (xy 41.879222 -463.203037)
			(xy 41.965684 -463.265025) (xy 42.047181 -463.33341) (xy 42.12324 -463.407795) (xy 42.193422 -463.48775)
			(xy 42.25732 -463.57281) (xy 42.314563 -463.662484) (xy 42.36482 -463.756252) (xy 42.4078 -463.853571)
			(xy 42.443254 -463.953877) (xy 42.470976 -464.056589) (xy 42.490806 -464.161112) (xy 42.502629 -464.26684)
			(xy 42.506376 -464.373161) (xy 42.502026 -464.479459) (xy 42.489604 -464.585118) (xy 42.469182 -464.689527)
			(xy 42.440879 -464.79208) (xy 42.404857 -464.892183) (xy 42.361326 -464.989257) (xy 42.310539 -465.082739)
			(xy 42.252788 -465.172087) (xy 42.188409 -465.256784) (xy 42.117775 -465.33634) (xy 42.079926 -465.37372)
			(xy 42.072331 -465.425964) (xy 42.050721 -465.529312) (xy 42.036746 -465.580222) (xy 42.026144 -465.616306)
			(xy 63.191304 -465.616306) (xy 63.195191 -465.561956) (xy 63.206772 -465.508713) (xy 63.225813 -465.45766)
			(xy 63.251926 -465.409836) (xy 63.284579 -465.366216) (xy 63.323107 -465.327686) (xy 63.366727 -465.295032)
			(xy 63.41455 -465.268918) (xy 63.465602 -465.249875) (xy 63.518845 -465.238292) (xy 63.573195 -465.234404)
			(xy 63.627544 -465.238291) (xy 63.680788 -465.249872) (xy 63.731841 -465.268913) (xy 63.779664 -465.295026)
			(xy 63.801752 -465.310982) (xy 63.820764 -465.324578) (xy 63.862647 -465.34531) (xy 63.907615 -465.358036)
			(xy 63.954152 -465.362326) (xy 64.000689 -465.358036) (xy 64.045657 -465.34531) (xy 64.08754 -465.324578)
			(xy 64.106552 -465.310982) (xy 64.128651 -465.295031) (xy 64.176479 -465.268904) (xy 64.227539 -465.249851)
			(xy 64.280791 -465.238258) (xy 64.335151 -465.234363) (xy 64.389511 -465.238244) (xy 64.442766 -465.249823)
			(xy 64.493831 -465.268863) (xy 64.541666 -465.294978) (xy 64.585297 -465.327635) (xy 64.623836 -465.36617)
			(xy 64.656498 -465.409797) (xy 64.682619 -465.457629) (xy 64.701665 -465.508692) (xy 64.71325 -465.561946)
			(xy 64.717137 -465.616306) (xy 65.266684 -465.616306) (xy 65.270571 -465.561952) (xy 65.282153 -465.508704)
			(xy 65.301197 -465.457647) (xy 65.327312 -465.409819) (xy 65.359969 -465.366196) (xy 65.398502 -465.327664)
			(xy 65.442126 -465.295008) (xy 65.489954 -465.268893) (xy 65.541012 -465.249851) (xy 65.59426 -465.238269)
			(xy 65.648614 -465.234384) (xy 65.702968 -465.238273) (xy 65.756215 -465.249859) (xy 65.807271 -465.268905)
			(xy 65.855097 -465.295023) (xy 65.877186 -465.310982) (xy 65.896198 -465.324578) (xy 65.938081 -465.34531)
			(xy 65.983049 -465.358036) (xy 66.029586 -465.362326) (xy 66.076123 -465.358036) (xy 66.121091 -465.34531)
			(xy 66.162974 -465.324578) (xy 66.181986 -465.310982) (xy 66.204084 -465.295034) (xy 66.25191 -465.268913)
			(xy 66.302967 -465.249864) (xy 66.356215 -465.238275) (xy 66.41057 -465.234383) (xy 66.464926 -465.238267)
			(xy 66.518176 -465.249847) (xy 66.569236 -465.268888) (xy 66.617066 -465.295002) (xy 66.660692 -465.327658)
			(xy 66.699227 -465.36619) (xy 66.731885 -465.409814) (xy 66.758002 -465.457643) (xy 66.777046 -465.508701)
			(xy 66.78863 -465.56195) (xy 66.792517 -465.616306) (xy 66.792458 -465.617129) (xy 67.445446 -465.617129)
			(xy 67.44933 -465.562768) (xy 67.460911 -465.509514) (xy 67.479954 -465.45845) (xy 67.50607 -465.410616)
			(xy 67.538728 -465.366986) (xy 67.577263 -465.328448) (xy 67.62089 -465.295786) (xy 67.668722 -465.269666)
			(xy 67.719785 -465.25062) (xy 67.773038 -465.239035) (xy 67.827398 -465.235146) (xy 67.881758 -465.239034)
			(xy 67.935012 -465.250619) (xy 67.986074 -465.269665) (xy 68.033906 -465.295784) (xy 68.055998 -465.311744)
			(xy 68.07501 -465.32534) (xy 68.116893 -465.346072) (xy 68.161861 -465.358798) (xy 68.208398 -465.363088)
			(xy 68.254935 -465.358798) (xy 68.299903 -465.346072) (xy 68.341786 -465.32534) (xy 68.360798 -465.311744)
			(xy 68.382931 -465.295849) (xy 68.430754 -465.269734) (xy 68.481807 -465.250691) (xy 68.53505 -465.239108)
			(xy 68.5894 -465.235221) (xy 68.643749 -465.239108) (xy 68.696993 -465.250691) (xy 68.748045 -465.269734)
			(xy 68.795868 -465.295848) (xy 68.839487 -465.328503) (xy 68.878015 -465.367034) (xy 68.910667 -465.410656)
			(xy 68.936778 -465.458481) (xy 68.955817 -465.509535) (xy 68.967396 -465.562779) (xy 68.971279 -465.617129)
			(xy 68.967388 -465.671478) (xy 68.955801 -465.724721) (xy 68.936754 -465.775772) (xy 68.910636 -465.823593)
			(xy 68.877978 -465.86721) (xy 68.839444 -465.905734) (xy 68.79582 -465.938383) (xy 68.747993 -465.96449)
			(xy 68.696937 -465.983525) (xy 68.643692 -465.9951) (xy 68.589342 -465.998979) (xy 68.534993 -465.995084)
			(xy 68.481751 -465.983493) (xy 68.430702 -465.964442) (xy 68.382883 -465.93832) (xy 68.360798 -465.92236)
			(xy 68.341786 -465.908764) (xy 68.299903 -465.888032) (xy 68.254935 -465.875306) (xy 68.208398 -465.871016)
			(xy 68.161861 -465.875306) (xy 68.116893 -465.888032) (xy 68.07501 -465.908764) (xy 68.055998 -465.92236)
			(xy 68.033955 -465.938385) (xy 67.986127 -465.964511) (xy 67.935067 -465.983565) (xy 67.881815 -465.995158)
			(xy 67.827456 -465.999054) (xy 67.773095 -465.995174) (xy 67.71984 -465.983596) (xy 67.668775 -465.964557)
			(xy 67.620939 -465.938445) (xy 67.577306 -465.90579) (xy 67.538765 -465.867258) (xy 67.506101 -465.823632)
			(xy 67.479978 -465.775802) (xy 67.460928 -465.724741) (xy 67.449338 -465.671489) (xy 67.445446 -465.617129)
			(xy 66.792458 -465.617129) (xy 66.788628 -465.670662) (xy 66.777043 -465.72391) (xy 66.757997 -465.774968)
			(xy 66.731879 -465.822796) (xy 66.699219 -465.866419) (xy 66.660683 -465.90495) (xy 66.617056 -465.937605)
			(xy 66.569225 -465.963717) (xy 66.518164 -465.982757) (xy 66.464914 -465.994335) (xy 66.410558 -465.998217)
			(xy 66.356203 -465.994323) (xy 66.302955 -465.982733) (xy 66.251899 -465.963682) (xy 66.204074 -465.937559)
			(xy 66.181986 -465.921598) (xy 66.162974 -465.908002) (xy 66.121091 -465.88727) (xy 66.076123 -465.874544)
			(xy 66.029586 -465.870254) (xy 65.983049 -465.874544) (xy 65.938081 -465.88727) (xy 65.896198 -465.908002)
			(xy 65.877186 -465.921598) (xy 65.855108 -465.93757) (xy 65.807282 -465.96369) (xy 65.756227 -465.982737)
			(xy 65.70298 -465.994325) (xy 65.648626 -465.998216) (xy 65.594272 -465.994332) (xy 65.541023 -465.982752)
			(xy 65.489965 -465.963712) (xy 65.442136 -465.937598) (xy 65.398511 -465.904944) (xy 65.359977 -465.866413)
			(xy 65.327319 -465.822791) (xy 65.301202 -465.774964) (xy 65.282157 -465.723907) (xy 65.270572 -465.67066)
			(xy 65.266684 -465.616306) (xy 64.717137 -465.616306) (xy 64.713248 -465.670666) (xy 64.701662 -465.72392)
			(xy 64.682614 -465.774982) (xy 64.656492 -465.822813) (xy 64.623829 -465.866439) (xy 64.585288 -465.904973)
			(xy 64.541656 -465.937628) (xy 64.49382 -465.963742) (xy 64.442755 -465.982781) (xy 64.3895 -465.994358)
			(xy 64.335139 -465.998237) (xy 64.280779 -465.99434) (xy 64.227527 -465.982746) (xy 64.176468 -465.963691)
			(xy 64.128641 -465.937562) (xy 64.106552 -465.921598) (xy 64.08754 -465.908002) (xy 64.045657 -465.88727)
			(xy 64.000689 -465.874544) (xy 63.954152 -465.870254) (xy 63.907615 -465.874544) (xy 63.862647 -465.88727)
			(xy 63.820764 -465.908002) (xy 63.801752 -465.921598) (xy 63.779674 -465.937567) (xy 63.731852 -465.963682)
			(xy 63.680799 -465.982724) (xy 63.627556 -465.994308) (xy 63.573207 -465.998196) (xy 63.518857 -465.99431)
			(xy 63.465614 -465.982728) (xy 63.414561 -465.963687) (xy 63.366737 -465.937575) (xy 63.323116 -465.904922)
			(xy 63.284587 -465.866393) (xy 63.251932 -465.822774) (xy 63.225818 -465.774951) (xy 63.206775 -465.723898)
			(xy 63.195192 -465.670655) (xy 63.191304 -465.616306) (xy 42.026144 -465.616306) (xy 42.021555 -465.631926)
			(xy 41.984725 -465.733212) (xy 41.940717 -465.831591) (xy 41.889758 -465.926556) (xy 41.83211 -466.017616)
			(xy 41.768071 -466.104301) (xy 41.697972 -466.186163) (xy 41.622176 -466.26278) (xy 41.541073 -466.333755)
			(xy 41.455082 -466.398723) (xy 41.364647 -466.457347) (xy 41.270236 -466.509326) (xy 41.172335 -466.55439)
			(xy 41.071452 -466.592307) (xy 40.968105 -466.62288) (xy 40.86283 -466.645954) (xy 40.75617 -466.661407)
			(xy 40.648675 -466.66916) (xy 40.594788 -466.669628) (xy 26.983182 -466.669628) (xy 22.766528 -462.45272)
			(xy 22.766528 -444.148972) (xy 22.825964 -444.089536) (xy 22.825964 -442.448442) (xy 22.667976 -442.290454)
			(xy 22.667976 -413.544766) (xy 22.141688 -413.018478) (xy 21.497036 -413.018478) (xy 21.480417 -413.019014)
			(xy 21.448306 -413.027598) (xy 21.419506 -413.044192) (xy 21.407374 -413.055562) (xy 14.962632 -419.500558)
			(xy 14.962632 -447.480182) (xy 13.597128 -448.845686) (xy 13.584796 -448.858962) (xy 13.567443 -448.890752)
			(xy 13.559685 -448.926129) (xy 13.560298 -448.944238) (xy 13.560298 -448.945762) (xy 13.564333 -449.010454)
			(xy 13.565461 -449.140081) (xy 13.558671 -449.269535) (xy 13.543989 -449.398333) (xy 13.52147 -449.525993)
			(xy 13.491198 -449.652041) (xy 13.453285 -449.776005) (xy 13.407873 -449.897422) (xy 13.355133 -450.01584)
			(xy 13.305154 -450.111815) (xy 20.03353 -450.111815) (xy 20.037525 -450.057789) (xy 20.049123 -450.004872)
			(xy 20.06809 -449.954127) (xy 20.094045 -449.906577) (xy 20.126467 -449.863176) (xy 20.145248 -449.843652)
			(xy 20.16051 -449.827612) (xy 20.185864 -449.791322) (xy 20.204544 -449.751187) (xy 20.215984 -449.708421)
			(xy 20.219838 -449.66432) (xy 20.215991 -449.620218) (xy 20.204557 -449.577451) (xy 20.185884 -449.537312)
			(xy 20.160536 -449.501018) (xy 20.145248 -449.485004) (xy 20.126375 -449.465373) (xy 20.093818 -449.421722)
			(xy 20.0678 -449.373884) (xy 20.048848 -449.322833) (xy 20.037349 -449.269606) (xy 20.033535 -449.215284)
			(xy 20.037485 -449.160973) (xy 20.049118 -449.107774) (xy 20.068198 -449.056771) (xy 20.094336 -449.008999)
			(xy 20.127002 -448.96543) (xy 20.165532 -448.926948) (xy 20.209143 -448.894337) (xy 20.256947 -448.868259)
			(xy 20.307975 -448.849243) (xy 20.361187 -448.837677) (xy 20.415504 -448.833795) (xy 20.469821 -448.837677)
			(xy 20.523033 -448.849243) (xy 20.574061 -448.868259) (xy 20.621865 -448.894337) (xy 20.665476 -448.926948)
			(xy 20.704006 -448.96543) (xy 20.736672 -449.008999) (xy 20.76281 -449.056771) (xy 20.78189 -449.107774)
			(xy 20.793523 -449.160973) (xy 20.797473 -449.215284) (xy 20.793659 -449.269606) (xy 20.78216 -449.322833)
			(xy 20.763208 -449.373884) (xy 20.73719 -449.421722) (xy 20.704633 -449.465373) (xy 20.68576 -449.485004)
			(xy 20.670441 -449.500993) (xy 20.645089 -449.537292) (xy 20.626412 -449.577437) (xy 20.614976 -449.620211)
			(xy 20.611128 -449.66432) (xy 20.614983 -449.708428) (xy 20.626425 -449.751201) (xy 20.645109 -449.791342)
			(xy 20.670467 -449.827638) (xy 20.68576 -449.843652) (xy 20.70454 -449.863177) (xy 20.736961 -449.906578)
			(xy 20.762915 -449.954128) (xy 20.781882 -450.004873) (xy 20.79348 -450.05779) (xy 20.797475 -450.111815)
			(xy 20.793787 -450.165863) (xy 20.78249 -450.218845) (xy 20.763812 -450.269696) (xy 20.738127 -450.317393)
			(xy 20.705954 -450.360978) (xy 20.687284 -450.380608) (xy 20.672243 -450.396602) (xy 20.647314 -450.432738)
			(xy 20.628959 -450.472617) (xy 20.617722 -450.515055) (xy 20.613938 -450.558792) (xy 20.61772 -450.602529)
			(xy 20.628953 -450.644968) (xy 20.647306 -450.684848) (xy 20.672233 -450.720986) (xy 20.687284 -450.73697)
			(xy 20.706592 -450.757274) (xy 20.739649 -450.80251) (xy 20.765734 -450.852096) (xy 20.784286 -450.904963)
			(xy 20.794906 -450.959975) (xy 20.797365 -451.015949) (xy 20.791611 -451.071681) (xy 20.777767 -451.125972)
			(xy 20.756131 -451.177654) (xy 20.727169 -451.225615) (xy 20.691503 -451.268825) (xy 20.649901 -451.306353)
			(xy 20.603256 -451.337393) (xy 20.552574 -451.361276) (xy 20.498943 -451.37749) (xy 20.443518 -451.385685)
			(xy 20.38749 -451.385685) (xy 20.332065 -451.37749) (xy 20.278434 -451.361276) (xy 20.227752 -451.337393)
			(xy 20.181107 -451.306353) (xy 20.139505 -451.268825) (xy 20.103839 -451.225615) (xy 20.074877 -451.177654)
			(xy 20.053241 -451.125972) (xy 20.039397 -451.071681) (xy 20.033643 -451.015949) (xy 20.036102 -450.959975)
			(xy 20.046722 -450.904963) (xy 20.065274 -450.852096) (xy 20.091359 -450.80251) (xy 20.124416 -450.757274)
			(xy 20.143724 -450.73697) (xy 20.158818 -450.721011) (xy 20.183803 -450.684888) (xy 20.202201 -450.645004)
			(xy 20.213464 -450.602551) (xy 20.217254 -450.558792) (xy 20.213461 -450.515034) (xy 20.202196 -450.472581)
			(xy 20.183795 -450.432699) (xy 20.158808 -450.396577) (xy 20.143724 -450.380608) (xy 20.125053 -450.360979)
			(xy 20.092879 -450.317394) (xy 20.067194 -450.269697) (xy 20.048515 -450.218846) (xy 20.037218 -450.165863)
			(xy 20.03353 -450.111815) (xy 13.305154 -450.111815) (xy 13.295259 -450.130816) (xy 13.228477 -450.241922)
			(xy 13.155034 -450.348743) (xy 13.075206 -450.45088) (xy 12.989291 -450.547951) (xy 12.897608 -450.639595)
			(xy 12.8005 -450.72547) (xy 12.698329 -450.805255) (xy 12.591478 -450.878652) (xy 12.480344 -450.945387)
			(xy 12.365342 -451.005212) (xy 12.246902 -451.057903) (xy 12.125465 -451.103263) (xy 12.001485 -451.141124)
			(xy 11.875425 -451.171343) (xy 11.747755 -451.193808) (xy 11.618951 -451.208435) (xy 11.489494 -451.21517)
			(xy 11.359868 -451.213988) (xy 11.230555 -451.204892) (xy 11.10204 -451.187917) (xy 10.9748 -451.163126)
			(xy 10.849312 -451.130612) (xy 10.726044 -451.090496) (xy 10.605455 -451.042928) (xy 10.487996 -450.988085)
			(xy 10.374105 -450.926172) (xy 10.264207 -450.85742) (xy 10.158712 -450.782085) (xy 10.058015 -450.700449)
			(xy 9.96249 -450.612817) (xy 9.872494 -450.519516) (xy 9.830054 -450.470524) (xy 9.8154 -450.454054)
			(xy 9.781446 -450.425944) (xy 9.743147 -450.404121) (xy 9.701654 -450.389241) (xy 9.658214 -450.381751)
			(xy 9.614134 -450.381878) (xy 9.570738 -450.389616) (xy 9.529331 -450.404733) (xy 9.491157 -450.426776)
			(xy 9.473946 -450.440552) (xy 7.642352 -450.440552) (xy 7.546848 -450.483986) (xy 7.529068 -450.504052)
			(xy 7.485078 -450.552744) (xy 7.391952 -450.645216) (xy 7.29329 -450.731755) (xy 7.189467 -450.812031)
			(xy 7.080881 -450.885736) (xy 6.967947 -450.952589) (xy 6.851098 -451.012334) (xy 6.730779 -451.064743)
			(xy 6.60745 -451.109615) (xy 6.481585 -451.146779) (xy 6.353663 -451.176093) (xy 6.224173 -451.197444)
			(xy 6.093612 -451.210751) (xy 5.962478 -451.215962) (xy 5.896864 -451.214998) (xy 5.87436 -451.214979)
			(xy 5.8299 -451.221915) (xy 5.787357 -451.236573) (xy 5.74806 -451.258495) (xy 5.713239 -451.286995)
			(xy 5.683982 -451.321183) (xy 5.661204 -451.35999) (xy 5.645618 -451.402202) (xy 5.637709 -451.446499)
			(xy 5.637276 -451.468998) (xy 5.637276 -453.340924) (xy 10.339314 -453.340924) (xy 10.339314 -453.247052)
			(xy 10.347275 -453.153518) (xy 10.363139 -453.060996) (xy 10.386793 -452.970153) (xy 10.418065 -452.881644)
			(xy 10.456731 -452.796105) (xy 10.502512 -452.714153) (xy 10.555078 -452.636379) (xy 10.614051 -452.563344)
			(xy 10.679004 -452.495572) (xy 10.749471 -452.433553) (xy 10.824944 -452.377734) (xy 10.904879 -452.328516)
			(xy 10.9887 -452.286254) (xy 11.075803 -452.251254) (xy 11.16556 -452.223766) (xy 11.257325 -452.203989)
			(xy 11.350437 -452.192066) (xy 11.444224 -452.188082) (xy 11.538011 -452.192066) (xy 11.631123 -452.203989)
			(xy 11.722888 -452.223766) (xy 11.812645 -452.251254) (xy 11.899748 -452.286254) (xy 11.983569 -452.328516)
			(xy 12.063504 -452.377734) (xy 12.138977 -452.433553) (xy 12.209444 -452.495572) (xy 12.274397 -452.563344)
			(xy 12.33337 -452.636379) (xy 12.385936 -452.714153) (xy 12.431717 -452.796105) (xy 12.470383 -452.881644)
			(xy 12.501655 -452.970153) (xy 12.525309 -453.060996) (xy 12.541173 -453.153518) (xy 12.549134 -453.247052)
			(xy 12.549632 -453.293988) (xy 12.549134 -453.340924) (xy 12.541173 -453.434458) (xy 12.525309 -453.52698)
			(xy 12.501655 -453.617823) (xy 12.470383 -453.706332) (xy 12.431717 -453.791871) (xy 12.385936 -453.873823)
			(xy 12.33337 -453.951597) (xy 12.274397 -454.024632) (xy 12.209444 -454.092404) (xy 12.138977 -454.154423)
			(xy 12.063504 -454.210242) (xy 11.983569 -454.25946) (xy 11.899748 -454.301722) (xy 11.812645 -454.336722)
			(xy 11.722888 -454.36421) (xy 11.631123 -454.383987) (xy 11.538011 -454.39591) (xy 11.444224 -454.399895)
			(xy 11.350437 -454.39591) (xy 11.257325 -454.383987) (xy 11.16556 -454.36421) (xy 11.075803 -454.336722)
			(xy 10.9887 -454.301722) (xy 10.904879 -454.25946) (xy 10.824944 -454.210242) (xy 10.749471 -454.154423)
			(xy 10.679004 -454.092404) (xy 10.614051 -454.024632) (xy 10.555078 -453.951597) (xy 10.502512 -453.873823)
			(xy 10.456731 -453.791871) (xy 10.418065 -453.706332) (xy 10.386793 -453.617823) (xy 10.363139 -453.52698)
			(xy 10.347275 -453.434458) (xy 10.339314 -453.340924) (xy 5.637276 -453.340924) (xy 5.637276 -457.541068)
			(xy 10.339314 -457.541068) (xy 10.339314 -457.447196) (xy 10.347275 -457.353662) (xy 10.363139 -457.26114)
			(xy 10.386793 -457.170297) (xy 10.418065 -457.081788) (xy 10.456731 -456.996249) (xy 10.502512 -456.914297)
			(xy 10.555078 -456.836523) (xy 10.614051 -456.763488) (xy 10.679004 -456.695716) (xy 10.749471 -456.633697)
			(xy 10.824944 -456.577878) (xy 10.904879 -456.52866) (xy 10.9887 -456.486398) (xy 11.075803 -456.451398)
			(xy 11.16556 -456.42391) (xy 11.257325 -456.404133) (xy 11.350437 -456.39221) (xy 11.444224 -456.388226)
			(xy 11.538011 -456.39221) (xy 11.631123 -456.404133) (xy 11.722888 -456.42391) (xy 11.812645 -456.451398)
			(xy 11.899748 -456.486398) (xy 11.983569 -456.52866) (xy 12.063504 -456.577878) (xy 12.138977 -456.633697)
			(xy 12.209444 -456.695716) (xy 12.274397 -456.763488) (xy 12.33337 -456.836523) (xy 12.385936 -456.914297)
			(xy 12.431717 -456.996249) (xy 12.470383 -457.081788) (xy 12.501655 -457.170297) (xy 12.525309 -457.26114)
			(xy 12.541173 -457.353662) (xy 12.549134 -457.447196) (xy 12.549632 -457.494132) (xy 12.549134 -457.541068)
			(xy 12.541173 -457.634602) (xy 12.525309 -457.727124) (xy 12.501655 -457.817967) (xy 12.470383 -457.906476)
			(xy 12.431717 -457.992015) (xy 12.385936 -458.073967) (xy 12.33337 -458.151741) (xy 12.274397 -458.224776)
			(xy 12.209444 -458.292548) (xy 12.138977 -458.354567) (xy 12.063504 -458.410386) (xy 11.983569 -458.459604)
			(xy 11.899748 -458.501866) (xy 11.812645 -458.536866) (xy 11.722888 -458.564354) (xy 11.631123 -458.584131)
			(xy 11.538011 -458.596054) (xy 11.444224 -458.600039) (xy 11.350437 -458.596054) (xy 11.257325 -458.584131)
			(xy 11.16556 -458.564354) (xy 11.075803 -458.536866) (xy 10.9887 -458.501866) (xy 10.904879 -458.459604)
			(xy 10.824944 -458.410386) (xy 10.749471 -458.354567) (xy 10.679004 -458.292548) (xy 10.614051 -458.224776)
			(xy 10.555078 -458.151741) (xy 10.502512 -458.073967) (xy 10.456731 -457.992015) (xy 10.418065 -457.906476)
			(xy 10.386793 -457.817967) (xy 10.363139 -457.727124) (xy 10.347275 -457.634602) (xy 10.339314 -457.541068)
			(xy 5.637276 -457.541068) (xy 5.637276 -459.482698) (xy 5.732526 -459.577948) (xy 5.795518 -459.577948)
			(xy 5.799836 -459.577694) (xy 5.861726 -459.573919) (xy 5.985726 -459.572717) (xy 6.109584 -459.578759)
			(xy 6.232878 -459.592026) (xy 6.355187 -459.612473) (xy 6.476092 -459.640029) (xy 6.595181 -459.674601)
			(xy 6.712048 -459.71607) (xy 6.769354 -459.739746) (xy 6.827925 -459.764992) (xy 6.942241 -459.82158)
			(xy 7.05295 -459.884937) (xy 7.159652 -459.954832) (xy 7.26196 -460.031014) (xy 7.359505 -460.113206)
			(xy 7.451934 -460.201111) (xy 7.538914 -460.294413) (xy 7.620129 -460.392773) (xy 7.695286 -460.495836)
			(xy 7.764113 -460.60323) (xy 7.826362 -460.714565) (xy 7.881807 -460.829441) (xy 7.930249 -460.947441)
			(xy 7.971512 -461.068139) (xy 8.005446 -461.191098) (xy 8.03193 -461.315875) (xy 8.050867 -461.442017)
			(xy 8.062189 -461.56907) (xy 8.0645 -461.632808) (xy 8.065458 -461.649146) (xy 8.074656 -461.680544)
			(xy 8.091541 -461.708568) (xy 8.115002 -461.731372) (xy 8.143494 -461.747454) (xy 8.175141 -461.755755)
			(xy 8.1915 -461.756252) (xy 9.195816 -461.756252) (xy 9.212467 -461.755755) (xy 9.244633 -461.747131)
			(xy 9.27347 -461.730473) (xy 9.297013 -461.706919) (xy 9.313655 -461.678074) (xy 9.322264 -461.645903)
			(xy 9.322816 -461.629252) (xy 9.322816 -459.572868) (xy 13.565632 -459.572868) (xy 13.565632 -463.815176)
			(xy 11.227308 -463.815176) (xy 10.593324 -464.44916) (xy 3.60934 -464.44916) (xy 1.958594 -462.798414)
			(xy 1.941953 -462.78248) (xy 1.904041 -462.75631) (xy 1.862032 -462.737402) (xy 1.817303 -462.726376)
			(xy 1.771319 -462.723593) (xy 1.725587 -462.729145) (xy 1.681605 -462.742849) (xy 1.640813 -462.764257)
			(xy 1.604548 -462.792667) (xy 1.573999 -462.827148) (xy 1.550165 -462.866571) (xy 1.533828 -462.909645)
			(xy 1.525523 -462.954958) (xy 1.525016 -462.977992) (xy 1.525016 -467.382924) (xy 63.19128 -467.382924)
			(xy 63.195164 -467.328571) (xy 63.206744 -467.275324) (xy 63.225784 -467.224266) (xy 63.251896 -467.176439)
			(xy 63.284549 -467.132814) (xy 63.323078 -467.09428) (xy 63.366699 -467.061621) (xy 63.414523 -467.035503)
			(xy 63.465578 -467.016457) (xy 63.518824 -467.004871) (xy 63.573177 -467.00098) (xy 63.62753 -467.004864)
			(xy 63.680777 -467.016444) (xy 63.731834 -467.035484) (xy 63.779662 -467.061596) (xy 63.801752 -467.077552)
			(xy 63.820764 -467.091148) (xy 63.862647 -467.11188) (xy 63.907615 -467.124606) (xy 63.954152 -467.128896)
			(xy 64.000689 -467.124606) (xy 64.045657 -467.11188) (xy 64.08754 -467.091148) (xy 64.106552 -467.077552)
			(xy 64.128679 -467.061642) (xy 64.176505 -467.035519) (xy 64.227563 -467.016469) (xy 64.280812 -467.004879)
			(xy 64.335169 -467.000987) (xy 64.389526 -467.00487) (xy 64.442777 -467.016451) (xy 64.493838 -467.035493)
			(xy 64.541668 -467.061608) (xy 64.585295 -467.094265) (xy 64.62383 -467.132799) (xy 64.656488 -467.176425)
			(xy 64.682604 -467.224256) (xy 64.701647 -467.275316) (xy 64.713229 -467.328567) (xy 64.717113 -467.382924)
			(xy 65.26666 -467.382924) (xy 65.270544 -467.328566) (xy 65.282125 -467.275315) (xy 65.301167 -467.224253)
			(xy 65.327282 -467.176422) (xy 65.359939 -467.132794) (xy 65.398473 -467.094257) (xy 65.442098 -467.061598)
			(xy 65.489928 -467.035479) (xy 65.540988 -467.016433) (xy 65.594239 -467.004848) (xy 65.648596 -467.00096)
			(xy 65.702954 -467.004847) (xy 65.756205 -467.016431) (xy 65.807265 -467.035476) (xy 65.855095 -467.061593)
			(xy 65.877186 -467.077552) (xy 65.896198 -467.091148) (xy 65.938081 -467.11188) (xy 65.983049 -467.124606)
			(xy 66.029586 -467.128896) (xy 66.076123 -467.124606) (xy 66.121091 -467.11188) (xy 66.162974 -467.091148)
			(xy 66.181986 -467.077552) (xy 66.204112 -467.061645) (xy 66.251936 -467.035527) (xy 66.302991 -467.016482)
			(xy 66.356236 -467.004896) (xy 66.410588 -467.001007) (xy 66.46494 -467.004893) (xy 66.518186 -467.016475)
			(xy 66.569242 -467.035517) (xy 66.617068 -467.061632) (xy 66.66069 -467.094287) (xy 66.69922 -467.132819)
			(xy 66.731875 -467.176442) (xy 66.757988 -467.224269) (xy 66.777028 -467.275325) (xy 66.788609 -467.328571)
			(xy 66.792493 -467.382924) (xy 66.792446 -467.383587) (xy 67.445502 -467.383587) (xy 67.449392 -467.329235)
			(xy 67.460977 -467.27599) (xy 67.480022 -467.224935) (xy 67.50614 -467.177111) (xy 67.538798 -467.133491)
			(xy 67.577331 -467.094963) (xy 67.620956 -467.062311) (xy 67.668784 -467.0362) (xy 67.719841 -467.017162)
			(xy 67.773088 -467.005584) (xy 67.82744 -467.001702) (xy 67.881792 -467.005596) (xy 67.935036 -467.017185)
			(xy 67.986089 -467.036233) (xy 68.033911 -467.062354) (xy 68.055998 -467.078314) (xy 68.07501 -467.09191)
			(xy 68.116893 -467.112642) (xy 68.161861 -467.125368) (xy 68.208398 -467.129658) (xy 68.254935 -467.125368)
			(xy 68.299903 -467.112642) (xy 68.341786 -467.09191) (xy 68.360798 -467.078314) (xy 68.382866 -467.062324)
			(xy 68.430693 -467.0362) (xy 68.481751 -467.017149) (xy 68.535 -467.005559) (xy 68.589358 -467.001665)
			(xy 68.643716 -467.005547) (xy 68.696968 -467.017125) (xy 68.74803 -467.036165) (xy 68.795863 -467.062278)
			(xy 68.839492 -467.094933) (xy 68.87803 -467.133466) (xy 68.910692 -467.17709) (xy 68.936812 -467.224919)
			(xy 68.955859 -467.275979) (xy 68.967446 -467.329229) (xy 68.971335 -467.383587) (xy 68.967449 -467.437945)
			(xy 68.955866 -467.491196) (xy 68.936823 -467.542257) (xy 68.910706 -467.590088) (xy 68.878047 -467.633714)
			(xy 68.839512 -467.672249) (xy 68.795885 -467.704907) (xy 68.748054 -467.731024) (xy 68.696993 -467.750067)
			(xy 68.643742 -467.76165) (xy 68.589384 -467.765535) (xy 68.535026 -467.761645) (xy 68.481776 -467.750058)
			(xy 68.430717 -467.731011) (xy 68.382888 -467.70489) (xy 68.360798 -467.68893) (xy 68.341786 -467.675334)
			(xy 68.299903 -467.654602) (xy 68.254935 -467.641876) (xy 68.208398 -467.637586) (xy 68.161861 -467.641876)
			(xy 68.116893 -467.654602) (xy 68.07501 -467.675334) (xy 68.055998 -467.68893) (xy 68.033889 -467.70486)
			(xy 67.986065 -467.730978) (xy 67.935011 -467.750023) (xy 67.881766 -467.761608) (xy 67.827414 -467.765498)
			(xy 67.773061 -467.761612) (xy 67.719815 -467.750031) (xy 67.66876 -467.730989) (xy 67.620934 -467.704875)
			(xy 67.577311 -467.67222) (xy 67.53878 -467.633689) (xy 67.506125 -467.590067) (xy 67.480011 -467.542241)
			(xy 67.460969 -467.491185) (xy 67.449388 -467.437939) (xy 67.445502 -467.383587) (xy 66.792446 -467.383587)
			(xy 66.788602 -467.437276) (xy 66.777015 -467.490521) (xy 66.757968 -467.541575) (xy 66.731849 -467.589398)
			(xy 66.699189 -467.633017) (xy 66.660654 -467.671544) (xy 66.617027 -467.704194) (xy 66.569198 -467.730303)
			(xy 66.51814 -467.749339) (xy 66.464893 -467.760914) (xy 66.41054 -467.764793) (xy 66.356188 -467.760897)
			(xy 66.302944 -467.749305) (xy 66.251892 -467.730253) (xy 66.204072 -467.704129) (xy 66.181986 -467.688168)
			(xy 66.162974 -467.674572) (xy 66.121091 -467.65384) (xy 66.076123 -467.641114) (xy 66.029586 -467.636824)
			(xy 65.983049 -467.641114) (xy 65.938081 -467.65384) (xy 65.896198 -467.674572) (xy 65.877186 -467.688168)
			(xy 65.855136 -467.704181) (xy 65.807309 -467.730304) (xy 65.756251 -467.749355) (xy 65.703001 -467.760946)
			(xy 65.648644 -467.76484) (xy 65.594286 -467.760959) (xy 65.541034 -467.74938) (xy 65.489971 -467.730341)
			(xy 65.442139 -467.704228) (xy 65.398509 -467.671574) (xy 65.359971 -467.633043) (xy 65.327308 -467.589419)
			(xy 65.301187 -467.54159) (xy 65.282139 -467.490532) (xy 65.270551 -467.437281) (xy 65.26666 -467.382924)
			(xy 64.717113 -467.382924) (xy 64.713222 -467.437281) (xy 64.701634 -467.49053) (xy 64.682584 -467.541588)
			(xy 64.656462 -467.589415) (xy 64.623799 -467.633037) (xy 64.585259 -467.671566) (xy 64.541628 -467.704218)
			(xy 64.493794 -467.730327) (xy 64.442731 -467.749363) (xy 64.389478 -467.760937) (xy 64.335121 -467.764813)
			(xy 64.280765 -467.760914) (xy 64.227517 -467.749318) (xy 64.176462 -467.730261) (xy 64.128638 -467.704132)
			(xy 64.106552 -467.688168) (xy 64.08754 -467.674572) (xy 64.045657 -467.65384) (xy 64.000689 -467.641114)
			(xy 63.954152 -467.636824) (xy 63.907615 -467.641114) (xy 63.862647 -467.65384) (xy 63.820764 -467.674572)
			(xy 63.801752 -467.688168) (xy 63.779702 -467.704178) (xy 63.731878 -467.730296) (xy 63.680823 -467.749342)
			(xy 63.627577 -467.760929) (xy 63.573225 -467.76482) (xy 63.518872 -467.760936) (xy 63.465624 -467.749356)
			(xy 63.414567 -467.730317) (xy 63.366739 -467.704205) (xy 63.323114 -467.671552) (xy 63.28458 -467.633023)
			(xy 63.251922 -467.589402) (xy 63.225804 -467.541577) (xy 63.206757 -467.490522) (xy 63.195171 -467.437277)
			(xy 63.19128 -467.382924) (xy 1.525016 -467.382924) (xy 1.525016 -471.172032) (xy 6.671831 -471.172032)
			(xy 6.675786 -471.080195) (xy 6.687621 -470.989038) (xy 6.707248 -470.899235) (xy 6.734522 -470.811453)
			(xy 6.769242 -470.726339) (xy 6.81115 -470.644526) (xy 6.859936 -470.566618) (xy 6.915239 -470.493193)
			(xy 6.976649 -470.424793) (xy 7.043711 -470.361926) (xy 7.11593 -470.305056) (xy 7.19277 -470.254605)
			(xy 7.273663 -470.210946) (xy 7.358009 -470.174403) (xy 7.445185 -470.145246) (xy 7.534544 -470.123692)
			(xy 7.625425 -470.109898) (xy 7.717156 -470.103968) (xy 7.809057 -470.105946) (xy 7.900448 -470.115817)
			(xy 7.990652 -470.133507) (xy 8.079001 -470.158887) (xy 8.164841 -470.191767) (xy 8.247537 -470.231905)
			(xy 8.326477 -470.279004) (xy 8.401075 -470.332714) (xy 8.470781 -470.392638) (xy 8.535076 -470.458332)
			(xy 8.593487 -470.52931) (xy 8.645579 -470.605047) (xy 8.690968 -470.684982) (xy 8.729318 -470.768522)
			(xy 8.760343 -470.85505) (xy 8.783816 -470.943925) (xy 8.799562 -471.034489) (xy 8.807464 -471.126071)
			(xy 8.807958 -471.172032) (xy 8.807464 -471.217993) (xy 8.799562 -471.309575) (xy 8.783816 -471.400139)
			(xy 8.760343 -471.489014) (xy 8.729318 -471.575542) (xy 8.690968 -471.659082) (xy 8.645579 -471.739017)
			(xy 8.593487 -471.814754) (xy 8.535076 -471.885732) (xy 8.470781 -471.951426) (xy 8.401075 -472.01135)
			(xy 8.326477 -472.06506) (xy 8.247537 -472.112159) (xy 8.164841 -472.152297) (xy 8.079001 -472.185177)
			(xy 7.990652 -472.210557) (xy 7.900448 -472.228247) (xy 7.809057 -472.238118) (xy 7.717156 -472.240096)
			(xy 7.625425 -472.234166) (xy 7.534544 -472.220372) (xy 7.445185 -472.198818) (xy 7.358009 -472.169661)
			(xy 7.273663 -472.133118) (xy 7.19277 -472.089459) (xy 7.11593 -472.039008) (xy 7.043711 -471.982138)
			(xy 6.976649 -471.919271) (xy 6.915239 -471.850871) (xy 6.859936 -471.777446) (xy 6.81115 -471.699538)
			(xy 6.769242 -471.617725) (xy 6.734522 -471.532611) (xy 6.707248 -471.444829) (xy 6.687621 -471.355026)
			(xy 6.675786 -471.263869) (xy 6.671831 -471.172032) (xy 1.525016 -471.172032) (xy 1.525016 -473.700094)
			(xy 11.59841 -473.700094) (xy 11.602414 -473.499986) (xy 11.614422 -473.300198) (xy 11.634414 -473.10105)
			(xy 11.662357 -472.902862) (xy 11.698207 -472.705951) (xy 11.741908 -472.510631) (xy 11.793387 -472.317217)
			(xy 11.852564 -472.126017) (xy 11.919344 -471.937337) (xy 11.993619 -471.751481) (xy 12.07527 -471.568745)
			(xy 12.164168 -471.389422) (xy 12.260168 -471.2138) (xy 12.363119 -471.042159) (xy 12.472854 -470.874775)
			(xy 12.589199 -470.711915) (xy 12.711966 -470.55384) (xy 12.840959 -470.400804) (xy 12.975972 -470.253052)
			(xy 13.116789 -470.110819) (xy 13.263183 -469.974335) (xy 13.414921 -469.843816) (xy 13.57176 -469.719474)
			(xy 13.733447 -469.601506) (xy 13.899726 -469.490101) (xy 14.070328 -469.385439) (xy 14.244981 -469.287686)
			(xy 14.423405 -469.196999) (xy 14.605315 -469.113523) (xy 14.790419 -469.037392) (xy 14.978421 -468.968728)
			(xy 15.169019 -468.907641) (xy 15.361909 -468.854229) (xy 15.556781 -468.808577) (xy 15.753324 -468.770758)
			(xy 15.951223 -468.740834) (xy 16.15016 -468.71885) (xy 16.349818 -468.704844) (xy 16.549876 -468.698838)
			(xy 16.750015 -468.70084) (xy 16.949913 -468.710849) (xy 17.14925 -468.728847) (xy 17.347708 -468.754806)
			(xy 17.544968 -468.788684) (xy 17.740715 -468.830428) (xy 17.934635 -468.87997) (xy 18.126418 -468.937231)
			(xy 18.315756 -469.00212) (xy 18.502346 -469.074532) (xy 18.68589 -469.154351) (xy 18.866093 -469.24145)
			(xy 19.042667 -469.335688) (xy 19.215329 -469.436917) (xy 19.383803 -469.544972) (xy 19.547819 -469.659681)
			(xy 19.707114 -469.780861) (xy 19.861433 -469.908316) (xy 20.010529 -470.041845) (xy 20.154163 -470.181231)
			(xy 20.292105 -470.326253) (xy 20.424135 -470.476677) (xy 20.550041 -470.632264) (xy 20.66962 -470.792763)
			(xy 20.782683 -470.957918) (xy 20.889047 -471.127465) (xy 20.988543 -471.301131) (xy 21.08101 -471.478639)
			(xy 21.166302 -471.659705) (xy 21.244281 -471.844038) (xy 21.314822 -472.031343) (xy 21.348077 -472.13164)
			(xy 70.723742 -472.13164) (xy 70.723742 -472.071704) (xy 70.731565 -472.012282) (xy 70.747078 -471.954389)
			(xy 70.770014 -471.899016) (xy 70.799981 -471.84711) (xy 70.836468 -471.79956) (xy 70.878848 -471.75718)
			(xy 70.926398 -471.720693) (xy 70.978304 -471.690726) (xy 71.033677 -471.66779) (xy 71.09157 -471.652277)
			(xy 71.150992 -471.644454) (xy 71.210928 -471.644454) (xy 71.27035 -471.652277) (xy 71.328243 -471.66779)
			(xy 71.383616 -471.690726) (xy 71.435522 -471.720693) (xy 71.483072 -471.75718) (xy 71.525452 -471.79956)
			(xy 71.561939 -471.84711) (xy 71.591906 -471.899016) (xy 71.614842 -471.954389) (xy 71.630355 -472.012282)
			(xy 71.638178 -472.071704) (xy 71.638668 -472.101672) (xy 71.638178 -472.13164) (xy 71.630355 -472.191062)
			(xy 71.614842 -472.248955) (xy 71.591906 -472.304328) (xy 71.561939 -472.356234) (xy 71.525452 -472.403784)
			(xy 71.483072 -472.446164) (xy 71.435522 -472.482651) (xy 71.383616 -472.512618) (xy 71.328243 -472.535554)
			(xy 71.27035 -472.551067) (xy 71.210928 -472.55889) (xy 71.150992 -472.55889) (xy 71.09157 -472.551067)
			(xy 71.033677 -472.535554) (xy 70.978304 -472.512618) (xy 70.926398 -472.482651) (xy 70.878848 -472.446164)
			(xy 70.836468 -472.403784) (xy 70.799981 -472.356234) (xy 70.770014 -472.304328) (xy 70.747078 -472.248955)
			(xy 70.731565 -472.191062) (xy 70.723742 -472.13164) (xy 21.348077 -472.13164) (xy 21.377813 -472.221321)
			(xy 21.433152 -472.413667) (xy 21.480752 -472.608072) (xy 21.520535 -472.804227) (xy 21.552438 -473.001817)
			(xy 21.57641 -473.200524) (xy 21.592413 -473.400032) (xy 21.600421 -473.60002) (xy 21.600568 -473.629478)
			(xy 70.656686 -473.629478) (xy 70.656686 -473.569542) (xy 70.664509 -473.51012) (xy 70.680022 -473.452227)
			(xy 70.702958 -473.396854) (xy 70.732925 -473.344948) (xy 70.769412 -473.297398) (xy 70.811792 -473.255018)
			(xy 70.859342 -473.218531) (xy 70.911248 -473.188564) (xy 70.966621 -473.165628) (xy 71.024514 -473.150115)
			(xy 71.083936 -473.142292) (xy 71.143872 -473.142292) (xy 71.203294 -473.150115) (xy 71.261187 -473.165628)
			(xy 71.31656 -473.188564) (xy 71.368466 -473.218531) (xy 71.416016 -473.255018) (xy 71.458396 -473.297398)
			(xy 71.494883 -473.344948) (xy 71.52485 -473.396854) (xy 71.547786 -473.452227) (xy 71.563299 -473.51012)
			(xy 71.571122 -473.569542) (xy 71.571612 -473.59951) (xy 73.941938 -473.59951) (xy 73.946009 -473.543888)
			(xy 73.958135 -473.489451) (xy 73.978058 -473.43736) (xy 74.005354 -473.388725) (xy 74.03944 -473.344582)
			(xy 74.079589 -473.305873) (xy 74.124947 -473.273422) (xy 74.174547 -473.247921) (xy 74.227331 -473.229914)
			(xy 74.282174 -473.219784) (xy 74.337908 -473.217747) (xy 74.393345 -473.223847) (xy 74.447302 -473.237953)
			(xy 74.498631 -473.259765) (xy 74.546237 -473.288819) (xy 74.589105 -473.324494) (xy 74.626322 -473.366031)
			(xy 74.657095 -473.412544) (xy 74.680767 -473.463041) (xy 74.696835 -473.516448) (xy 74.704955 -473.571624)
			(xy 74.705464 -473.59951) (xy 74.704955 -473.627396) (xy 74.696835 -473.682572) (xy 74.680767 -473.735979)
			(xy 74.657095 -473.786476) (xy 74.626322 -473.832989) (xy 74.589105 -473.874526) (xy 74.546237 -473.910201)
			(xy 74.498631 -473.939255) (xy 74.447302 -473.961067) (xy 74.393345 -473.975173) (xy 74.337908 -473.981273)
			(xy 74.282174 -473.979236) (xy 74.227331 -473.969106) (xy 74.174547 -473.951099) (xy 74.124947 -473.925598)
			(xy 74.079589 -473.893147) (xy 74.03944 -473.854438) (xy 74.005354 -473.810295) (xy 73.978058 -473.76166)
			(xy 73.958135 -473.709569) (xy 73.946009 -473.655132) (xy 73.941938 -473.59951) (xy 71.571612 -473.59951)
			(xy 71.571122 -473.629478) (xy 71.563299 -473.6889) (xy 71.547786 -473.746793) (xy 71.52485 -473.802166)
			(xy 71.494883 -473.854072) (xy 71.458396 -473.901622) (xy 71.416016 -473.944002) (xy 71.368466 -473.980489)
			(xy 71.31656 -474.010456) (xy 71.261187 -474.033392) (xy 71.203294 -474.048905) (xy 71.143872 -474.056728)
			(xy 71.083936 -474.056728) (xy 71.024514 -474.048905) (xy 70.966621 -474.033392) (xy 70.911248 -474.010456)
			(xy 70.859342 -473.980489) (xy 70.811792 -473.944002) (xy 70.769412 -473.901622) (xy 70.732925 -473.854072)
			(xy 70.702958 -473.802166) (xy 70.680022 -473.746793) (xy 70.664509 -473.6889) (xy 70.656686 -473.629478)
			(xy 21.600568 -473.629478) (xy 21.600922 -473.700094) (xy 21.600421 -473.800168) (xy 21.592413 -474.000156)
			(xy 21.57641 -474.199664) (xy 21.552438 -474.398371) (xy 21.520535 -474.595961) (xy 21.480752 -474.792116)
			(xy 21.433152 -474.986521) (xy 21.377813 -475.178867) (xy 21.314822 -475.368845) (xy 21.244281 -475.55615)
			(xy 21.166302 -475.740483) (xy 21.08101 -475.921549) (xy 20.988543 -476.099057) (xy 20.889047 -476.272723)
			(xy 20.782683 -476.44227) (xy 20.66962 -476.607425) (xy 20.550041 -476.767924) (xy 20.424135 -476.923511)
			(xy 20.292105 -477.073935) (xy 20.154163 -477.218957) (xy 20.010529 -477.358343) (xy 19.861433 -477.491872)
			(xy 19.707114 -477.619327) (xy 19.547819 -477.740507) (xy 19.383803 -477.855216) (xy 19.215329 -477.963271)
			(xy 19.042667 -478.0645) (xy 18.866093 -478.158738) (xy 18.68589 -478.245837) (xy 18.502346 -478.325656)
			(xy 18.315756 -478.398068) (xy 18.126418 -478.462957) (xy 17.934635 -478.520218) (xy 17.740715 -478.56976)
			(xy 17.544968 -478.611504) (xy 17.347708 -478.645382) (xy 17.14925 -478.671341) (xy 16.949913 -478.689339)
			(xy 16.750015 -478.699348) (xy 16.549876 -478.70135) (xy 16.349818 -478.695344) (xy 16.15016 -478.681338)
			(xy 15.951223 -478.659354) (xy 15.753324 -478.62943) (xy 15.556781 -478.591611) (xy 15.361909 -478.545959)
			(xy 15.169019 -478.492547) (xy 14.978421 -478.43146) (xy 14.790419 -478.362796) (xy 14.605315 -478.286665)
			(xy 14.423405 -478.203189) (xy 14.244981 -478.112502) (xy 14.070328 -478.014749) (xy 13.899726 -477.910087)
			(xy 13.733447 -477.798682) (xy 13.57176 -477.680714) (xy 13.414921 -477.556372) (xy 13.263183 -477.425853)
			(xy 13.116789 -477.289369) (xy 12.975972 -477.147136) (xy 12.840959 -476.999384) (xy 12.711966 -476.846348)
			(xy 12.589199 -476.688273) (xy 12.472854 -476.525413) (xy 12.363119 -476.358029) (xy 12.260168 -476.186388)
			(xy 12.164168 -476.010766) (xy 12.07527 -475.831443) (xy 11.993619 -475.648707) (xy 11.919344 -475.462851)
			(xy 11.852564 -475.274171) (xy 11.793387 -475.082971) (xy 11.741908 -474.889557) (xy 11.698207 -474.694237)
			(xy 11.662357 -474.497326) (xy 11.634414 -474.299138) (xy 11.614422 -474.09999) (xy 11.602414 -473.900202)
			(xy 11.59841 -473.700094) (xy 1.525016 -473.700094) (xy 1.525016 -476.244412) (xy 4.852416 -476.244412)
			(xy 6.707632 -476.244412) (xy 6.707632 -478.099628) (xy 4.852416 -478.099628) (xy 4.852416 -476.244412)
			(xy 1.525016 -476.244412) (xy 1.525016 -478.799906) (xy 74.39914 -478.799906) (xy 74.39914 -477.799908)
			(xy 74.399635 -477.715487) (xy 74.407549 -477.546829) (xy 74.423359 -477.378729) (xy 74.447032 -477.211554)
			(xy 74.478514 -477.045672) (xy 74.517737 -476.881448) (xy 74.564615 -476.719244) (xy 74.619044 -476.559414)
			(xy 74.680904 -476.402312) (xy 74.750061 -476.248282) (xy 74.826361 -476.097663) (xy 74.909637 -475.950785)
			(xy 74.999706 -475.807973) (xy 75.09637 -475.669539) (xy 75.199416 -475.535788) (xy 75.308619 -475.407014)
			(xy 75.423737 -475.2835) (xy 75.544518 -475.165518) (xy 75.670697 -475.053327) (xy 75.801995 -474.947173)
			(xy 75.938125 -474.847291) (xy 76.078787 -474.753898) (xy 76.223672 -474.667202) (xy 76.372461 -474.587392)
			(xy 76.524828 -474.514644) (xy 76.680437 -474.449117) (xy 76.838946 -474.390957) (xy 77.000007 -474.340289)
			(xy 77.163266 -474.297227) (xy 77.328364 -474.261865) (xy 77.494938 -474.23428) (xy 77.662622 -474.214533)
			(xy 77.831048 -474.202667) (xy 77.999844 -474.198709) (xy 78.16864 -474.202667) (xy 78.337066 -474.214533)
			(xy 78.50475 -474.23428) (xy 78.671324 -474.261865) (xy 78.836422 -474.297227) (xy 78.999681 -474.340289)
			(xy 79.160742 -474.390957) (xy 79.319251 -474.449117) (xy 79.47486 -474.514644) (xy 79.627227 -474.587392)
			(xy 79.776016 -474.667202) (xy 79.920901 -474.753898) (xy 80.061563 -474.847291) (xy 80.197693 -474.947173)
			(xy 80.328991 -475.053327) (xy 80.45517 -475.165518) (xy 80.575951 -475.2835) (xy 80.691069 -475.407014)
			(xy 80.800272 -475.535788) (xy 80.903318 -475.669539) (xy 80.999982 -475.807973) (xy 81.090051 -475.950785)
			(xy 81.173327 -476.097663) (xy 81.249627 -476.248282) (xy 81.318784 -476.402312) (xy 81.380644 -476.559414)
			(xy 81.435073 -476.719244) (xy 81.481951 -476.881448) (xy 81.521174 -477.045672) (xy 81.552656 -477.211554)
			(xy 81.576329 -477.378729) (xy 81.592139 -477.546829) (xy 81.600053 -477.715487) (xy 81.600548 -477.799908)
			(xy 81.600548 -478.799906) (xy 81.600053 -478.884327) (xy 81.592139 -479.052985) (xy 81.576329 -479.221085)
			(xy 81.552656 -479.38826) (xy 81.521174 -479.554142) (xy 81.481951 -479.718366) (xy 81.435073 -479.88057)
			(xy 81.380644 -480.0404) (xy 81.318784 -480.197502) (xy 81.249627 -480.351532) (xy 81.173327 -480.502151)
			(xy 81.090051 -480.649029) (xy 80.999982 -480.791841) (xy 80.903318 -480.930275) (xy 80.800272 -481.064026)
			(xy 80.691069 -481.1928) (xy 80.575951 -481.316314) (xy 80.45517 -481.434296) (xy 80.328991 -481.546487)
			(xy 80.197693 -481.652641) (xy 80.061563 -481.752523) (xy 79.920901 -481.845916) (xy 79.776016 -481.932612)
			(xy 79.627227 -482.012422) (xy 79.47486 -482.08517) (xy 79.319251 -482.150697) (xy 79.160742 -482.208857)
			(xy 78.999681 -482.259525) (xy 78.836422 -482.302587) (xy 78.671324 -482.337949) (xy 78.50475 -482.365534)
			(xy 78.337066 -482.385281) (xy 78.16864 -482.397147) (xy 77.999844 -482.401105) (xy 77.831048 -482.397147)
			(xy 77.662622 -482.385281) (xy 77.494938 -482.365534) (xy 77.328364 -482.337949) (xy 77.163266 -482.302587)
			(xy 77.000007 -482.259525) (xy 76.838946 -482.208857) (xy 76.680437 -482.150697) (xy 76.524828 -482.08517)
			(xy 76.372461 -482.012422) (xy 76.223672 -481.932612) (xy 76.078787 -481.845916) (xy 75.938125 -481.752523)
			(xy 75.801995 -481.652641) (xy 75.670697 -481.546487) (xy 75.544518 -481.434296) (xy 75.423737 -481.316314)
			(xy 75.308619 -481.1928) (xy 75.199416 -481.064026) (xy 75.09637 -480.930275) (xy 74.999706 -480.791841)
			(xy 74.909637 -480.649029) (xy 74.826361 -480.502151) (xy 74.750061 -480.351532) (xy 74.680904 -480.197502)
			(xy 74.619044 -480.0404) (xy 74.564615 -479.88057) (xy 74.517737 -479.718366) (xy 74.478514 -479.554142)
			(xy 74.447032 -479.38826) (xy 74.423359 -479.221085) (xy 74.407549 -479.052985) (xy 74.399635 -478.884327)
			(xy 74.39914 -478.799906) (xy 1.525016 -478.799906) (xy 1.525016 -480.172014) (xy 6.671831 -480.172014)
			(xy 6.675786 -480.080177) (xy 6.687621 -479.98902) (xy 6.707248 -479.899217) (xy 6.734522 -479.811435)
			(xy 6.769242 -479.726321) (xy 6.81115 -479.644508) (xy 6.859936 -479.5666) (xy 6.915239 -479.493175)
			(xy 6.976649 -479.424775) (xy 7.043711 -479.361908) (xy 7.11593 -479.305038) (xy 7.19277 -479.254587)
			(xy 7.273663 -479.210928) (xy 7.358009 -479.174385) (xy 7.445185 -479.145228) (xy 7.534544 -479.123674)
			(xy 7.625425 -479.10988) (xy 7.717156 -479.10395) (xy 7.809057 -479.105928) (xy 7.900448 -479.115799)
			(xy 7.990652 -479.133489) (xy 8.079001 -479.158869) (xy 8.164841 -479.191749) (xy 8.247537 -479.231887)
			(xy 8.326477 -479.278986) (xy 8.401075 -479.332696) (xy 8.470781 -479.39262) (xy 8.535076 -479.458314)
			(xy 8.593487 -479.529292) (xy 8.645579 -479.605029) (xy 8.690968 -479.684964) (xy 8.729318 -479.768504)
			(xy 8.760343 -479.855032) (xy 8.783816 -479.943907) (xy 8.799562 -480.034471) (xy 8.807464 -480.126053)
			(xy 8.807958 -480.172014) (xy 8.807464 -480.217975) (xy 8.799562 -480.309557) (xy 8.783816 -480.400121)
			(xy 8.760343 -480.488996) (xy 8.729318 -480.575524) (xy 8.690968 -480.659064) (xy 8.645579 -480.738999)
			(xy 8.593487 -480.814736) (xy 8.535076 -480.885714) (xy 8.470781 -480.951408) (xy 8.401075 -481.011332)
			(xy 8.326477 -481.065042) (xy 8.247537 -481.112141) (xy 8.164841 -481.152279) (xy 8.079001 -481.185159)
			(xy 7.990652 -481.210539) (xy 7.900448 -481.228229) (xy 7.809057 -481.2381) (xy 7.717156 -481.240078)
			(xy 7.625425 -481.234148) (xy 7.534544 -481.220354) (xy 7.445185 -481.1988) (xy 7.358009 -481.169643)
			(xy 7.273663 -481.1331) (xy 7.19277 -481.089441) (xy 7.11593 -481.03899) (xy 7.043711 -480.98212)
			(xy 6.976649 -480.919253) (xy 6.915239 -480.850853) (xy 6.859936 -480.777428) (xy 6.81115 -480.69952)
			(xy 6.769242 -480.617707) (xy 6.734522 -480.532593) (xy 6.707248 -480.444811) (xy 6.687621 -480.355008)
			(xy 6.675786 -480.263851) (xy 6.671831 -480.172014) (xy 1.525016 -480.172014) (xy 1.525016 -481.880672)
			(xy 51.007772 -481.880672) (xy 52.65928 -481.880672) (xy 52.65928 -483.532688) (xy 51.007772 -483.532688)
			(xy 51.007772 -481.880672) (xy 1.525016 -481.880672) (xy 1.525016 -482.747235) (xy 47.507896 -482.747235)
			(xy 47.507896 -482.666125) (xy 47.515846 -482.585406) (xy 47.531669 -482.505855) (xy 47.555214 -482.428239)
			(xy 47.586253 -482.353303) (xy 47.624488 -482.281771) (xy 47.66955 -482.214331) (xy 47.721005 -482.151632)
			(xy 47.778358 -482.094279) (xy 47.841057 -482.042824) (xy 47.908497 -481.997762) (xy 47.980029 -481.959527)
			(xy 48.054965 -481.928488) (xy 48.132581 -481.904943) (xy 48.212132 -481.88912) (xy 48.292851 -481.88117)
			(xy 48.373961 -481.88117) (xy 48.45468 -481.88912) (xy 48.534231 -481.904943) (xy 48.611847 -481.928488)
			(xy 48.686783 -481.959527) (xy 48.758315 -481.997762) (xy 48.825755 -482.042824) (xy 48.888454 -482.094279)
			(xy 48.945807 -482.151632) (xy 48.997262 -482.214331) (xy 49.042324 -482.281771) (xy 49.080559 -482.353303)
			(xy 49.111598 -482.428239) (xy 49.135143 -482.505855) (xy 49.150966 -482.585406) (xy 49.158916 -482.666125)
			(xy 49.159414 -482.70668) (xy 49.158916 -482.747235) (xy 49.150966 -482.827954) (xy 49.135143 -482.907505)
			(xy 49.111598 -482.985121) (xy 49.080559 -483.060057) (xy 49.042324 -483.131589) (xy 48.997262 -483.199029)
			(xy 48.945807 -483.261728) (xy 48.888454 -483.319081) (xy 48.825755 -483.370536) (xy 48.758315 -483.415598)
			(xy 48.686783 -483.453833) (xy 48.611847 -483.484872) (xy 48.534231 -483.508417) (xy 48.45468 -483.52424)
			(xy 48.373961 -483.53219) (xy 48.292851 -483.53219) (xy 48.212132 -483.52424) (xy 48.132581 -483.508417)
			(xy 48.054965 -483.484872) (xy 47.980029 -483.453833) (xy 47.908497 -483.415598) (xy 47.841057 -483.370536)
			(xy 47.778358 -483.319081) (xy 47.721005 -483.261728) (xy 47.66955 -483.199029) (xy 47.624488 -483.131589)
			(xy 47.586253 -483.060057) (xy 47.555214 -482.985121) (xy 47.531669 -482.907505) (xy 47.515846 -482.827954)
			(xy 47.507896 -482.747235) (xy 1.525016 -482.747235) (xy 1.525016 -485.198883) (xy 73.977596 -485.198883)
			(xy 73.981486 -485.144529) (xy 73.993073 -485.091283) (xy 74.012119 -485.040227) (xy 74.038239 -484.992402)
			(xy 74.070899 -484.948781) (xy 74.109434 -484.910252) (xy 74.153061 -484.8776) (xy 74.200891 -484.85149)
			(xy 74.251951 -484.832453) (xy 74.305199 -484.820876) (xy 74.359554 -484.816996) (xy 74.413907 -484.820892)
			(xy 74.467153 -484.832483) (xy 74.518207 -484.851535) (xy 74.566029 -484.877659) (xy 74.588116 -484.89362)
			(xy 74.607128 -484.907216) (xy 74.649011 -484.927948) (xy 74.693979 -484.940674) (xy 74.740516 -484.944964)
			(xy 74.787053 -484.940674) (xy 74.832021 -484.927948) (xy 74.873904 -484.907216) (xy 74.892916 -484.89362)
			(xy 74.914978 -484.877624) (xy 74.962804 -484.851502) (xy 75.01386 -484.832453) (xy 75.067109 -484.820863)
			(xy 75.121464 -484.816971) (xy 75.175821 -484.820853) (xy 75.229071 -484.832432) (xy 75.280131 -484.851472)
			(xy 75.327962 -484.877585) (xy 75.37159 -484.910239) (xy 75.410126 -484.94877) (xy 75.442787 -484.992393)
			(xy 75.468906 -485.040221) (xy 75.487953 -485.091279) (xy 75.499539 -485.144527) (xy 75.503429 -485.198883)
			(xy 75.906678 -485.198883) (xy 75.910569 -485.144525) (xy 75.922156 -485.091275) (xy 75.941205 -485.040215)
			(xy 75.967327 -484.992387) (xy 75.99999 -484.948763) (xy 76.03853 -484.910232) (xy 76.082161 -484.877579)
			(xy 76.129995 -484.851468) (xy 76.181059 -484.832432) (xy 76.234312 -484.820856) (xy 76.288671 -484.816978)
			(xy 76.343028 -484.820877) (xy 76.396277 -484.832472) (xy 76.447334 -484.851527) (xy 76.495159 -484.877656)
			(xy 76.517246 -484.89362) (xy 76.536258 -484.907216) (xy 76.578141 -484.927948) (xy 76.623109 -484.940674)
			(xy 76.669646 -484.944964) (xy 76.716183 -484.940674) (xy 76.761151 -484.927948) (xy 76.803034 -484.907216)
			(xy 76.822046 -484.89362) (xy 76.844179 -484.877627) (xy 76.892093 -484.851436) (xy 76.943253 -484.832348)
			(xy 76.996613 -484.820753) (xy 77.051081 -484.816889) (xy 77.105543 -484.820833) (xy 77.158885 -484.832507)
			(xy 77.210017 -484.85167) (xy 77.257893 -484.877931) (xy 77.301532 -484.910753) (xy 77.340043 -484.949464)
			(xy 77.356716 -484.97109) (xy 77.370495 -484.988853) (xy 77.40326 -485.019629) (xy 77.44093 -485.044158)
			(xy 77.482328 -485.061676) (xy 77.526163 -485.071635) (xy 77.571067 -485.073726) (xy 77.615637 -485.067881)
			(xy 77.658484 -485.054285) (xy 77.698269 -485.033361) (xy 77.733752 -485.005762) (xy 77.749146 -484.989378)
			(xy 77.76845 -484.968753) (xy 77.812039 -484.932823) (xy 77.86045 -484.903712) (xy 77.912624 -484.882057)
			(xy 77.96742 -484.868332) (xy 78.023641 -484.862836) (xy 78.080058 -484.86569) (xy 78.135438 -484.876831)
			(xy 78.188569 -484.896016) (xy 78.238291 -484.922825) (xy 78.26121 -484.93934) (xy 78.280222 -484.952936)
			(xy 78.322105 -484.973668) (xy 78.367073 -484.986394) (xy 78.41361 -484.990684) (xy 78.460147 -484.986394)
			(xy 78.505115 -484.973668) (xy 78.546998 -484.952936) (xy 78.56601 -484.93934) (xy 78.588053 -484.923316)
			(xy 78.635881 -484.897191) (xy 78.68694 -484.878138) (xy 78.74019 -484.866546) (xy 78.794549 -484.862651)
			(xy 78.848908 -484.866532) (xy 78.902162 -484.878109) (xy 78.953226 -484.897148) (xy 79.001061 -484.923261)
			(xy 79.044692 -484.955915) (xy 79.083232 -484.994447) (xy 79.115896 -485.038072) (xy 79.142018 -485.085901)
			(xy 79.161068 -485.136961) (xy 79.172657 -485.190212) (xy 79.176549 -485.244571) (xy 79.579798 -485.244571)
			(xy 79.58369 -485.190217) (xy 79.595278 -485.136969) (xy 79.614327 -485.085913) (xy 79.640449 -485.038088)
			(xy 79.673112 -484.994468) (xy 79.71165 -484.955941) (xy 79.75528 -484.92329) (xy 79.803112 -484.897182)
			(xy 79.854173 -484.878148) (xy 79.907424 -484.866574) (xy 79.96178 -484.862698) (xy 80.016134 -484.866597)
			(xy 80.069379 -484.878193) (xy 80.120433 -484.897248) (xy 80.168254 -484.923377) (xy 80.19034 -484.93934)
			(xy 80.209352 -484.952936) (xy 80.251235 -484.973668) (xy 80.296203 -484.986394) (xy 80.34274 -484.990684)
			(xy 80.389277 -484.986394) (xy 80.434245 -484.973668) (xy 80.476128 -484.952936) (xy 80.49514 -484.93934)
			(xy 80.517182 -484.923319) (xy 80.565008 -484.897198) (xy 80.616064 -484.87815) (xy 80.669311 -484.866561)
			(xy 80.723666 -484.862669) (xy 80.778021 -484.866552) (xy 80.831271 -484.878131) (xy 80.88233 -484.89717)
			(xy 80.93016 -484.923282) (xy 80.973788 -484.955935) (xy 81.012324 -484.994465) (xy 81.044984 -485.038087)
			(xy 81.071104 -485.085913) (xy 81.090152 -485.136969) (xy 81.101739 -485.190217) (xy 81.105631 -485.244571)
			(xy 81.101747 -485.298926) (xy 81.090168 -485.352176) (xy 81.071128 -485.403235) (xy 81.045015 -485.451065)
			(xy 81.041913 -485.45521) (xy 87.02089 -485.45521) (xy 87.02089 -485.395274) (xy 87.028713 -485.335852)
			(xy 87.044226 -485.277959) (xy 87.067162 -485.222586) (xy 87.097129 -485.17068) (xy 87.133616 -485.12313)
			(xy 87.175996 -485.08075) (xy 87.223546 -485.044263) (xy 87.275452 -485.014296) (xy 87.330825 -484.99136)
			(xy 87.388718 -484.975847) (xy 87.44814 -484.968024) (xy 87.508076 -484.968024) (xy 87.567498 -484.975847)
			(xy 87.625391 -484.99136) (xy 87.680764 -485.014296) (xy 87.73267 -485.044263) (xy 87.78022 -485.08075)
			(xy 87.8226 -485.12313) (xy 87.859087 -485.17068) (xy 87.889054 -485.222586) (xy 87.91199 -485.277959)
			(xy 87.927503 -485.335852) (xy 87.935326 -485.395274) (xy 87.935816 -485.425242) (xy 87.935326 -485.45521)
			(xy 87.927503 -485.514632) (xy 87.91199 -485.572525) (xy 87.889054 -485.627898) (xy 87.859087 -485.679804)
			(xy 87.8226 -485.727354) (xy 87.78022 -485.769734) (xy 87.73267 -485.806221) (xy 87.680764 -485.836188)
			(xy 87.625391 -485.859124) (xy 87.567498 -485.874637) (xy 87.508076 -485.88246) (xy 87.44814 -485.88246)
			(xy 87.388718 -485.874637) (xy 87.330825 -485.859124) (xy 87.275452 -485.836188) (xy 87.223546 -485.806221)
			(xy 87.175996 -485.769734) (xy 87.133616 -485.727354) (xy 87.097129 -485.679804) (xy 87.067162 -485.627898)
			(xy 87.044226 -485.572525) (xy 87.028713 -485.514632) (xy 87.02089 -485.45521) (xy 81.041913 -485.45521)
			(xy 81.012361 -485.494692) (xy 80.973831 -485.533227) (xy 80.930209 -485.565887) (xy 80.882383 -485.592006)
			(xy 80.831326 -485.611053) (xy 80.778078 -485.62264) (xy 80.723724 -485.626531) (xy 80.669368 -485.622647)
			(xy 80.616119 -485.611066) (xy 80.56506 -485.592026) (xy 80.517231 -485.565912) (xy 80.49514 -485.549956)
			(xy 80.476128 -485.53636) (xy 80.434245 -485.515628) (xy 80.389277 -485.502902) (xy 80.34274 -485.498612)
			(xy 80.296203 -485.502902) (xy 80.251235 -485.515628) (xy 80.209352 -485.53636) (xy 80.19034 -485.549956)
			(xy 80.168206 -485.565855) (xy 80.12038 -485.591975) (xy 80.069324 -485.611024) (xy 80.016077 -485.622611)
			(xy 79.961722 -485.626502) (xy 79.907367 -485.622617) (xy 79.854118 -485.611036) (xy 79.80306 -485.591994)
			(xy 79.755231 -485.565878) (xy 79.711606 -485.533222) (xy 79.673074 -485.494688) (xy 79.640418 -485.451063)
			(xy 79.614303 -485.403234) (xy 79.595262 -485.352175) (xy 79.583682 -485.298926) (xy 79.579798 -485.244571)
			(xy 79.176549 -485.244571) (xy 79.172665 -485.29893) (xy 79.161084 -485.352184) (xy 79.142042 -485.403247)
			(xy 79.115927 -485.45108) (xy 79.08327 -485.494709) (xy 79.044736 -485.533247) (xy 79.001109 -485.565908)
			(xy 78.953279 -485.592028) (xy 78.902218 -485.611074) (xy 78.848965 -485.62266) (xy 78.794606 -485.626549)
			(xy 78.740247 -485.622662) (xy 78.686995 -485.611078) (xy 78.635933 -485.592033) (xy 78.588101 -485.565915)
			(xy 78.56601 -485.549956) (xy 78.546998 -485.53636) (xy 78.505115 -485.515628) (xy 78.460147 -485.502902)
			(xy 78.41361 -485.498612) (xy 78.367073 -485.502902) (xy 78.322105 -485.515628) (xy 78.280222 -485.53636)
			(xy 78.26121 -485.549956) (xy 78.239114 -485.566003) (xy 78.191194 -485.592193) (xy 78.140028 -485.61128)
			(xy 78.086662 -485.622872) (xy 78.032188 -485.626732) (xy 77.977721 -485.622783) (xy 77.924375 -485.611104)
			(xy 77.87324 -485.591934) (xy 77.825363 -485.565665) (xy 77.781722 -485.532835) (xy 77.743212 -485.494116)
			(xy 77.72654 -485.472486) (xy 77.712697 -485.454776) (xy 77.67994 -485.424004) (xy 77.64228 -485.399476)
			(xy 77.600891 -485.381957) (xy 77.557066 -485.371994) (xy 77.512171 -485.369898) (xy 77.467608 -485.375735)
			(xy 77.424767 -485.389321) (xy 77.384986 -485.410234) (xy 77.349505 -485.437821) (xy 77.33411 -485.454198)
			(xy 77.314845 -485.474861) (xy 77.271251 -485.510793) (xy 77.222834 -485.539904) (xy 77.170655 -485.561558)
			(xy 77.115853 -485.57528) (xy 77.059627 -485.580772) (xy 77.003205 -485.577913) (xy 76.947822 -485.566765)
			(xy 76.894688 -485.547573) (xy 76.844965 -485.520755) (xy 76.822046 -485.504236) (xy 76.803034 -485.49064)
			(xy 76.761151 -485.469908) (xy 76.716183 -485.457182) (xy 76.669646 -485.452892) (xy 76.623109 -485.457182)
			(xy 76.578141 -485.469908) (xy 76.536258 -485.49064) (xy 76.517246 -485.504236) (xy 76.49513 -485.520162)
			(xy 76.447303 -485.546286) (xy 76.396245 -485.565338) (xy 76.342995 -485.576928) (xy 76.288637 -485.580822)
			(xy 76.234279 -485.576939) (xy 76.181027 -485.565359) (xy 76.129965 -485.546318) (xy 76.082132 -485.520203)
			(xy 76.038504 -485.487546) (xy 75.999968 -485.449011) (xy 75.967309 -485.405385) (xy 75.941191 -485.357554)
			(xy 75.922147 -485.306493) (xy 75.910564 -485.253241) (xy 75.906678 -485.198883) (xy 75.503429 -485.198883)
			(xy 75.499544 -485.253239) (xy 75.487962 -485.306489) (xy 75.46892 -485.357549) (xy 75.442805 -485.405378)
			(xy 75.410148 -485.449004) (xy 75.371615 -485.487539) (xy 75.327991 -485.520197) (xy 75.280162 -485.546314)
			(xy 75.229103 -485.565358) (xy 75.175854 -485.576942) (xy 75.121498 -485.580829) (xy 75.067142 -485.576941)
			(xy 75.013893 -485.565357) (xy 74.962834 -485.546312) (xy 74.915006 -485.520195) (xy 74.892916 -485.504236)
			(xy 74.873904 -485.49064) (xy 74.832021 -485.469908) (xy 74.787053 -485.457182) (xy 74.740516 -485.452892)
			(xy 74.693979 -485.457182) (xy 74.649011 -485.469908) (xy 74.607128 -485.49064) (xy 74.588116 -485.504236)
			(xy 74.566001 -485.52016) (xy 74.518176 -485.546279) (xy 74.467121 -485.565326) (xy 74.413874 -485.576913)
			(xy 74.35952 -485.580804) (xy 74.305166 -485.576919) (xy 74.251918 -485.565338) (xy 74.200861 -485.546296)
			(xy 74.153033 -485.520182) (xy 74.109409 -485.487526) (xy 74.070876 -485.448994) (xy 74.03822 -485.40537)
			(xy 74.012105 -485.357542) (xy 73.993063 -485.306485) (xy 73.981482 -485.253237) (xy 73.977596 -485.198883)
			(xy 1.525016 -485.198883) (xy 1.525016 -486.955605) (xy 73.977567 -486.955605) (xy 73.981455 -486.901247)
			(xy 73.993039 -486.847995) (xy 74.012084 -486.796935) (xy 74.038203 -486.749104) (xy 74.070863 -486.705478)
			(xy 74.109399 -486.666945) (xy 74.153028 -486.634288) (xy 74.20086 -486.608173) (xy 74.251922 -486.589131)
			(xy 74.305174 -486.577551) (xy 74.359532 -486.573667) (xy 74.41389 -486.57756) (xy 74.46714 -486.589149)
			(xy 74.518199 -486.6082) (xy 74.566027 -486.634323) (xy 74.588116 -486.650284) (xy 74.607128 -486.66388)
			(xy 74.649011 -486.684612) (xy 74.693979 -486.697338) (xy 74.740516 -486.701628) (xy 74.787053 -486.697338)
			(xy 74.832021 -486.684612) (xy 74.873904 -486.66388) (xy 74.892916 -486.650284) (xy 74.915011 -486.634336)
			(xy 74.962835 -486.608219) (xy 75.013889 -486.589174) (xy 75.067134 -486.577589) (xy 75.121486 -486.573699)
			(xy 75.175838 -486.577585) (xy 75.229084 -486.589166) (xy 75.280139 -486.608207) (xy 75.327965 -486.634321)
			(xy 75.371587 -486.666975) (xy 75.410119 -486.705505) (xy 75.442774 -486.749127) (xy 75.468889 -486.796952)
			(xy 75.487931 -486.848007) (xy 75.499514 -486.901253) (xy 75.503401 -486.955605) (xy 75.90665 -486.955605)
			(xy 75.910537 -486.901243) (xy 75.922123 -486.847987) (xy 75.94117 -486.796923) (xy 75.967291 -486.749089)
			(xy 75.999954 -486.705461) (xy 76.038494 -486.666925) (xy 76.082127 -486.634267) (xy 76.129964 -486.608151)
			(xy 76.18103 -486.58911) (xy 76.234287 -486.577531) (xy 76.288649 -486.57365) (xy 76.343011 -486.577545)
			(xy 76.396265 -486.589138) (xy 76.447326 -486.608192) (xy 76.495156 -486.63432) (xy 76.517246 -486.650284)
			(xy 76.536258 -486.66388) (xy 76.578141 -486.684612) (xy 76.623109 -486.697338) (xy 76.669646 -486.701628)
			(xy 76.716183 -486.697338) (xy 76.761151 -486.684612) (xy 76.803034 -486.66388) (xy 76.822046 -486.650284)
			(xy 76.844171 -486.634278) (xy 76.892085 -486.608082) (xy 76.943246 -486.58899) (xy 76.996608 -486.577392)
			(xy 77.051079 -486.573527) (xy 77.105544 -486.577472) (xy 77.158889 -486.589147) (xy 77.210022 -486.608314)
			(xy 77.257898 -486.63458) (xy 77.301537 -486.667407) (xy 77.340045 -486.706125) (xy 77.356716 -486.727754)
			(xy 77.370493 -486.745516) (xy 77.403262 -486.776285) (xy 77.440933 -486.800809) (xy 77.482331 -486.818322)
			(xy 77.526164 -486.828279) (xy 77.571065 -486.830369) (xy 77.615634 -486.824526) (xy 77.65848 -486.810934)
			(xy 77.698265 -486.790015) (xy 77.73375 -486.762423) (xy 77.749146 -486.746042) (xy 77.768454 -486.72542)
			(xy 77.812041 -486.689484) (xy 77.86045 -486.660369) (xy 77.912623 -486.638711) (xy 77.96742 -486.624984)
			(xy 78.023642 -486.619487) (xy 78.08006 -486.622342) (xy 78.13544 -486.633485) (xy 78.188572 -486.652673)
			(xy 78.238292 -486.679486) (xy 78.26121 -486.696004) (xy 78.280222 -486.7096) (xy 78.322105 -486.730332)
			(xy 78.367073 -486.743058) (xy 78.41361 -486.747348) (xy 78.460147 -486.743058) (xy 78.505115 -486.730332)
			(xy 78.546998 -486.7096) (xy 78.56601 -486.696004) (xy 78.588087 -486.680029) (xy 78.635912 -486.653908)
			(xy 78.686968 -486.63486) (xy 78.740216 -486.623272) (xy 78.79457 -486.61938) (xy 78.848926 -486.623263)
			(xy 78.902175 -486.634843) (xy 78.953234 -486.653883) (xy 79.001064 -486.679997) (xy 79.04469 -486.712651)
			(xy 79.083225 -486.751182) (xy 79.115883 -486.794805) (xy 79.142001 -486.842633) (xy 79.161047 -486.89369)
			(xy 79.172631 -486.946938) (xy 79.17652 -487.001293) (xy 79.579769 -487.001293) (xy 79.583658 -486.946934)
			(xy 79.595245 -486.893682) (xy 79.614292 -486.842621) (xy 79.640413 -486.794791) (xy 79.673076 -486.751166)
			(xy 79.711615 -486.712633) (xy 79.755246 -486.679978) (xy 79.80308 -486.653865) (xy 79.854144 -486.634826)
			(xy 79.907398 -486.623249) (xy 79.961758 -486.619369) (xy 80.016116 -486.623266) (xy 80.069367 -486.634859)
			(xy 80.120425 -486.653913) (xy 80.168252 -486.680041) (xy 80.19034 -486.696004) (xy 80.209352 -486.7096)
			(xy 80.251235 -486.730332) (xy 80.296203 -486.743058) (xy 80.34274 -486.747348) (xy 80.389277 -486.743058)
			(xy 80.434245 -486.730332) (xy 80.476128 -486.7096) (xy 80.49514 -486.696004) (xy 80.517216 -486.680031)
			(xy 80.565039 -486.653915) (xy 80.616093 -486.634871) (xy 80.669337 -486.623287) (xy 80.723688 -486.619398)
			(xy 80.778038 -486.623283) (xy 80.831283 -486.634864) (xy 80.882338 -486.653905) (xy 80.930163 -486.680018)
			(xy 80.973785 -486.712671) (xy 81.012316 -486.7512) (xy 81.044972 -486.79482) (xy 81.067295 -486.8357)
			(xy 87.30918 -486.8357) (xy 87.30918 -486.775764) (xy 87.317003 -486.716342) (xy 87.332516 -486.658449)
			(xy 87.355452 -486.603076) (xy 87.385419 -486.55117) (xy 87.421906 -486.50362) (xy 87.464286 -486.46124)
			(xy 87.511836 -486.424753) (xy 87.563742 -486.394786) (xy 87.619115 -486.37185) (xy 87.677008 -486.356337)
			(xy 87.73643 -486.348514) (xy 87.796366 -486.348514) (xy 87.855788 -486.356337) (xy 87.913681 -486.37185)
			(xy 87.969054 -486.394786) (xy 88.02096 -486.424753) (xy 88.06851 -486.46124) (xy 88.11089 -486.50362)
			(xy 88.147377 -486.55117) (xy 88.177344 -486.603076) (xy 88.20028 -486.658449) (xy 88.215793 -486.716342)
			(xy 88.223616 -486.775764) (xy 88.224106 -486.805732) (xy 88.223616 -486.8357) (xy 88.215793 -486.895122)
			(xy 88.20028 -486.953015) (xy 88.177344 -487.008388) (xy 88.147377 -487.060294) (xy 88.11089 -487.107844)
			(xy 88.06851 -487.150224) (xy 88.02096 -487.186711) (xy 87.969054 -487.216678) (xy 87.913681 -487.239614)
			(xy 87.855788 -487.255127) (xy 87.796366 -487.26295) (xy 87.73643 -487.26295) (xy 87.677008 -487.255127)
			(xy 87.619115 -487.239614) (xy 87.563742 -487.216678) (xy 87.511836 -487.186711) (xy 87.464286 -487.150224)
			(xy 87.421906 -487.107844) (xy 87.385419 -487.060294) (xy 87.355452 -487.008388) (xy 87.332516 -486.953015)
			(xy 87.317003 -486.895122) (xy 87.30918 -486.8357) (xy 81.067295 -486.8357) (xy 81.071087 -486.842644)
			(xy 81.09013 -486.893698) (xy 81.101714 -486.946942) (xy 81.105602 -487.001293) (xy 81.101716 -487.055644)
			(xy 81.090134 -487.108888) (xy 81.071093 -487.159943) (xy 81.044979 -487.207767) (xy 81.012326 -487.251389)
			(xy 80.973796 -487.28992) (xy 80.930175 -487.322574) (xy 80.882351 -487.348689) (xy 80.831297 -487.367732)
			(xy 80.778053 -487.379315) (xy 80.723702 -487.383202) (xy 80.669351 -487.379315) (xy 80.616107 -487.367733)
			(xy 80.565053 -487.348691) (xy 80.517228 -487.322577) (xy 80.49514 -487.30662) (xy 80.476128 -487.293024)
			(xy 80.434245 -487.272292) (xy 80.389277 -487.259566) (xy 80.34274 -487.255276) (xy 80.296203 -487.259566)
			(xy 80.251235 -487.272292) (xy 80.209352 -487.293024) (xy 80.19034 -487.30662) (xy 80.16824 -487.322567)
			(xy 80.120412 -487.348693) (xy 80.069353 -487.367745) (xy 80.016102 -487.379337) (xy 79.961744 -487.383231)
			(xy 79.907384 -487.379349) (xy 79.854131 -487.36777) (xy 79.803067 -487.348729) (xy 79.755234 -487.322614)
			(xy 79.711604 -487.289958) (xy 79.673066 -487.251424) (xy 79.640405 -487.207797) (xy 79.614286 -487.159966)
			(xy 79.595241 -487.108904) (xy 79.583656 -487.055652) (xy 79.579769 -487.001293) (xy 79.17652 -487.001293)
			(xy 79.172633 -487.055648) (xy 79.161051 -487.108896) (xy 79.142007 -487.159954) (xy 79.115891 -487.207782)
			(xy 79.083234 -487.251407) (xy 79.044701 -487.289939) (xy 79.001076 -487.322595) (xy 78.953247 -487.348711)
			(xy 78.902189 -487.367753) (xy 78.84894 -487.379335) (xy 78.794585 -487.38322) (xy 78.74023 -487.37933)
			(xy 78.686982 -487.367744) (xy 78.635925 -487.348698) (xy 78.588099 -487.322579) (xy 78.56601 -487.30662)
			(xy 78.546998 -487.293024) (xy 78.505115 -487.272292) (xy 78.460147 -487.259566) (xy 78.41361 -487.255276)
			(xy 78.367073 -487.259566) (xy 78.322105 -487.272292) (xy 78.280222 -487.293024) (xy 78.26121 -487.30662)
			(xy 78.239118 -487.322674) (xy 78.191198 -487.348867) (xy 78.140031 -487.367956) (xy 78.086664 -487.37955)
			(xy 78.032189 -487.383411) (xy 77.977721 -487.379461) (xy 77.924373 -487.367781) (xy 77.873237 -487.348609)
			(xy 77.82536 -487.322337) (xy 77.78172 -487.289504) (xy 77.743211 -487.250781) (xy 77.72654 -487.22915)
			(xy 77.712698 -487.211441) (xy 77.679939 -487.180673) (xy 77.642278 -487.156148) (xy 77.60089 -487.138631)
			(xy 77.557065 -487.12867) (xy 77.512172 -487.126574) (xy 77.46761 -487.13241) (xy 77.42477 -487.145994)
			(xy 77.384988 -487.166904) (xy 77.349506 -487.194487) (xy 77.33411 -487.210862) (xy 77.314842 -487.231524)
			(xy 77.27125 -487.267458) (xy 77.222835 -487.296572) (xy 77.170655 -487.318227) (xy 77.115853 -487.331951)
			(xy 77.059626 -487.337443) (xy 77.003204 -487.334584) (xy 76.94782 -487.323435) (xy 76.894686 -487.304241)
			(xy 76.844964 -487.277421) (xy 76.822046 -487.2609) (xy 76.803034 -487.247304) (xy 76.761151 -487.226572)
			(xy 76.716183 -487.213846) (xy 76.669646 -487.209556) (xy 76.623109 -487.213846) (xy 76.578141 -487.226572)
			(xy 76.536258 -487.247304) (xy 76.517246 -487.2609) (xy 76.495164 -487.276875) (xy 76.447335 -487.303004)
			(xy 76.396274 -487.322059) (xy 76.343021 -487.333654) (xy 76.288659 -487.33755) (xy 76.234296 -487.33367)
			(xy 76.181039 -487.322093) (xy 76.129972 -487.303053) (xy 76.082135 -487.276938) (xy 76.038502 -487.244281)
			(xy 75.99996 -487.205747) (xy 75.967296 -487.162119) (xy 75.941174 -487.114286) (xy 75.922125 -487.063222)
			(xy 75.910539 -487.009967) (xy 75.90665 -486.955605) (xy 75.503401 -486.955605) (xy 75.499512 -487.009957)
			(xy 75.487929 -487.063202) (xy 75.468885 -487.114256) (xy 75.442769 -487.162081) (xy 75.410112 -487.205702)
			(xy 75.37158 -487.244231) (xy 75.327957 -487.276884) (xy 75.28013 -487.302997) (xy 75.229074 -487.322037)
			(xy 75.175828 -487.333616) (xy 75.121476 -487.337501) (xy 75.067125 -487.33361) (xy 75.01388 -487.322023)
			(xy 74.962826 -487.302977) (xy 74.915003 -487.276859) (xy 74.892916 -487.2609) (xy 74.873904 -487.247304)
			(xy 74.832021 -487.226572) (xy 74.787053 -487.213846) (xy 74.740516 -487.209556) (xy 74.693979 -487.213846)
			(xy 74.649011 -487.226572) (xy 74.607128 -487.247304) (xy 74.588116 -487.2609) (xy 74.566035 -487.276872)
			(xy 74.518208 -487.302996) (xy 74.46715 -487.322048) (xy 74.4139 -487.333639) (xy 74.359542 -487.337533)
			(xy 74.305184 -487.33365) (xy 74.251931 -487.322071) (xy 74.200868 -487.303031) (xy 74.153036 -487.276917)
			(xy 74.109406 -487.244262) (xy 74.070869 -487.205729) (xy 74.038208 -487.162104) (xy 74.012088 -487.114274)
			(xy 73.993042 -487.063214) (xy 73.981456 -487.009963) (xy 73.977567 -486.955605) (xy 1.525016 -486.955605)
			(xy 1.525016 -488.321854) (xy 85.988126 -488.321854) (xy 85.988126 -488.261918) (xy 85.995949 -488.202496)
			(xy 86.011462 -488.144603) (xy 86.034398 -488.08923) (xy 86.064365 -488.037324) (xy 86.100852 -487.989774)
			(xy 86.143232 -487.947394) (xy 86.190782 -487.910907) (xy 86.242688 -487.88094) (xy 86.298061 -487.858004)
			(xy 86.355954 -487.842491) (xy 86.415376 -487.834668) (xy 86.475312 -487.834668) (xy 86.534734 -487.842491)
			(xy 86.592627 -487.858004) (xy 86.648 -487.88094) (xy 86.699906 -487.910907) (xy 86.747456 -487.947394)
			(xy 86.789836 -487.989774) (xy 86.826323 -488.037324) (xy 86.85629 -488.08923) (xy 86.879226 -488.144603)
			(xy 86.894739 -488.202496) (xy 86.902562 -488.261918) (xy 86.903052 -488.291886) (xy 86.902562 -488.321854)
			(xy 86.894739 -488.381276) (xy 86.879226 -488.439169) (xy 86.85629 -488.494542) (xy 86.826323 -488.546448)
			(xy 86.789836 -488.593998) (xy 86.747456 -488.636378) (xy 86.699906 -488.672865) (xy 86.648 -488.702832)
			(xy 86.592627 -488.725768) (xy 86.534734 -488.741281) (xy 86.475312 -488.749104) (xy 86.415376 -488.749104)
			(xy 86.355954 -488.741281) (xy 86.298061 -488.725768) (xy 86.242688 -488.702832) (xy 86.190782 -488.672865)
			(xy 86.143232 -488.636378) (xy 86.100852 -488.593998) (xy 86.064365 -488.546448) (xy 86.034398 -488.494542)
			(xy 86.011462 -488.439169) (xy 85.995949 -488.381276) (xy 85.988126 -488.321854) (xy 1.525016 -488.321854)
			(xy 1.525016 -488.722223) (xy 73.977543 -488.722223) (xy 73.981428 -488.667861) (xy 73.993011 -488.614606)
			(xy 74.012055 -488.563541) (xy 74.038173 -488.515707) (xy 74.070833 -488.472076) (xy 74.10937 -488.433538)
			(xy 74.152999 -488.400877) (xy 74.200833 -488.374758) (xy 74.251898 -488.355713) (xy 74.305153 -488.34413)
			(xy 74.359514 -488.340243) (xy 74.413876 -488.344134) (xy 74.46713 -488.355721) (xy 74.518193 -488.37477)
			(xy 74.566025 -488.400893) (xy 74.588116 -488.416854) (xy 74.607128 -488.43045) (xy 74.649011 -488.451182)
			(xy 74.693979 -488.463908) (xy 74.740516 -488.468198) (xy 74.787053 -488.463908) (xy 74.832021 -488.451182)
			(xy 74.873904 -488.43045) (xy 74.892916 -488.416854) (xy 74.915039 -488.400947) (xy 74.962862 -488.374833)
			(xy 75.013913 -488.355792) (xy 75.067155 -488.34421) (xy 75.121504 -488.340323) (xy 75.175852 -488.344211)
			(xy 75.229094 -488.355794) (xy 75.280145 -488.374837) (xy 75.327967 -488.400951) (xy 75.371585 -488.433605)
			(xy 75.410112 -488.472135) (xy 75.442764 -488.515755) (xy 75.468874 -488.563579) (xy 75.487913 -488.614632)
			(xy 75.499493 -488.667874) (xy 75.503377 -488.722223) (xy 75.906625 -488.722223) (xy 75.910511 -488.667857)
			(xy 75.922094 -488.614598) (xy 75.94114 -488.563529) (xy 75.967261 -488.515692) (xy 75.999924 -488.472059)
			(xy 76.038465 -488.433518) (xy 76.082099 -488.400856) (xy 76.129937 -488.374737) (xy 76.181006 -488.355692)
			(xy 76.234266 -488.34411) (xy 76.288631 -488.340225) (xy 76.342997 -488.344119) (xy 76.396254 -488.35571)
			(xy 76.44732 -488.374763) (xy 76.495154 -488.40089) (xy 76.517246 -488.416854) (xy 76.536258 -488.43045)
			(xy 76.578141 -488.451182) (xy 76.623109 -488.463908) (xy 76.669646 -488.468198) (xy 76.716183 -488.463908)
			(xy 76.761151 -488.451182) (xy 76.803034 -488.43045) (xy 76.822046 -488.416854) (xy 76.844175 -488.400854)
			(xy 76.892089 -488.37466) (xy 76.94325 -488.35557) (xy 76.99661 -488.343974) (xy 77.05108 -488.340109)
			(xy 77.105543 -488.344054) (xy 77.158887 -488.355728) (xy 77.21002 -488.374893) (xy 77.257895 -488.401157)
			(xy 77.301534 -488.433982) (xy 77.340044 -488.472697) (xy 77.356716 -488.494324) (xy 77.370494 -488.512086)
			(xy 77.403261 -488.542858) (xy 77.440932 -488.567385) (xy 77.48233 -488.5849) (xy 77.526164 -488.594858)
			(xy 77.571066 -488.596948) (xy 77.615636 -488.591105) (xy 77.658482 -488.57751) (xy 77.698267 -488.556589)
			(xy 77.733751 -488.528994) (xy 77.749146 -488.512612) (xy 77.768453 -488.491989) (xy 77.81204 -488.456055)
			(xy 77.86045 -488.426942) (xy 77.912623 -488.405286) (xy 77.96742 -488.391559) (xy 78.023642 -488.386063)
			(xy 78.080059 -488.388917) (xy 78.135439 -488.400059) (xy 78.18857 -488.419246) (xy 78.238292 -488.446058)
			(xy 78.26121 -488.462574) (xy 78.280222 -488.47617) (xy 78.322105 -488.496902) (xy 78.367073 -488.509628)
			(xy 78.41361 -488.513918) (xy 78.460147 -488.509628) (xy 78.505115 -488.496902) (xy 78.546998 -488.47617)
			(xy 78.56601 -488.462574) (xy 78.588115 -488.446639) (xy 78.635939 -488.420522) (xy 78.686992 -488.401478)
			(xy 78.740237 -488.389893) (xy 78.794588 -488.386004) (xy 78.84894 -488.38989) (xy 78.902185 -488.401471)
			(xy 78.95324 -488.420513) (xy 79.001066 -488.446627) (xy 79.044688 -488.479281) (xy 79.083218 -488.517812)
			(xy 79.115873 -488.561434) (xy 79.141987 -488.609259) (xy 79.161029 -488.660314) (xy 79.17261 -488.713559)
			(xy 79.176496 -488.767911) (xy 79.579745 -488.767911) (xy 79.583632 -488.713548) (xy 79.595217 -488.660292)
			(xy 79.614263 -488.609227) (xy 79.640383 -488.561393) (xy 79.673046 -488.517763) (xy 79.711586 -488.479227)
			(xy 79.755218 -488.446567) (xy 79.803054 -488.420451) (xy 79.85412 -488.401408) (xy 79.907377 -488.389828)
			(xy 79.96174 -488.385945) (xy 80.016102 -488.389839) (xy 80.069356 -488.401431) (xy 80.120419 -488.420484)
			(xy 80.16825 -488.446611) (xy 80.19034 -488.462574) (xy 80.209352 -488.47617) (xy 80.251235 -488.496902)
			(xy 80.296203 -488.509628) (xy 80.34274 -488.513918) (xy 80.389277 -488.509628) (xy 80.434245 -488.496902)
			(xy 80.476128 -488.47617) (xy 80.49514 -488.462574) (xy 80.517244 -488.446642) (xy 80.565066 -488.42053)
			(xy 80.616117 -488.401489) (xy 80.669358 -488.389908) (xy 80.723706 -488.386022) (xy 80.778053 -488.38991)
			(xy 80.831294 -488.401492) (xy 80.882344 -488.420534) (xy 80.930165 -488.446648) (xy 80.973783 -488.479301)
			(xy 81.01231 -488.517829) (xy 81.044961 -488.561449) (xy 81.071072 -488.609271) (xy 81.090112 -488.660322)
			(xy 81.101693 -488.713563) (xy 81.105578 -488.767911) (xy 81.10169 -488.822258) (xy 81.090106 -488.875499)
			(xy 81.071063 -488.926549) (xy 81.044949 -488.97437) (xy 81.012296 -489.017987) (xy 80.973767 -489.056513)
			(xy 80.930147 -489.089164) (xy 80.882325 -489.115275) (xy 80.831273 -489.134314) (xy 80.778031 -489.145893)
			(xy 80.723684 -489.149778) (xy 80.669337 -489.145889) (xy 80.616096 -489.134305) (xy 80.565046 -489.115261)
			(xy 80.517226 -489.089147) (xy 80.49514 -489.07319) (xy 80.476128 -489.059594) (xy 80.434245 -489.038862)
			(xy 80.389277 -489.026136) (xy 80.34274 -489.021846) (xy 80.296203 -489.026136) (xy 80.251235 -489.038862)
			(xy 80.209352 -489.059594) (xy 80.19034 -489.07319) (xy 80.168268 -489.089178) (xy 80.120438 -489.115307)
			(xy 80.069377 -489.134363) (xy 80.016123 -489.145958) (xy 79.961762 -489.149855) (xy 79.907399 -489.145975)
			(xy 79.854141 -489.134398) (xy 79.803074 -489.115358) (xy 79.755236 -489.089244) (xy 79.711602 -489.056587)
			(xy 79.67306 -489.018053) (xy 79.640395 -488.974425) (xy 79.614272 -488.926592) (xy 79.595223 -488.875528)
			(xy 79.583635 -488.822273) (xy 79.579745 -488.767911) (xy 79.176496 -488.767911) (xy 79.172607 -488.822262)
			(xy 79.161022 -488.875507) (xy 79.141978 -488.926561) (xy 79.115861 -488.974385) (xy 79.083204 -489.018005)
			(xy 79.044671 -489.056533) (xy 79.001048 -489.089185) (xy 78.953221 -489.115296) (xy 78.902165 -489.134335)
			(xy 78.848919 -489.145913) (xy 78.794567 -489.149796) (xy 78.740216 -489.145904) (xy 78.686972 -489.134316)
			(xy 78.635919 -489.115269) (xy 78.588097 -489.089149) (xy 78.56601 -489.07319) (xy 78.546998 -489.059594)
			(xy 78.505115 -489.038862) (xy 78.460147 -489.026136) (xy 78.41361 -489.021846) (xy 78.367073 -489.026136)
			(xy 78.322105 -489.038862) (xy 78.280222 -489.059594) (xy 78.26121 -489.07319) (xy 78.239109 -489.08923)
			(xy 78.191189 -489.115417) (xy 78.140024 -489.134502) (xy 78.08666 -489.146093) (xy 78.032188 -489.149953)
			(xy 77.977722 -489.146003) (xy 77.924376 -489.134325) (xy 77.873242 -489.115157) (xy 77.825365 -489.088891)
			(xy 77.781725 -489.056064) (xy 77.743213 -489.017348) (xy 77.72654 -488.99572) (xy 77.712698 -488.978011)
			(xy 77.679938 -488.947246) (xy 77.642276 -488.922724) (xy 77.600888 -488.90521) (xy 77.557065 -488.89525)
			(xy 77.512173 -488.893154) (xy 77.467612 -488.898989) (xy 77.424772 -488.912572) (xy 77.38499 -488.933479)
			(xy 77.349507 -488.961058) (xy 77.33411 -488.977432) (xy 77.314847 -488.998097) (xy 77.271251 -489.034026)
			(xy 77.222834 -489.063135) (xy 77.170655 -489.084786) (xy 77.115853 -489.098508) (xy 77.059627 -489.103999)
			(xy 77.003206 -489.10114) (xy 76.947823 -489.089994) (xy 76.894689 -489.070803) (xy 76.844965 -489.043988)
			(xy 76.822046 -489.02747) (xy 76.803034 -489.013874) (xy 76.761151 -488.993142) (xy 76.716183 -488.980416)
			(xy 76.669646 -488.976126) (xy 76.623109 -488.980416) (xy 76.578141 -488.993142) (xy 76.536258 -489.013874)
			(xy 76.517246 -489.02747) (xy 76.495192 -489.043485) (xy 76.447361 -489.069618) (xy 76.396298 -489.088677)
			(xy 76.343042 -489.100275) (xy 76.288677 -489.104175) (xy 76.234311 -489.100297) (xy 76.18105 -489.088721)
			(xy 76.129979 -489.069682) (xy 76.082137 -489.043568) (xy 76.038499 -489.010911) (xy 75.999954 -488.972376)
			(xy 75.967286 -488.928747) (xy 75.941159 -488.880912) (xy 75.922107 -488.829846) (xy 75.910517 -488.776588)
			(xy 75.906625 -488.722223) (xy 75.503377 -488.722223) (xy 75.499486 -488.776571) (xy 75.4879 -488.829812)
			(xy 75.468855 -488.880863) (xy 75.442739 -488.928683) (xy 75.410082 -488.9723) (xy 75.371551 -489.010825)
			(xy 75.327929 -489.043474) (xy 75.280104 -489.069582) (xy 75.22905 -489.088619) (xy 75.175807 -489.100195)
			(xy 75.121458 -489.104077) (xy 75.06711 -489.100183) (xy 75.01387 -489.088595) (xy 74.96282 -489.069548)
			(xy 74.915001 -489.043429) (xy 74.892916 -489.02747) (xy 74.873904 -489.013874) (xy 74.832021 -488.993142)
			(xy 74.787053 -488.980416) (xy 74.740516 -488.976126) (xy 74.693979 -488.980416) (xy 74.649011 -488.993142)
			(xy 74.607128 -489.013874) (xy 74.588116 -489.02747) (xy 74.566063 -489.043483) (xy 74.518234 -489.069611)
			(xy 74.467174 -489.088666) (xy 74.413921 -489.10026) (xy 74.35956 -489.104157) (xy 74.305198 -489.100277)
			(xy 74.251941 -489.0887) (xy 74.200875 -489.069661) (xy 74.153038 -489.043547) (xy 74.109404 -489.010892)
			(xy 74.070863 -488.972358) (xy 74.038197 -488.928732) (xy 74.012074 -488.8809) (xy 73.993024 -488.829838)
			(xy 73.981435 -488.776584) (xy 73.977543 -488.722223) (xy 1.525016 -488.722223) (xy 1.525016 -489.433866)
			(xy 83.972128 -489.433866) (xy 83.972128 -489.37393) (xy 83.979951 -489.314508) (xy 83.995464 -489.256615)
			(xy 84.0184 -489.201242) (xy 84.048367 -489.149336) (xy 84.084854 -489.101786) (xy 84.127234 -489.059406)
			(xy 84.174784 -489.022919) (xy 84.22669 -488.992952) (xy 84.282063 -488.970016) (xy 84.339956 -488.954503)
			(xy 84.399378 -488.94668) (xy 84.459314 -488.94668) (xy 84.518736 -488.954503) (xy 84.576629 -488.970016)
			(xy 84.632002 -488.992952) (xy 84.683908 -489.022919) (xy 84.731458 -489.059406) (xy 84.773838 -489.101786)
			(xy 84.810325 -489.149336) (xy 84.840292 -489.201242) (xy 84.863228 -489.256615) (xy 84.878741 -489.314508)
			(xy 84.886564 -489.37393) (xy 84.887054 -489.403898) (xy 84.886564 -489.433866) (xy 84.878741 -489.493288)
			(xy 84.863228 -489.551181) (xy 84.840292 -489.606554) (xy 84.810325 -489.65846) (xy 84.773838 -489.70601)
			(xy 84.731458 -489.74839) (xy 84.683908 -489.784877) (xy 84.632002 -489.814844) (xy 84.576629 -489.83778)
			(xy 84.518736 -489.853293) (xy 84.459314 -489.861116) (xy 84.399378 -489.861116) (xy 84.339956 -489.853293)
			(xy 84.282063 -489.83778) (xy 84.22669 -489.814844) (xy 84.174784 -489.784877) (xy 84.127234 -489.74839)
			(xy 84.084854 -489.70601) (xy 84.048367 -489.65846) (xy 84.0184 -489.606554) (xy 83.995464 -489.551181)
			(xy 83.979951 -489.493288) (xy 83.972128 -489.433866) (xy 1.525016 -489.433866) (xy 1.525016 -491.999778)
			(xy 6.671831 -491.999778) (xy 6.675786 -491.907941) (xy 6.687621 -491.816784) (xy 6.707248 -491.726981)
			(xy 6.734522 -491.639199) (xy 6.769242 -491.554085) (xy 6.81115 -491.472272) (xy 6.859936 -491.394364)
			(xy 6.915239 -491.320939) (xy 6.976649 -491.252539) (xy 7.043711 -491.189672) (xy 7.11593 -491.132802)
			(xy 7.19277 -491.082351) (xy 7.273663 -491.038692) (xy 7.358009 -491.002149) (xy 7.445185 -490.972992)
			(xy 7.534544 -490.951438) (xy 7.625425 -490.937644) (xy 7.717156 -490.931714) (xy 7.809057 -490.933692)
			(xy 7.900448 -490.943563) (xy 7.990652 -490.961253) (xy 8.079001 -490.986633) (xy 8.164841 -491.019513)
			(xy 8.247537 -491.059651) (xy 8.326477 -491.10675) (xy 8.401075 -491.16046) (xy 8.470781 -491.220384)
			(xy 8.535076 -491.286078) (xy 8.593487 -491.357056) (xy 8.645579 -491.432793) (xy 8.690968 -491.512728)
			(xy 8.729318 -491.596268) (xy 8.760343 -491.682796) (xy 8.783816 -491.771671) (xy 8.799562 -491.862235)
			(xy 8.807464 -491.953817) (xy 8.807958 -491.999778) (xy 8.807464 -492.045739) (xy 8.799562 -492.137321)
			(xy 8.783816 -492.227885) (xy 8.760343 -492.31676) (xy 8.729318 -492.403288) (xy 8.690968 -492.486828)
			(xy 8.645579 -492.566763) (xy 8.593487 -492.6425) (xy 8.535076 -492.713478) (xy 8.470781 -492.779172)
			(xy 8.401075 -492.839096) (xy 8.326477 -492.892806) (xy 8.247537 -492.939905) (xy 8.164841 -492.980043)
			(xy 8.079001 -493.012923) (xy 7.990652 -493.038303) (xy 7.900448 -493.055993) (xy 7.809057 -493.065864)
			(xy 7.717156 -493.067842) (xy 7.625425 -493.061912) (xy 7.534544 -493.048118) (xy 7.445185 -493.026564)
			(xy 7.358009 -492.997407) (xy 7.273663 -492.960864) (xy 7.19277 -492.917205) (xy 7.11593 -492.866754)
			(xy 7.043711 -492.809884) (xy 6.976649 -492.747017) (xy 6.915239 -492.678617) (xy 6.859936 -492.605192)
			(xy 6.81115 -492.527284) (xy 6.769242 -492.445471) (xy 6.734522 -492.360357) (xy 6.707248 -492.272575)
			(xy 6.687621 -492.182772) (xy 6.675786 -492.091615) (xy 6.671831 -491.999778) (xy 1.525016 -491.999778)
			(xy 1.525016 -495.86007) (xy 39.818564 -495.86007) (xy 39.819058 -495.802661) (xy 39.826902 -495.688113)
			(xy 39.842544 -495.574366) (xy 39.865911 -495.461952) (xy 39.896896 -495.351394) (xy 39.935352 -495.243209)
			(xy 39.981101 -495.1379) (xy 40.03393 -495.035958) (xy 40.093592 -494.937859) (xy 40.159809 -494.84406)
			(xy 40.232272 -494.754998) (xy 40.310645 -494.671089) (xy 40.39456 -494.592723) (xy 40.483627 -494.520266)
			(xy 40.577431 -494.454056) (xy 40.675535 -494.394402) (xy 40.777481 -494.341581) (xy 40.882793 -494.295839)
			(xy 40.990981 -494.257391) (xy 41.101541 -494.226415) (xy 41.213957 -494.203056) (xy 41.327705 -494.187423)
			(xy 41.442254 -494.179588) (xy 41.557072 -494.179588) (xy 41.671621 -494.187423) (xy 41.785369 -494.203056)
			(xy 41.897785 -494.226415) (xy 42.008345 -494.257391) (xy 42.116533 -494.295839) (xy 42.221845 -494.341581)
			(xy 42.323791 -494.394402) (xy 42.421895 -494.454056) (xy 42.501239 -494.51006) (xy 63.647577 -494.51006)
			(xy 63.651612 -494.434356) (xy 63.663671 -494.359511) (xy 63.683617 -494.28637) (xy 63.711224 -494.215765)
			(xy 63.74618 -494.148494) (xy 63.788088 -494.085319) (xy 63.836474 -494.026957) (xy 63.89079 -493.974069)
			(xy 63.950419 -493.927254) (xy 64.014687 -493.887042) (xy 64.082864 -493.85389) (xy 64.15418 -493.828172)
			(xy 64.227825 -493.81018) (xy 64.302965 -493.800118) (xy 64.378749 -493.798099) (xy 64.454319 -493.804148)
			(xy 64.528817 -493.818195) (xy 64.6014 -493.840081) (xy 64.671246 -493.869558) (xy 64.737563 -493.906293)
			(xy 64.799599 -493.949868) (xy 64.856652 -493.99979) (xy 64.908076 -494.055494) (xy 64.953287 -494.116349)
			(xy 64.991774 -494.181664) (xy 65.0231 -494.2507) (xy 65.04691 -494.322675) (xy 65.062935 -494.396773)
			(xy 65.070994 -494.472154) (xy 65.071498 -494.51006) (xy 66.187577 -494.51006) (xy 66.191612 -494.434356)
			(xy 66.203671 -494.359511) (xy 66.223617 -494.28637) (xy 66.251224 -494.215765) (xy 66.28618 -494.148494)
			(xy 66.328088 -494.085319) (xy 66.376474 -494.026957) (xy 66.43079 -493.974069) (xy 66.490419 -493.927254)
			(xy 66.554687 -493.887042) (xy 66.622864 -493.85389) (xy 66.69418 -493.828172) (xy 66.767825 -493.81018)
			(xy 66.842965 -493.800118) (xy 66.918749 -493.798099) (xy 66.994319 -493.804148) (xy 67.068817 -493.818195)
			(xy 67.1414 -493.840081) (xy 67.211246 -493.869558) (xy 67.277563 -493.906293) (xy 67.339599 -493.949868)
			(xy 67.396652 -493.99979) (xy 67.448076 -494.055494) (xy 67.493287 -494.116349) (xy 67.531774 -494.181664)
			(xy 67.5631 -494.2507) (xy 67.58691 -494.322675) (xy 67.602935 -494.396773) (xy 67.610994 -494.472154)
			(xy 67.611498 -494.51006) (xy 68.727577 -494.51006) (xy 68.731612 -494.434356) (xy 68.743671 -494.359511)
			(xy 68.763617 -494.28637) (xy 68.791224 -494.215765) (xy 68.82618 -494.148494) (xy 68.868088 -494.085319)
			(xy 68.916474 -494.026957) (xy 68.97079 -493.974069) (xy 69.030419 -493.927254) (xy 69.094687 -493.887042)
			(xy 69.162864 -493.85389) (xy 69.23418 -493.828172) (xy 69.307825 -493.81018) (xy 69.382965 -493.800118)
			(xy 69.458749 -493.798099) (xy 69.534319 -493.804148) (xy 69.608817 -493.818195) (xy 69.6814 -493.840081)
			(xy 69.751246 -493.869558) (xy 69.817563 -493.906293) (xy 69.879599 -493.949868) (xy 69.936652 -493.99979)
			(xy 69.988076 -494.055494) (xy 70.033287 -494.116349) (xy 70.071774 -494.181664) (xy 70.1031 -494.2507)
			(xy 70.12691 -494.322675) (xy 70.142935 -494.396773) (xy 70.150994 -494.472154) (xy 70.151498 -494.51006)
			(xy 71.267577 -494.51006) (xy 71.271612 -494.434356) (xy 71.283671 -494.359511) (xy 71.303617 -494.28637)
			(xy 71.331224 -494.215765) (xy 71.36618 -494.148494) (xy 71.408088 -494.085319) (xy 71.456474 -494.026957)
			(xy 71.51079 -493.974069) (xy 71.570419 -493.927254) (xy 71.634687 -493.887042) (xy 71.702864 -493.85389)
			(xy 71.77418 -493.828172) (xy 71.847825 -493.81018) (xy 71.922965 -493.800118) (xy 71.998749 -493.798099)
			(xy 72.074319 -493.804148) (xy 72.148817 -493.818195) (xy 72.2214 -493.840081) (xy 72.291246 -493.869558)
			(xy 72.357563 -493.906293) (xy 72.419599 -493.949868) (xy 72.476652 -493.99979) (xy 72.528076 -494.055494)
			(xy 72.573287 -494.116349) (xy 72.611774 -494.181664) (xy 72.6431 -494.2507) (xy 72.66691 -494.322675)
			(xy 72.682935 -494.396773) (xy 72.690994 -494.472154) (xy 72.691498 -494.51006) (xy 73.807577 -494.51006)
			(xy 73.811612 -494.434356) (xy 73.823671 -494.359511) (xy 73.843617 -494.28637) (xy 73.871224 -494.215765)
			(xy 73.90618 -494.148494) (xy 73.948088 -494.085319) (xy 73.996474 -494.026957) (xy 74.05079 -493.974069)
			(xy 74.110419 -493.927254) (xy 74.174687 -493.887042) (xy 74.242864 -493.85389) (xy 74.31418 -493.828172)
			(xy 74.387825 -493.81018) (xy 74.462965 -493.800118) (xy 74.538749 -493.798099) (xy 74.614319 -493.804148)
			(xy 74.688817 -493.818195) (xy 74.7614 -493.840081) (xy 74.831246 -493.869558) (xy 74.897563 -493.906293)
			(xy 74.959599 -493.949868) (xy 75.016652 -493.99979) (xy 75.068076 -494.055494) (xy 75.113287 -494.116349)
			(xy 75.151774 -494.181664) (xy 75.1831 -494.2507) (xy 75.20691 -494.322675) (xy 75.222935 -494.396773)
			(xy 75.230994 -494.472154) (xy 75.231498 -494.51006) (xy 76.347577 -494.51006) (xy 76.351612 -494.434356)
			(xy 76.363671 -494.359511) (xy 76.383617 -494.28637) (xy 76.411224 -494.215765) (xy 76.44618 -494.148494)
			(xy 76.488088 -494.085319) (xy 76.536474 -494.026957) (xy 76.59079 -493.974069) (xy 76.650419 -493.927254)
			(xy 76.714687 -493.887042) (xy 76.782864 -493.85389) (xy 76.85418 -493.828172) (xy 76.927825 -493.81018)
			(xy 77.002965 -493.800118) (xy 77.078749 -493.798099) (xy 77.154319 -493.804148) (xy 77.228817 -493.818195)
			(xy 77.3014 -493.840081) (xy 77.371246 -493.869558) (xy 77.437563 -493.906293) (xy 77.499599 -493.949868)
			(xy 77.556652 -493.99979) (xy 77.608076 -494.055494) (xy 77.653287 -494.116349) (xy 77.691774 -494.181664)
			(xy 77.7231 -494.2507) (xy 77.74691 -494.322675) (xy 77.762935 -494.396773) (xy 77.770994 -494.472154)
			(xy 77.771498 -494.51006) (xy 78.887577 -494.51006) (xy 78.891612 -494.434356) (xy 78.903671 -494.359511)
			(xy 78.923617 -494.28637) (xy 78.951224 -494.215765) (xy 78.98618 -494.148494) (xy 79.028088 -494.085319)
			(xy 79.076474 -494.026957) (xy 79.13079 -493.974069) (xy 79.190419 -493.927254) (xy 79.254687 -493.887042)
			(xy 79.322864 -493.85389) (xy 79.39418 -493.828172) (xy 79.467825 -493.81018) (xy 79.542965 -493.800118)
			(xy 79.618749 -493.798099) (xy 79.694319 -493.804148) (xy 79.768817 -493.818195) (xy 79.8414 -493.840081)
			(xy 79.911246 -493.869558) (xy 79.977563 -493.906293) (xy 80.039599 -493.949868) (xy 80.096652 -493.99979)
			(xy 80.148076 -494.055494) (xy 80.193287 -494.116349) (xy 80.231774 -494.181664) (xy 80.2631 -494.2507)
			(xy 80.28691 -494.322675) (xy 80.302935 -494.396773) (xy 80.310994 -494.472154) (xy 80.311498 -494.51006)
			(xy 81.427577 -494.51006) (xy 81.431612 -494.434356) (xy 81.443671 -494.359511) (xy 81.463617 -494.28637)
			(xy 81.491224 -494.215765) (xy 81.52618 -494.148494) (xy 81.568088 -494.085319) (xy 81.616474 -494.026957)
			(xy 81.67079 -493.974069) (xy 81.730419 -493.927254) (xy 81.794687 -493.887042) (xy 81.862864 -493.85389)
			(xy 81.93418 -493.828172) (xy 82.007825 -493.81018) (xy 82.082965 -493.800118) (xy 82.158749 -493.798099)
			(xy 82.234319 -493.804148) (xy 82.308817 -493.818195) (xy 82.3814 -493.840081) (xy 82.451246 -493.869558)
			(xy 82.517563 -493.906293) (xy 82.579599 -493.949868) (xy 82.585544 -493.95507) (xy 86.197697 -493.95507)
			(xy 86.201732 -493.879366) (xy 86.213791 -493.804521) (xy 86.233737 -493.73138) (xy 86.261344 -493.660775)
			(xy 86.2963 -493.593504) (xy 86.338208 -493.530329) (xy 86.386594 -493.471967) (xy 86.44091 -493.419079)
			(xy 86.500539 -493.372264) (xy 86.564807 -493.332052) (xy 86.632984 -493.2989) (xy 86.7043 -493.273182)
			(xy 86.777945 -493.25519) (xy 86.853085 -493.245128) (xy 86.928869 -493.243109) (xy 87.004439 -493.249158)
			(xy 87.078937 -493.263205) (xy 87.15152 -493.285091) (xy 87.221366 -493.314568) (xy 87.287683 -493.351303)
			(xy 87.349719 -493.394878) (xy 87.406772 -493.4448) (xy 87.458196 -493.500504) (xy 87.503407 -493.561359)
			(xy 87.541894 -493.626674) (xy 87.57322 -493.69571) (xy 87.59703 -493.767685) (xy 87.613055 -493.841783)
			(xy 87.621114 -493.917164) (xy 87.621618 -493.95507) (xy 87.621114 -493.992976) (xy 87.613055 -494.068357)
			(xy 87.59703 -494.142455) (xy 87.57322 -494.21443) (xy 87.541894 -494.283466) (xy 87.503407 -494.348781)
			(xy 87.458196 -494.409636) (xy 87.406772 -494.46534) (xy 87.349719 -494.515262) (xy 87.287683 -494.558837)
			(xy 87.221366 -494.595572) (xy 87.15152 -494.625049) (xy 87.078937 -494.646935) (xy 87.004439 -494.660982)
			(xy 86.928869 -494.667031) (xy 86.853085 -494.665012) (xy 86.777945 -494.65495) (xy 86.7043 -494.636958)
			(xy 86.632984 -494.61124) (xy 86.564807 -494.578088) (xy 86.500539 -494.537876) (xy 86.44091 -494.491061)
			(xy 86.386594 -494.438173) (xy 86.338208 -494.379811) (xy 86.2963 -494.316636) (xy 86.261344 -494.249365)
			(xy 86.233737 -494.17876) (xy 86.213791 -494.105619) (xy 86.201732 -494.030774) (xy 86.197697 -493.95507)
			(xy 82.585544 -493.95507) (xy 82.636652 -493.99979) (xy 82.688076 -494.055494) (xy 82.733287 -494.116349)
			(xy 82.771774 -494.181664) (xy 82.8031 -494.2507) (xy 82.82691 -494.322675) (xy 82.842935 -494.396773)
			(xy 82.850994 -494.472154) (xy 82.851498 -494.51006) (xy 82.850994 -494.547966) (xy 82.842935 -494.623347)
			(xy 82.82691 -494.697445) (xy 82.8031 -494.76942) (xy 82.771774 -494.838456) (xy 82.733287 -494.903771)
			(xy 82.688076 -494.964626) (xy 82.636652 -495.02033) (xy 82.579599 -495.070252) (xy 82.517563 -495.113827)
			(xy 82.451246 -495.150562) (xy 82.3814 -495.180039) (xy 82.308817 -495.201925) (xy 82.234319 -495.215972)
			(xy 82.158749 -495.222021) (xy 82.082965 -495.220002) (xy 82.007825 -495.20994) (xy 81.93418 -495.191948)
			(xy 81.862864 -495.16623) (xy 81.794687 -495.133078) (xy 81.730419 -495.092866) (xy 81.67079 -495.046051)
			(xy 81.616474 -494.993163) (xy 81.568088 -494.934801) (xy 81.52618 -494.871626) (xy 81.491224 -494.804355)
			(xy 81.463617 -494.73375) (xy 81.443671 -494.660609) (xy 81.431612 -494.585764) (xy 81.427577 -494.51006)
			(xy 80.311498 -494.51006) (xy 80.310994 -494.547966) (xy 80.302935 -494.623347) (xy 80.28691 -494.697445)
			(xy 80.2631 -494.76942) (xy 80.231774 -494.838456) (xy 80.193287 -494.903771) (xy 80.148076 -494.964626)
			(xy 80.096652 -495.02033) (xy 80.039599 -495.070252) (xy 79.977563 -495.113827) (xy 79.911246 -495.150562)
			(xy 79.8414 -495.180039) (xy 79.768817 -495.201925) (xy 79.694319 -495.215972) (xy 79.618749 -495.222021)
			(xy 79.542965 -495.220002) (xy 79.467825 -495.20994) (xy 79.39418 -495.191948) (xy 79.322864 -495.16623)
			(xy 79.254687 -495.133078) (xy 79.190419 -495.092866) (xy 79.13079 -495.046051) (xy 79.076474 -494.993163)
			(xy 79.028088 -494.934801) (xy 78.98618 -494.871626) (xy 78.951224 -494.804355) (xy 78.923617 -494.73375)
			(xy 78.903671 -494.660609) (xy 78.891612 -494.585764) (xy 78.887577 -494.51006) (xy 77.771498 -494.51006)
			(xy 77.770994 -494.547966) (xy 77.762935 -494.623347) (xy 77.74691 -494.697445) (xy 77.7231 -494.76942)
			(xy 77.691774 -494.838456) (xy 77.653287 -494.903771) (xy 77.608076 -494.964626) (xy 77.556652 -495.02033)
			(xy 77.499599 -495.070252) (xy 77.437563 -495.113827) (xy 77.371246 -495.150562) (xy 77.3014 -495.180039)
			(xy 77.228817 -495.201925) (xy 77.154319 -495.215972) (xy 77.078749 -495.222021) (xy 77.002965 -495.220002)
			(xy 76.927825 -495.20994) (xy 76.85418 -495.191948) (xy 76.782864 -495.16623) (xy 76.714687 -495.133078)
			(xy 76.650419 -495.092866) (xy 76.59079 -495.046051) (xy 76.536474 -494.993163) (xy 76.488088 -494.934801)
			(xy 76.44618 -494.871626) (xy 76.411224 -494.804355) (xy 76.383617 -494.73375) (xy 76.363671 -494.660609)
			(xy 76.351612 -494.585764) (xy 76.347577 -494.51006) (xy 75.231498 -494.51006) (xy 75.230994 -494.547966)
			(xy 75.222935 -494.623347) (xy 75.20691 -494.697445) (xy 75.1831 -494.76942) (xy 75.151774 -494.838456)
			(xy 75.113287 -494.903771) (xy 75.068076 -494.964626) (xy 75.016652 -495.02033) (xy 74.959599 -495.070252)
			(xy 74.897563 -495.113827) (xy 74.831246 -495.150562) (xy 74.7614 -495.180039) (xy 74.688817 -495.201925)
			(xy 74.614319 -495.215972) (xy 74.538749 -495.222021) (xy 74.462965 -495.220002) (xy 74.387825 -495.20994)
			(xy 74.31418 -495.191948) (xy 74.242864 -495.16623) (xy 74.174687 -495.133078) (xy 74.110419 -495.092866)
			(xy 74.05079 -495.046051) (xy 73.996474 -494.993163) (xy 73.948088 -494.934801) (xy 73.90618 -494.871626)
			(xy 73.871224 -494.804355) (xy 73.843617 -494.73375) (xy 73.823671 -494.660609) (xy 73.811612 -494.585764)
			(xy 73.807577 -494.51006) (xy 72.691498 -494.51006) (xy 72.690994 -494.547966) (xy 72.682935 -494.623347)
			(xy 72.66691 -494.697445) (xy 72.6431 -494.76942) (xy 72.611774 -494.838456) (xy 72.573287 -494.903771)
			(xy 72.528076 -494.964626) (xy 72.476652 -495.02033) (xy 72.419599 -495.070252) (xy 72.357563 -495.113827)
			(xy 72.291246 -495.150562) (xy 72.2214 -495.180039) (xy 72.148817 -495.201925) (xy 72.074319 -495.215972)
			(xy 71.998749 -495.222021) (xy 71.922965 -495.220002) (xy 71.847825 -495.20994) (xy 71.77418 -495.191948)
			(xy 71.702864 -495.16623) (xy 71.634687 -495.133078) (xy 71.570419 -495.092866) (xy 71.51079 -495.046051)
			(xy 71.456474 -494.993163) (xy 71.408088 -494.934801) (xy 71.36618 -494.871626) (xy 71.331224 -494.804355)
			(xy 71.303617 -494.73375) (xy 71.283671 -494.660609) (xy 71.271612 -494.585764) (xy 71.267577 -494.51006)
			(xy 70.151498 -494.51006) (xy 70.150994 -494.547966) (xy 70.142935 -494.623347) (xy 70.12691 -494.697445)
			(xy 70.1031 -494.76942) (xy 70.071774 -494.838456) (xy 70.033287 -494.903771) (xy 69.988076 -494.964626)
			(xy 69.936652 -495.02033) (xy 69.879599 -495.070252) (xy 69.817563 -495.113827) (xy 69.751246 -495.150562)
			(xy 69.6814 -495.180039) (xy 69.608817 -495.201925) (xy 69.534319 -495.215972) (xy 69.458749 -495.222021)
			(xy 69.382965 -495.220002) (xy 69.307825 -495.20994) (xy 69.23418 -495.191948) (xy 69.162864 -495.16623)
			(xy 69.094687 -495.133078) (xy 69.030419 -495.092866) (xy 68.97079 -495.046051) (xy 68.916474 -494.993163)
			(xy 68.868088 -494.934801) (xy 68.82618 -494.871626) (xy 68.791224 -494.804355) (xy 68.763617 -494.73375)
			(xy 68.743671 -494.660609) (xy 68.731612 -494.585764) (xy 68.727577 -494.51006) (xy 67.611498 -494.51006)
			(xy 67.610994 -494.547966) (xy 67.602935 -494.623347) (xy 67.58691 -494.697445) (xy 67.5631 -494.76942)
			(xy 67.531774 -494.838456) (xy 67.493287 -494.903771) (xy 67.448076 -494.964626) (xy 67.396652 -495.02033)
			(xy 67.339599 -495.070252) (xy 67.277563 -495.113827) (xy 67.211246 -495.150562) (xy 67.1414 -495.180039)
			(xy 67.068817 -495.201925) (xy 66.994319 -495.215972) (xy 66.918749 -495.222021) (xy 66.842965 -495.220002)
			(xy 66.767825 -495.20994) (xy 66.69418 -495.191948) (xy 66.622864 -495.16623) (xy 66.554687 -495.133078)
			(xy 66.490419 -495.092866) (xy 66.43079 -495.046051) (xy 66.376474 -494.993163) (xy 66.328088 -494.934801)
			(xy 66.28618 -494.871626) (xy 66.251224 -494.804355) (xy 66.223617 -494.73375) (xy 66.203671 -494.660609)
			(xy 66.191612 -494.585764) (xy 66.187577 -494.51006) (xy 65.071498 -494.51006) (xy 65.070994 -494.547966)
			(xy 65.062935 -494.623347) (xy 65.04691 -494.697445) (xy 65.0231 -494.76942) (xy 64.991774 -494.838456)
			(xy 64.953287 -494.903771) (xy 64.908076 -494.964626) (xy 64.856652 -495.02033) (xy 64.799599 -495.070252)
			(xy 64.737563 -495.113827) (xy 64.671246 -495.150562) (xy 64.6014 -495.180039) (xy 64.528817 -495.201925)
			(xy 64.454319 -495.215972) (xy 64.378749 -495.222021) (xy 64.302965 -495.220002) (xy 64.227825 -495.20994)
			(xy 64.15418 -495.191948) (xy 64.082864 -495.16623) (xy 64.014687 -495.133078) (xy 63.950419 -495.092866)
			(xy 63.89079 -495.046051) (xy 63.836474 -494.993163) (xy 63.788088 -494.934801) (xy 63.74618 -494.871626)
			(xy 63.711224 -494.804355) (xy 63.683617 -494.73375) (xy 63.663671 -494.660609) (xy 63.651612 -494.585764)
			(xy 63.647577 -494.51006) (xy 42.501239 -494.51006) (xy 42.515699 -494.520266) (xy 42.604766 -494.592723)
			(xy 42.688681 -494.671089) (xy 42.767054 -494.754998) (xy 42.839517 -494.84406) (xy 42.905734 -494.937859)
			(xy 42.965396 -495.035958) (xy 43.018225 -495.1379) (xy 43.056094 -495.22507) (xy 84.927697 -495.22507)
			(xy 84.931732 -495.149366) (xy 84.943791 -495.074521) (xy 84.963737 -495.00138) (xy 84.991344 -494.930775)
			(xy 85.0263 -494.863504) (xy 85.068208 -494.800329) (xy 85.116594 -494.741967) (xy 85.17091 -494.689079)
			(xy 85.230539 -494.642264) (xy 85.294807 -494.602052) (xy 85.362984 -494.5689) (xy 85.4343 -494.543182)
			(xy 85.507945 -494.52519) (xy 85.583085 -494.515128) (xy 85.658869 -494.513109) (xy 85.734439 -494.519158)
			(xy 85.808937 -494.533205) (xy 85.88152 -494.555091) (xy 85.951366 -494.584568) (xy 86.017683 -494.621303)
			(xy 86.079719 -494.664878) (xy 86.136772 -494.7148) (xy 86.188196 -494.770504) (xy 86.233407 -494.831359)
			(xy 86.271894 -494.896674) (xy 86.30322 -494.96571) (xy 86.32703 -495.037685) (xy 86.343055 -495.111783)
			(xy 86.351114 -495.187164) (xy 86.351618 -495.22507) (xy 86.351114 -495.262976) (xy 86.343055 -495.338357)
			(xy 86.32703 -495.412455) (xy 86.30322 -495.48443) (xy 86.271894 -495.553466) (xy 86.233407 -495.618781)
			(xy 86.188196 -495.679636) (xy 86.136772 -495.73534) (xy 86.079719 -495.785262) (xy 86.017683 -495.828837)
			(xy 85.951366 -495.865572) (xy 85.88152 -495.895049) (xy 85.808937 -495.916935) (xy 85.734439 -495.930982)
			(xy 85.658869 -495.937031) (xy 85.583085 -495.935012) (xy 85.507945 -495.92495) (xy 85.4343 -495.906958)
			(xy 85.362984 -495.88124) (xy 85.294807 -495.848088) (xy 85.230539 -495.807876) (xy 85.17091 -495.761061)
			(xy 85.116594 -495.708173) (xy 85.068208 -495.649811) (xy 85.0263 -495.586636) (xy 84.991344 -495.519365)
			(xy 84.963737 -495.44876) (xy 84.943791 -495.375619) (xy 84.931732 -495.300774) (xy 84.927697 -495.22507)
			(xy 43.056094 -495.22507) (xy 43.063974 -495.243209) (xy 43.10243 -495.351394) (xy 43.133415 -495.461952)
			(xy 43.156782 -495.574366) (xy 43.172424 -495.688113) (xy 43.180268 -495.802661) (xy 43.180762 -495.86007)
			(xy 43.180576 -495.893253) (xy 43.177909 -495.959567) (xy 43.175428 -495.992658) (xy 43.170272 -496.050942)
			(xy 43.152948 -496.166671) (xy 43.127616 -496.280914) (xy 43.094401 -496.393119) (xy 43.056327 -496.49507)
			(xy 86.197697 -496.49507) (xy 86.201732 -496.419366) (xy 86.213791 -496.344521) (xy 86.233737 -496.27138)
			(xy 86.261344 -496.200775) (xy 86.2963 -496.133504) (xy 86.338208 -496.070329) (xy 86.386594 -496.011967)
			(xy 86.44091 -495.959079) (xy 86.500539 -495.912264) (xy 86.564807 -495.872052) (xy 86.632984 -495.8389)
			(xy 86.7043 -495.813182) (xy 86.777945 -495.79519) (xy 86.853085 -495.785128) (xy 86.928869 -495.783109)
			(xy 87.004439 -495.789158) (xy 87.078937 -495.803205) (xy 87.15152 -495.825091) (xy 87.221366 -495.854568)
			(xy 87.287683 -495.891303) (xy 87.349719 -495.934878) (xy 87.406772 -495.9848) (xy 87.458196 -496.040504)
			(xy 87.503407 -496.101359) (xy 87.541894 -496.166674) (xy 87.57322 -496.23571) (xy 87.59703 -496.307685)
			(xy 87.613055 -496.381783) (xy 87.621114 -496.457164) (xy 87.621618 -496.49507) (xy 87.621114 -496.532976)
			(xy 87.613055 -496.608357) (xy 87.59703 -496.682455) (xy 87.57322 -496.75443) (xy 87.541894 -496.823466)
			(xy 87.503407 -496.888781) (xy 87.458196 -496.949636) (xy 87.406772 -497.00534) (xy 87.349719 -497.055262)
			(xy 87.287683 -497.098837) (xy 87.221366 -497.135572) (xy 87.15152 -497.165049) (xy 87.078937 -497.186935)
			(xy 87.004439 -497.200982) (xy 86.928869 -497.207031) (xy 86.853085 -497.205012) (xy 86.777945 -497.19495)
			(xy 86.7043 -497.176958) (xy 86.632984 -497.15124) (xy 86.564807 -497.118088) (xy 86.500539 -497.077876)
			(xy 86.44091 -497.031061) (xy 86.386594 -496.978173) (xy 86.338208 -496.919811) (xy 86.2963 -496.856636)
			(xy 86.261344 -496.789365) (xy 86.233737 -496.71876) (xy 86.213791 -496.645619) (xy 86.201732 -496.570774)
			(xy 86.197697 -496.49507) (xy 43.056327 -496.49507) (xy 43.053462 -496.502742) (xy 43.004999 -496.609253)
			(xy 42.949245 -496.712135) (xy 42.886471 -496.810891) (xy 42.816981 -496.905042) (xy 42.741111 -496.994132)
			(xy 42.659229 -497.077729) (xy 42.571732 -497.15543) (xy 42.500813 -497.21008) (xy 63.647577 -497.21008)
			(xy 63.651612 -497.134376) (xy 63.663671 -497.059531) (xy 63.683617 -496.98639) (xy 63.711224 -496.915785)
			(xy 63.74618 -496.848514) (xy 63.788088 -496.785339) (xy 63.836474 -496.726977) (xy 63.89079 -496.674089)
			(xy 63.950419 -496.627274) (xy 64.014687 -496.587062) (xy 64.082864 -496.55391) (xy 64.15418 -496.528192)
			(xy 64.227825 -496.5102) (xy 64.302965 -496.500138) (xy 64.378749 -496.498119) (xy 64.454319 -496.504168)
			(xy 64.528817 -496.518215) (xy 64.6014 -496.540101) (xy 64.671246 -496.569578) (xy 64.737563 -496.606313)
			(xy 64.799599 -496.649888) (xy 64.856652 -496.69981) (xy 64.908076 -496.755514) (xy 64.953287 -496.816369)
			(xy 64.991774 -496.881684) (xy 65.0231 -496.95072) (xy 65.04691 -497.022695) (xy 65.062935 -497.096793)
			(xy 65.070994 -497.172174) (xy 65.071498 -497.21008) (xy 66.187577 -497.21008) (xy 66.191612 -497.134376)
			(xy 66.203671 -497.059531) (xy 66.223617 -496.98639) (xy 66.251224 -496.915785) (xy 66.28618 -496.848514)
			(xy 66.328088 -496.785339) (xy 66.376474 -496.726977) (xy 66.43079 -496.674089) (xy 66.490419 -496.627274)
			(xy 66.554687 -496.587062) (xy 66.622864 -496.55391) (xy 66.69418 -496.528192) (xy 66.767825 -496.5102)
			(xy 66.842965 -496.500138) (xy 66.918749 -496.498119) (xy 66.994319 -496.504168) (xy 67.068817 -496.518215)
			(xy 67.1414 -496.540101) (xy 67.211246 -496.569578) (xy 67.277563 -496.606313) (xy 67.339599 -496.649888)
			(xy 67.396652 -496.69981) (xy 67.448076 -496.755514) (xy 67.493287 -496.816369) (xy 67.531774 -496.881684)
			(xy 67.5631 -496.95072) (xy 67.58691 -497.022695) (xy 67.602935 -497.096793) (xy 67.610994 -497.172174)
			(xy 67.611498 -497.21008) (xy 68.727577 -497.21008) (xy 68.731612 -497.134376) (xy 68.743671 -497.059531)
			(xy 68.763617 -496.98639) (xy 68.791224 -496.915785) (xy 68.82618 -496.848514) (xy 68.868088 -496.785339)
			(xy 68.916474 -496.726977) (xy 68.97079 -496.674089) (xy 69.030419 -496.627274) (xy 69.094687 -496.587062)
			(xy 69.162864 -496.55391) (xy 69.23418 -496.528192) (xy 69.307825 -496.5102) (xy 69.382965 -496.500138)
			(xy 69.458749 -496.498119) (xy 69.534319 -496.504168) (xy 69.608817 -496.518215) (xy 69.6814 -496.540101)
			(xy 69.751246 -496.569578) (xy 69.817563 -496.606313) (xy 69.879599 -496.649888) (xy 69.936652 -496.69981)
			(xy 69.988076 -496.755514) (xy 70.033287 -496.816369) (xy 70.071774 -496.881684) (xy 70.1031 -496.95072)
			(xy 70.12691 -497.022695) (xy 70.142935 -497.096793) (xy 70.150994 -497.172174) (xy 70.151498 -497.21008)
			(xy 71.267577 -497.21008) (xy 71.271612 -497.134376) (xy 71.283671 -497.059531) (xy 71.303617 -496.98639)
			(xy 71.331224 -496.915785) (xy 71.36618 -496.848514) (xy 71.408088 -496.785339) (xy 71.456474 -496.726977)
			(xy 71.51079 -496.674089) (xy 71.570419 -496.627274) (xy 71.634687 -496.587062) (xy 71.702864 -496.55391)
			(xy 71.77418 -496.528192) (xy 71.847825 -496.5102) (xy 71.922965 -496.500138) (xy 71.998749 -496.498119)
			(xy 72.074319 -496.504168) (xy 72.148817 -496.518215) (xy 72.2214 -496.540101) (xy 72.291246 -496.569578)
			(xy 72.357563 -496.606313) (xy 72.419599 -496.649888) (xy 72.476652 -496.69981) (xy 72.528076 -496.755514)
			(xy 72.573287 -496.816369) (xy 72.611774 -496.881684) (xy 72.6431 -496.95072) (xy 72.66691 -497.022695)
			(xy 72.682935 -497.096793) (xy 72.690994 -497.172174) (xy 72.691498 -497.21008) (xy 73.807577 -497.21008)
			(xy 73.811612 -497.134376) (xy 73.823671 -497.059531) (xy 73.843617 -496.98639) (xy 73.871224 -496.915785)
			(xy 73.90618 -496.848514) (xy 73.948088 -496.785339) (xy 73.996474 -496.726977) (xy 74.05079 -496.674089)
			(xy 74.110419 -496.627274) (xy 74.174687 -496.587062) (xy 74.242864 -496.55391) (xy 74.31418 -496.528192)
			(xy 74.387825 -496.5102) (xy 74.462965 -496.500138) (xy 74.538749 -496.498119) (xy 74.614319 -496.504168)
			(xy 74.688817 -496.518215) (xy 74.7614 -496.540101) (xy 74.831246 -496.569578) (xy 74.897563 -496.606313)
			(xy 74.959599 -496.649888) (xy 75.016652 -496.69981) (xy 75.068076 -496.755514) (xy 75.113287 -496.816369)
			(xy 75.151774 -496.881684) (xy 75.1831 -496.95072) (xy 75.20691 -497.022695) (xy 75.222935 -497.096793)
			(xy 75.230994 -497.172174) (xy 75.231498 -497.21008) (xy 76.347577 -497.21008) (xy 76.351612 -497.134376)
			(xy 76.363671 -497.059531) (xy 76.383617 -496.98639) (xy 76.411224 -496.915785) (xy 76.44618 -496.848514)
			(xy 76.488088 -496.785339) (xy 76.536474 -496.726977) (xy 76.59079 -496.674089) (xy 76.650419 -496.627274)
			(xy 76.714687 -496.587062) (xy 76.782864 -496.55391) (xy 76.85418 -496.528192) (xy 76.927825 -496.5102)
			(xy 77.002965 -496.500138) (xy 77.078749 -496.498119) (xy 77.154319 -496.504168) (xy 77.228817 -496.518215)
			(xy 77.3014 -496.540101) (xy 77.371246 -496.569578) (xy 77.437563 -496.606313) (xy 77.499599 -496.649888)
			(xy 77.556652 -496.69981) (xy 77.608076 -496.755514) (xy 77.653287 -496.816369) (xy 77.691774 -496.881684)
			(xy 77.7231 -496.95072) (xy 77.74691 -497.022695) (xy 77.762935 -497.096793) (xy 77.770994 -497.172174)
			(xy 77.771498 -497.21008) (xy 78.887577 -497.21008) (xy 78.891612 -497.134376) (xy 78.903671 -497.059531)
			(xy 78.923617 -496.98639) (xy 78.951224 -496.915785) (xy 78.98618 -496.848514) (xy 79.028088 -496.785339)
			(xy 79.076474 -496.726977) (xy 79.13079 -496.674089) (xy 79.190419 -496.627274) (xy 79.254687 -496.587062)
			(xy 79.322864 -496.55391) (xy 79.39418 -496.528192) (xy 79.467825 -496.5102) (xy 79.542965 -496.500138)
			(xy 79.618749 -496.498119) (xy 79.694319 -496.504168) (xy 79.768817 -496.518215) (xy 79.8414 -496.540101)
			(xy 79.911246 -496.569578) (xy 79.977563 -496.606313) (xy 80.039599 -496.649888) (xy 80.096652 -496.69981)
			(xy 80.148076 -496.755514) (xy 80.193287 -496.816369) (xy 80.231774 -496.881684) (xy 80.2631 -496.95072)
			(xy 80.28691 -497.022695) (xy 80.302935 -497.096793) (xy 80.310994 -497.172174) (xy 80.311498 -497.21008)
			(xy 81.427577 -497.21008) (xy 81.431612 -497.134376) (xy 81.443671 -497.059531) (xy 81.463617 -496.98639)
			(xy 81.491224 -496.915785) (xy 81.52618 -496.848514) (xy 81.568088 -496.785339) (xy 81.616474 -496.726977)
			(xy 81.67079 -496.674089) (xy 81.730419 -496.627274) (xy 81.794687 -496.587062) (xy 81.862864 -496.55391)
			(xy 81.93418 -496.528192) (xy 82.007825 -496.5102) (xy 82.082965 -496.500138) (xy 82.158749 -496.498119)
			(xy 82.234319 -496.504168) (xy 82.308817 -496.518215) (xy 82.3814 -496.540101) (xy 82.451246 -496.569578)
			(xy 82.517563 -496.606313) (xy 82.579599 -496.649888) (xy 82.636652 -496.69981) (xy 82.688076 -496.755514)
			(xy 82.733287 -496.816369) (xy 82.771774 -496.881684) (xy 82.8031 -496.95072) (xy 82.82691 -497.022695)
			(xy 82.842935 -497.096793) (xy 82.850994 -497.172174) (xy 82.851498 -497.21008) (xy 82.850994 -497.247986)
			(xy 82.842935 -497.323367) (xy 82.82691 -497.397465) (xy 82.8031 -497.46944) (xy 82.771774 -497.538476)
			(xy 82.733287 -497.603791) (xy 82.688076 -497.664646) (xy 82.636652 -497.72035) (xy 82.585544 -497.76507)
			(xy 84.927697 -497.76507) (xy 84.931732 -497.689366) (xy 84.943791 -497.614521) (xy 84.963737 -497.54138)
			(xy 84.991344 -497.470775) (xy 85.0263 -497.403504) (xy 85.068208 -497.340329) (xy 85.116594 -497.281967)
			(xy 85.17091 -497.229079) (xy 85.230539 -497.182264) (xy 85.294807 -497.142052) (xy 85.362984 -497.1089)
			(xy 85.4343 -497.083182) (xy 85.507945 -497.06519) (xy 85.583085 -497.055128) (xy 85.658869 -497.053109)
			(xy 85.734439 -497.059158) (xy 85.808937 -497.073205) (xy 85.88152 -497.095091) (xy 85.951366 -497.124568)
			(xy 86.017683 -497.161303) (xy 86.079719 -497.204878) (xy 86.136772 -497.2548) (xy 86.188196 -497.310504)
			(xy 86.233407 -497.371359) (xy 86.271894 -497.436674) (xy 86.30322 -497.50571) (xy 86.32703 -497.577685)
			(xy 86.343055 -497.651783) (xy 86.351114 -497.727164) (xy 86.351618 -497.76507) (xy 87.467697 -497.76507)
			(xy 87.471732 -497.689366) (xy 87.483791 -497.614521) (xy 87.503737 -497.54138) (xy 87.531344 -497.470775)
			(xy 87.5663 -497.403504) (xy 87.608208 -497.340329) (xy 87.656594 -497.281967) (xy 87.71091 -497.229079)
			(xy 87.770539 -497.182264) (xy 87.834807 -497.142052) (xy 87.902984 -497.1089) (xy 87.9743 -497.083182)
			(xy 88.047945 -497.06519) (xy 88.123085 -497.055128) (xy 88.198869 -497.053109) (xy 88.274439 -497.059158)
			(xy 88.348937 -497.073205) (xy 88.42152 -497.095091) (xy 88.491366 -497.124568) (xy 88.557683 -497.161303)
			(xy 88.619719 -497.204878) (xy 88.676772 -497.2548) (xy 88.728196 -497.310504) (xy 88.773407 -497.371359)
			(xy 88.811894 -497.436674) (xy 88.84322 -497.50571) (xy 88.86703 -497.577685) (xy 88.883055 -497.651783)
			(xy 88.891114 -497.727164) (xy 88.891618 -497.76507) (xy 90.007697 -497.76507) (xy 90.011732 -497.689366)
			(xy 90.023791 -497.614521) (xy 90.043737 -497.54138) (xy 90.071344 -497.470775) (xy 90.1063 -497.403504)
			(xy 90.148208 -497.340329) (xy 90.196594 -497.281967) (xy 90.25091 -497.229079) (xy 90.310539 -497.182264)
			(xy 90.374807 -497.142052) (xy 90.442984 -497.1089) (xy 90.5143 -497.083182) (xy 90.587945 -497.06519)
			(xy 90.663085 -497.055128) (xy 90.738869 -497.053109) (xy 90.814439 -497.059158) (xy 90.888937 -497.073205)
			(xy 90.96152 -497.095091) (xy 91.031366 -497.124568) (xy 91.097683 -497.161303) (xy 91.159719 -497.204878)
			(xy 91.165664 -497.21008) (xy 93.154506 -497.21008) (xy 93.158522 -497.09381) (xy 93.170549 -496.978095)
			(xy 93.190531 -496.863485) (xy 93.218373 -496.750526) (xy 93.253942 -496.639758) (xy 93.297068 -496.531707)
			(xy 93.347545 -496.426889) (xy 93.405134 -496.325804) (xy 93.46956 -496.228932) (xy 93.540515 -496.136736)
			(xy 93.617662 -496.049655) (xy 93.700633 -495.968104) (xy 93.789033 -495.892472) (xy 93.88244 -495.823118)
			(xy 93.980409 -495.760375) (xy 94.082473 -495.704539) (xy 94.188147 -495.655878) (xy 94.296926 -495.614624)
			(xy 94.408291 -495.580973) (xy 94.521714 -495.555085) (xy 94.636651 -495.537084) (xy 94.752557 -495.527055)
			(xy 94.868879 -495.525047) (xy 94.985062 -495.531069) (xy 95.100553 -495.545092) (xy 95.214801 -495.56705)
			(xy 95.327262 -495.596837) (xy 95.4374 -495.634312) (xy 95.54469 -495.679297) (xy 95.648621 -495.731576)
			(xy 95.748697 -495.790901) (xy 95.844443 -495.856989) (xy 95.9354 -495.929525) (xy 96.021136 -496.008164)
			(xy 96.101243 -496.09253) (xy 96.175339 -496.182222) (xy 96.243069 -496.276812) (xy 96.304113 -496.37585)
			(xy 96.358178 -496.478863) (xy 96.405008 -496.58536) (xy 96.444379 -496.694835) (xy 96.476103 -496.806765)
			(xy 96.500029 -496.920617) (xy 96.516043 -497.035849) (xy 96.52407 -497.151911) (xy 96.524572 -497.21008)
			(xy 96.52407 -497.268249) (xy 96.516043 -497.384311) (xy 96.500029 -497.499543) (xy 96.476103 -497.613395)
			(xy 96.444379 -497.725325) (xy 96.405008 -497.8348) (xy 96.358178 -497.941297) (xy 96.304113 -498.04431)
			(xy 96.243069 -498.143348) (xy 96.175339 -498.237938) (xy 96.101243 -498.32763) (xy 96.021136 -498.411996)
			(xy 95.9354 -498.490635) (xy 95.844443 -498.563171) (xy 95.748697 -498.629259) (xy 95.648621 -498.688584)
			(xy 95.54469 -498.740863) (xy 95.4374 -498.785848) (xy 95.327262 -498.823323) (xy 95.214801 -498.85311)
			(xy 95.100553 -498.875068) (xy 94.985062 -498.889091) (xy 94.868879 -498.895113) (xy 94.752557 -498.893105)
			(xy 94.636651 -498.883076) (xy 94.521714 -498.865075) (xy 94.408291 -498.839187) (xy 94.296926 -498.805536)
			(xy 94.188147 -498.764282) (xy 94.082473 -498.715621) (xy 93.980409 -498.659785) (xy 93.88244 -498.597042)
			(xy 93.789033 -498.527688) (xy 93.700633 -498.452056) (xy 93.617662 -498.370505) (xy 93.540515 -498.283424)
			(xy 93.46956 -498.191228) (xy 93.405134 -498.094356) (xy 93.347545 -497.993271) (xy 93.297068 -497.888453)
			(xy 93.253942 -497.780402) (xy 93.218373 -497.669634) (xy 93.190531 -497.556675) (xy 93.170549 -497.442065)
			(xy 93.158522 -497.32635) (xy 93.154506 -497.21008) (xy 91.165664 -497.21008) (xy 91.216772 -497.2548)
			(xy 91.268196 -497.310504) (xy 91.313407 -497.371359) (xy 91.351894 -497.436674) (xy 91.38322 -497.50571)
			(xy 91.40703 -497.577685) (xy 91.423055 -497.651783) (xy 91.431114 -497.727164) (xy 91.431618 -497.76507)
			(xy 91.431114 -497.802976) (xy 91.423055 -497.878357) (xy 91.40703 -497.952455) (xy 91.38322 -498.02443)
			(xy 91.351894 -498.093466) (xy 91.313407 -498.158781) (xy 91.268196 -498.219636) (xy 91.216772 -498.27534)
			(xy 91.159719 -498.325262) (xy 91.097683 -498.368837) (xy 91.031366 -498.405572) (xy 90.96152 -498.435049)
			(xy 90.888937 -498.456935) (xy 90.814439 -498.470982) (xy 90.738869 -498.477031) (xy 90.663085 -498.475012)
			(xy 90.587945 -498.46495) (xy 90.5143 -498.446958) (xy 90.442984 -498.42124) (xy 90.374807 -498.388088)
			(xy 90.310539 -498.347876) (xy 90.25091 -498.301061) (xy 90.196594 -498.248173) (xy 90.148208 -498.189811)
			(xy 90.1063 -498.126636) (xy 90.071344 -498.059365) (xy 90.043737 -497.98876) (xy 90.023791 -497.915619)
			(xy 90.011732 -497.840774) (xy 90.007697 -497.76507) (xy 88.891618 -497.76507) (xy 88.891114 -497.802976)
			(xy 88.883055 -497.878357) (xy 88.86703 -497.952455) (xy 88.84322 -498.02443) (xy 88.811894 -498.093466)
			(xy 88.773407 -498.158781) (xy 88.728196 -498.219636) (xy 88.676772 -498.27534) (xy 88.619719 -498.325262)
			(xy 88.557683 -498.368837) (xy 88.491366 -498.405572) (xy 88.42152 -498.435049) (xy 88.348937 -498.456935)
			(xy 88.274439 -498.470982) (xy 88.198869 -498.477031) (xy 88.123085 -498.475012) (xy 88.047945 -498.46495)
			(xy 87.9743 -498.446958) (xy 87.902984 -498.42124) (xy 87.834807 -498.388088) (xy 87.770539 -498.347876)
			(xy 87.71091 -498.301061) (xy 87.656594 -498.248173) (xy 87.608208 -498.189811) (xy 87.5663 -498.126636)
			(xy 87.531344 -498.059365) (xy 87.503737 -497.98876) (xy 87.483791 -497.915619) (xy 87.471732 -497.840774)
			(xy 87.467697 -497.76507) (xy 86.351618 -497.76507) (xy 86.351114 -497.802976) (xy 86.343055 -497.878357)
			(xy 86.32703 -497.952455) (xy 86.30322 -498.02443) (xy 86.271894 -498.093466) (xy 86.233407 -498.158781)
			(xy 86.188196 -498.219636) (xy 86.136772 -498.27534) (xy 86.079719 -498.325262) (xy 86.017683 -498.368837)
			(xy 85.951366 -498.405572) (xy 85.88152 -498.435049) (xy 85.808937 -498.456935) (xy 85.734439 -498.470982)
			(xy 85.658869 -498.477031) (xy 85.583085 -498.475012) (xy 85.507945 -498.46495) (xy 85.4343 -498.446958)
			(xy 85.362984 -498.42124) (xy 85.294807 -498.388088) (xy 85.230539 -498.347876) (xy 85.17091 -498.301061)
			(xy 85.116594 -498.248173) (xy 85.068208 -498.189811) (xy 85.0263 -498.126636) (xy 84.991344 -498.059365)
			(xy 84.963737 -497.98876) (xy 84.943791 -497.915619) (xy 84.931732 -497.840774) (xy 84.927697 -497.76507)
			(xy 82.585544 -497.76507) (xy 82.579599 -497.770272) (xy 82.517563 -497.813847) (xy 82.451246 -497.850582)
			(xy 82.3814 -497.880059) (xy 82.308817 -497.901945) (xy 82.234319 -497.915992) (xy 82.158749 -497.922041)
			(xy 82.082965 -497.920022) (xy 82.007825 -497.90996) (xy 81.93418 -497.891968) (xy 81.862864 -497.86625)
			(xy 81.794687 -497.833098) (xy 81.730419 -497.792886) (xy 81.67079 -497.746071) (xy 81.616474 -497.693183)
			(xy 81.568088 -497.634821) (xy 81.52618 -497.571646) (xy 81.491224 -497.504375) (xy 81.463617 -497.43377)
			(xy 81.443671 -497.360629) (xy 81.431612 -497.285784) (xy 81.427577 -497.21008) (xy 80.311498 -497.21008)
			(xy 80.310994 -497.247986) (xy 80.302935 -497.323367) (xy 80.28691 -497.397465) (xy 80.2631 -497.46944)
			(xy 80.231774 -497.538476) (xy 80.193287 -497.603791) (xy 80.148076 -497.664646) (xy 80.096652 -497.72035)
			(xy 80.039599 -497.770272) (xy 79.977563 -497.813847) (xy 79.911246 -497.850582) (xy 79.8414 -497.880059)
			(xy 79.768817 -497.901945) (xy 79.694319 -497.915992) (xy 79.618749 -497.922041) (xy 79.542965 -497.920022)
			(xy 79.467825 -497.90996) (xy 79.39418 -497.891968) (xy 79.322864 -497.86625) (xy 79.254687 -497.833098)
			(xy 79.190419 -497.792886) (xy 79.13079 -497.746071) (xy 79.076474 -497.693183) (xy 79.028088 -497.634821)
			(xy 78.98618 -497.571646) (xy 78.951224 -497.504375) (xy 78.923617 -497.43377) (xy 78.903671 -497.360629)
			(xy 78.891612 -497.285784) (xy 78.887577 -497.21008) (xy 77.771498 -497.21008) (xy 77.770994 -497.247986)
			(xy 77.762935 -497.323367) (xy 77.74691 -497.397465) (xy 77.7231 -497.46944) (xy 77.691774 -497.538476)
			(xy 77.653287 -497.603791) (xy 77.608076 -497.664646) (xy 77.556652 -497.72035) (xy 77.499599 -497.770272)
			(xy 77.437563 -497.813847) (xy 77.371246 -497.850582) (xy 77.3014 -497.880059) (xy 77.228817 -497.901945)
			(xy 77.154319 -497.915992) (xy 77.078749 -497.922041) (xy 77.002965 -497.920022) (xy 76.927825 -497.90996)
			(xy 76.85418 -497.891968) (xy 76.782864 -497.86625) (xy 76.714687 -497.833098) (xy 76.650419 -497.792886)
			(xy 76.59079 -497.746071) (xy 76.536474 -497.693183) (xy 76.488088 -497.634821) (xy 76.44618 -497.571646)
			(xy 76.411224 -497.504375) (xy 76.383617 -497.43377) (xy 76.363671 -497.360629) (xy 76.351612 -497.285784)
			(xy 76.347577 -497.21008) (xy 75.231498 -497.21008) (xy 75.230994 -497.247986) (xy 75.222935 -497.323367)
			(xy 75.20691 -497.397465) (xy 75.1831 -497.46944) (xy 75.151774 -497.538476) (xy 75.113287 -497.603791)
			(xy 75.068076 -497.664646) (xy 75.016652 -497.72035) (xy 74.959599 -497.770272) (xy 74.897563 -497.813847)
			(xy 74.831246 -497.850582) (xy 74.7614 -497.880059) (xy 74.688817 -497.901945) (xy 74.614319 -497.915992)
			(xy 74.538749 -497.922041) (xy 74.462965 -497.920022) (xy 74.387825 -497.90996) (xy 74.31418 -497.891968)
			(xy 74.242864 -497.86625) (xy 74.174687 -497.833098) (xy 74.110419 -497.792886) (xy 74.05079 -497.746071)
			(xy 73.996474 -497.693183) (xy 73.948088 -497.634821) (xy 73.90618 -497.571646) (xy 73.871224 -497.504375)
			(xy 73.843617 -497.43377) (xy 73.823671 -497.360629) (xy 73.811612 -497.285784) (xy 73.807577 -497.21008)
			(xy 72.691498 -497.21008) (xy 72.690994 -497.247986) (xy 72.682935 -497.323367) (xy 72.66691 -497.397465)
			(xy 72.6431 -497.46944) (xy 72.611774 -497.538476) (xy 72.573287 -497.603791) (xy 72.528076 -497.664646)
			(xy 72.476652 -497.72035) (xy 72.419599 -497.770272) (xy 72.357563 -497.813847) (xy 72.291246 -497.850582)
			(xy 72.2214 -497.880059) (xy 72.148817 -497.901945) (xy 72.074319 -497.915992) (xy 71.998749 -497.922041)
			(xy 71.922965 -497.920022) (xy 71.847825 -497.90996) (xy 71.77418 -497.891968) (xy 71.702864 -497.86625)
			(xy 71.634687 -497.833098) (xy 71.570419 -497.792886) (xy 71.51079 -497.746071) (xy 71.456474 -497.693183)
			(xy 71.408088 -497.634821) (xy 71.36618 -497.571646) (xy 71.331224 -497.504375) (xy 71.303617 -497.43377)
			(xy 71.283671 -497.360629) (xy 71.271612 -497.285784) (xy 71.267577 -497.21008) (xy 70.151498 -497.21008)
			(xy 70.150994 -497.247986) (xy 70.142935 -497.323367) (xy 70.12691 -497.397465) (xy 70.1031 -497.46944)
			(xy 70.071774 -497.538476) (xy 70.033287 -497.603791) (xy 69.988076 -497.664646) (xy 69.936652 -497.72035)
			(xy 69.879599 -497.770272) (xy 69.817563 -497.813847) (xy 69.751246 -497.850582) (xy 69.6814 -497.880059)
			(xy 69.608817 -497.901945) (xy 69.534319 -497.915992) (xy 69.458749 -497.922041) (xy 69.382965 -497.920022)
			(xy 69.307825 -497.90996) (xy 69.23418 -497.891968) (xy 69.162864 -497.86625) (xy 69.094687 -497.833098)
			(xy 69.030419 -497.792886) (xy 68.97079 -497.746071) (xy 68.916474 -497.693183) (xy 68.868088 -497.634821)
			(xy 68.82618 -497.571646) (xy 68.791224 -497.504375) (xy 68.763617 -497.43377) (xy 68.743671 -497.360629)
			(xy 68.731612 -497.285784) (xy 68.727577 -497.21008) (xy 67.611498 -497.21008) (xy 67.610994 -497.247986)
			(xy 67.602935 -497.323367) (xy 67.58691 -497.397465) (xy 67.5631 -497.46944) (xy 67.531774 -497.538476)
			(xy 67.493287 -497.603791) (xy 67.448076 -497.664646) (xy 67.396652 -497.72035) (xy 67.339599 -497.770272)
			(xy 67.277563 -497.813847) (xy 67.211246 -497.850582) (xy 67.1414 -497.880059) (xy 67.068817 -497.901945)
			(xy 66.994319 -497.915992) (xy 66.918749 -497.922041) (xy 66.842965 -497.920022) (xy 66.767825 -497.90996)
			(xy 66.69418 -497.891968) (xy 66.622864 -497.86625) (xy 66.554687 -497.833098) (xy 66.490419 -497.792886)
			(xy 66.43079 -497.746071) (xy 66.376474 -497.693183) (xy 66.328088 -497.634821) (xy 66.28618 -497.571646)
			(xy 66.251224 -497.504375) (xy 66.223617 -497.43377) (xy 66.203671 -497.360629) (xy 66.191612 -497.285784)
			(xy 66.187577 -497.21008) (xy 65.071498 -497.21008) (xy 65.070994 -497.247986) (xy 65.062935 -497.323367)
			(xy 65.04691 -497.397465) (xy 65.0231 -497.46944) (xy 64.991774 -497.538476) (xy 64.953287 -497.603791)
			(xy 64.908076 -497.664646) (xy 64.856652 -497.72035) (xy 64.799599 -497.770272) (xy 64.737563 -497.813847)
			(xy 64.671246 -497.850582) (xy 64.6014 -497.880059) (xy 64.528817 -497.901945) (xy 64.454319 -497.915992)
			(xy 64.378749 -497.922041) (xy 64.302965 -497.920022) (xy 64.227825 -497.90996) (xy 64.15418 -497.891968)
			(xy 64.082864 -497.86625) (xy 64.014687 -497.833098) (xy 63.950419 -497.792886) (xy 63.89079 -497.746071)
			(xy 63.836474 -497.693183) (xy 63.788088 -497.634821) (xy 63.74618 -497.571646) (xy 63.711224 -497.504375)
			(xy 63.683617 -497.43377) (xy 63.663671 -497.360629) (xy 63.651612 -497.285784) (xy 63.647577 -497.21008)
			(xy 42.500813 -497.21008) (xy 42.479042 -497.226857) (xy 42.381609 -497.291665) (xy 42.279905 -497.34954)
			(xy 42.174422 -497.400202) (xy 42.065671 -497.443404) (xy 41.954179 -497.478939) (xy 41.840485 -497.506634)
			(xy 41.725141 -497.526354) (xy 41.608704 -497.538005) (xy 41.491739 -497.54153) (xy 41.374812 -497.536912)
			(xy 41.258489 -497.524173) (xy 41.143334 -497.503375) (xy 41.029905 -497.474618) (xy 40.91875 -497.438042)
			(xy 40.810407 -497.393825) (xy 40.705403 -497.342179) (xy 40.604244 -497.283356) (xy 40.507421 -497.21764)
			(xy 40.415403 -497.145349) (xy 40.328636 -497.066834) (xy 40.247539 -496.982474) (xy 40.172506 -496.892679)
			(xy 40.103899 -496.797883) (xy 40.042051 -496.698544) (xy 39.987262 -496.595145) (xy 39.939796 -496.488186)
			(xy 39.899884 -496.378185) (xy 39.86772 -496.265674) (xy 39.843457 -496.151199) (xy 39.827215 -496.035313)
			(xy 39.819072 -495.918579) (xy 39.818564 -495.86007) (xy 1.525016 -495.86007) (xy 1.525016 -497.072412)
			(xy 4.852416 -497.072412) (xy 6.707632 -497.072412) (xy 6.707632 -497.433362) (xy 29.519874 -497.433362)
			(xy 29.519874 -497.346462) (xy 29.527892 -497.259933) (xy 29.54386 -497.174513) (xy 29.567641 -497.090931)
			(xy 29.599033 -497.009899) (xy 29.637767 -496.93211) (xy 29.683514 -496.858226) (xy 29.735883 -496.788879)
			(xy 29.794427 -496.724659) (xy 29.858647 -496.666115) (xy 29.927994 -496.613746) (xy 30.001878 -496.567999)
			(xy 30.079667 -496.529265) (xy 30.160699 -496.497873) (xy 30.244281 -496.474092) (xy 30.329701 -496.458124)
			(xy 30.41623 -496.450106) (xy 30.50313 -496.450106) (xy 30.589659 -496.458124) (xy 30.675079 -496.474092)
			(xy 30.758661 -496.497873) (xy 30.839693 -496.529265) (xy 30.917482 -496.567999) (xy 30.991366 -496.613746)
			(xy 31.060713 -496.666115) (xy 31.124933 -496.724659) (xy 31.183477 -496.788879) (xy 31.235846 -496.858226)
			(xy 31.281593 -496.93211) (xy 31.320327 -497.009899) (xy 31.351719 -497.090931) (xy 31.3755 -497.174513)
			(xy 31.391468 -497.259933) (xy 31.399486 -497.346462) (xy 31.399988 -497.389912) (xy 31.399486 -497.433362)
			(xy 34.599874 -497.433362) (xy 34.599874 -497.346462) (xy 34.607892 -497.259933) (xy 34.62386 -497.174513)
			(xy 34.647641 -497.090931) (xy 34.679033 -497.009899) (xy 34.717767 -496.93211) (xy 34.763514 -496.858226)
			(xy 34.815883 -496.788879) (xy 34.874427 -496.724659) (xy 34.938647 -496.666115) (xy 35.007994 -496.613746)
			(xy 35.081878 -496.567999) (xy 35.159667 -496.529265) (xy 35.240699 -496.497873) (xy 35.324281 -496.474092)
			(xy 35.409701 -496.458124) (xy 35.49623 -496.450106) (xy 35.58313 -496.450106) (xy 35.669659 -496.458124)
			(xy 35.755079 -496.474092) (xy 35.838661 -496.497873) (xy 35.919693 -496.529265) (xy 35.997482 -496.567999)
			(xy 36.071366 -496.613746) (xy 36.140713 -496.666115) (xy 36.204933 -496.724659) (xy 36.263477 -496.788879)
			(xy 36.315846 -496.858226) (xy 36.361593 -496.93211) (xy 36.400327 -497.009899) (xy 36.431719 -497.090931)
			(xy 36.4555 -497.174513) (xy 36.471468 -497.259933) (xy 36.479486 -497.346462) (xy 36.479988 -497.389912)
			(xy 36.479486 -497.433362) (xy 36.471468 -497.519891) (xy 36.4555 -497.605311) (xy 36.431719 -497.688893)
			(xy 36.400327 -497.769925) (xy 36.361593 -497.847714) (xy 36.315846 -497.921598) (xy 36.263477 -497.990945)
			(xy 36.204933 -498.055165) (xy 36.140713 -498.113709) (xy 36.071366 -498.166078) (xy 35.997482 -498.211825)
			(xy 35.919693 -498.250559) (xy 35.838661 -498.281951) (xy 35.755079 -498.305732) (xy 35.669659 -498.3217)
			(xy 35.58313 -498.329718) (xy 35.49623 -498.329718) (xy 35.409701 -498.3217) (xy 35.324281 -498.305732)
			(xy 35.240699 -498.281951) (xy 35.159667 -498.250559) (xy 35.081878 -498.211825) (xy 35.007994 -498.166078)
			(xy 34.938647 -498.113709) (xy 34.874427 -498.055165) (xy 34.815883 -497.990945) (xy 34.763514 -497.921598)
			(xy 34.717767 -497.847714) (xy 34.679033 -497.769925) (xy 34.647641 -497.688893) (xy 34.62386 -497.605311)
			(xy 34.607892 -497.519891) (xy 34.599874 -497.433362) (xy 31.399486 -497.433362) (xy 31.391468 -497.519891)
			(xy 31.3755 -497.605311) (xy 31.351719 -497.688893) (xy 31.320327 -497.769925) (xy 31.281593 -497.847714)
			(xy 31.235846 -497.921598) (xy 31.183477 -497.990945) (xy 31.124933 -498.055165) (xy 31.060713 -498.113709)
			(xy 30.991366 -498.166078) (xy 30.917482 -498.211825) (xy 30.839693 -498.250559) (xy 30.758661 -498.281951)
			(xy 30.675079 -498.305732) (xy 30.589659 -498.3217) (xy 30.50313 -498.329718) (xy 30.41623 -498.329718)
			(xy 30.329701 -498.3217) (xy 30.244281 -498.305732) (xy 30.160699 -498.281951) (xy 30.079667 -498.250559)
			(xy 30.001878 -498.211825) (xy 29.927994 -498.166078) (xy 29.858647 -498.113709) (xy 29.794427 -498.055165)
			(xy 29.735883 -497.990945) (xy 29.683514 -497.921598) (xy 29.637767 -497.847714) (xy 29.599033 -497.769925)
			(xy 29.567641 -497.688893) (xy 29.54386 -497.605311) (xy 29.527892 -497.519891) (xy 29.519874 -497.433362)
			(xy 6.707632 -497.433362) (xy 6.707632 -498.92712) (xy 4.852416 -498.92712) (xy 4.852416 -497.072412)
			(xy 1.525016 -497.072412) (xy 1.525016 -500.99976) (xy 6.671831 -500.99976) (xy 6.675786 -500.907923)
			(xy 6.687621 -500.816766) (xy 6.707248 -500.726963) (xy 6.734522 -500.639181) (xy 6.769242 -500.554067)
			(xy 6.81115 -500.472254) (xy 6.859936 -500.394346) (xy 6.915239 -500.320921) (xy 6.976649 -500.252521)
			(xy 7.043711 -500.189654) (xy 7.11593 -500.132784) (xy 7.19277 -500.082333) (xy 7.273663 -500.038674)
			(xy 7.358009 -500.002131) (xy 7.445185 -499.972974) (xy 7.534544 -499.95142) (xy 7.625425 -499.937626)
			(xy 7.717156 -499.931696) (xy 7.809057 -499.933674) (xy 7.900448 -499.943545) (xy 7.990652 -499.961235)
			(xy 8.032867 -499.973362) (xy 29.519874 -499.973362) (xy 29.519874 -499.886462) (xy 29.527892 -499.799933)
			(xy 29.54386 -499.714513) (xy 29.567641 -499.630931) (xy 29.599033 -499.549899) (xy 29.637767 -499.47211)
			(xy 29.683514 -499.398226) (xy 29.735883 -499.328879) (xy 29.794427 -499.264659) (xy 29.858647 -499.206115)
			(xy 29.927994 -499.153746) (xy 30.001878 -499.107999) (xy 30.079667 -499.069265) (xy 30.160699 -499.037873)
			(xy 30.244281 -499.014092) (xy 30.329701 -498.998124) (xy 30.41623 -498.990106) (xy 30.50313 -498.990106)
			(xy 30.589659 -498.998124) (xy 30.675079 -499.014092) (xy 30.758661 -499.037873) (xy 30.839693 -499.069265)
			(xy 30.917482 -499.107999) (xy 30.991366 -499.153746) (xy 31.060713 -499.206115) (xy 31.124933 -499.264659)
			(xy 31.183477 -499.328879) (xy 31.235846 -499.398226) (xy 31.281593 -499.47211) (xy 31.320327 -499.549899)
			(xy 31.351719 -499.630931) (xy 31.3755 -499.714513) (xy 31.391468 -499.799933) (xy 31.399486 -499.886462)
			(xy 31.399988 -499.929912) (xy 31.399486 -499.973362) (xy 34.599874 -499.973362) (xy 34.599874 -499.886462)
			(xy 34.607892 -499.799933) (xy 34.62386 -499.714513) (xy 34.647641 -499.630931) (xy 34.679033 -499.549899)
			(xy 34.717767 -499.47211) (xy 34.763514 -499.398226) (xy 34.815883 -499.328879) (xy 34.874427 -499.264659)
			(xy 34.938647 -499.206115) (xy 35.007994 -499.153746) (xy 35.081878 -499.107999) (xy 35.159667 -499.069265)
			(xy 35.240699 -499.037873) (xy 35.324281 -499.014092) (xy 35.409701 -498.998124) (xy 35.49623 -498.990106)
			(xy 35.58313 -498.990106) (xy 35.669659 -498.998124) (xy 35.755079 -499.014092) (xy 35.838661 -499.037873)
			(xy 35.919693 -499.069265) (xy 35.997482 -499.107999) (xy 36.071366 -499.153746) (xy 36.140713 -499.206115)
			(xy 36.204933 -499.264659) (xy 36.263477 -499.328879) (xy 36.315846 -499.398226) (xy 36.361593 -499.47211)
			(xy 36.400327 -499.549899) (xy 36.431719 -499.630931) (xy 36.4555 -499.714513) (xy 36.471468 -499.799933)
			(xy 36.479486 -499.886462) (xy 36.479988 -499.929912) (xy 36.479486 -499.973362) (xy 36.471468 -500.059891)
			(xy 36.4555 -500.145311) (xy 36.431719 -500.228893) (xy 36.400327 -500.309925) (xy 36.361593 -500.387714)
			(xy 36.315846 -500.461598) (xy 36.263477 -500.530945) (xy 36.204933 -500.595165) (xy 36.140713 -500.653709)
			(xy 36.071366 -500.706078) (xy 35.997482 -500.751825) (xy 35.919693 -500.790559) (xy 35.838661 -500.821951)
			(xy 35.755079 -500.845732) (xy 35.669659 -500.8617) (xy 35.58313 -500.869718) (xy 35.49623 -500.869718)
			(xy 35.409701 -500.8617) (xy 35.324281 -500.845732) (xy 35.240699 -500.821951) (xy 35.159667 -500.790559)
			(xy 35.081878 -500.751825) (xy 35.007994 -500.706078) (xy 34.938647 -500.653709) (xy 34.874427 -500.595165)
			(xy 34.815883 -500.530945) (xy 34.763514 -500.461598) (xy 34.717767 -500.387714) (xy 34.679033 -500.309925)
			(xy 34.647641 -500.228893) (xy 34.62386 -500.145311) (xy 34.607892 -500.059891) (xy 34.599874 -499.973362)
			(xy 31.399486 -499.973362) (xy 31.391468 -500.059891) (xy 31.3755 -500.145311) (xy 31.351719 -500.228893)
			(xy 31.320327 -500.309925) (xy 31.281593 -500.387714) (xy 31.235846 -500.461598) (xy 31.183477 -500.530945)
			(xy 31.124933 -500.595165) (xy 31.060713 -500.653709) (xy 30.991366 -500.706078) (xy 30.917482 -500.751825)
			(xy 30.839693 -500.790559) (xy 30.758661 -500.821951) (xy 30.675079 -500.845732) (xy 30.589659 -500.8617)
			(xy 30.50313 -500.869718) (xy 30.41623 -500.869718) (xy 30.329701 -500.8617) (xy 30.244281 -500.845732)
			(xy 30.160699 -500.821951) (xy 30.079667 -500.790559) (xy 30.001878 -500.751825) (xy 29.927994 -500.706078)
			(xy 29.858647 -500.653709) (xy 29.794427 -500.595165) (xy 29.735883 -500.530945) (xy 29.683514 -500.461598)
			(xy 29.637767 -500.387714) (xy 29.599033 -500.309925) (xy 29.567641 -500.228893) (xy 29.54386 -500.145311)
			(xy 29.527892 -500.059891) (xy 29.519874 -499.973362) (xy 8.032867 -499.973362) (xy 8.079001 -499.986615)
			(xy 8.164841 -500.019495) (xy 8.247537 -500.059633) (xy 8.326477 -500.106732) (xy 8.401075 -500.160442)
			(xy 8.470781 -500.220366) (xy 8.535076 -500.28606) (xy 8.593487 -500.357038) (xy 8.645579 -500.432775)
			(xy 8.690968 -500.51271) (xy 8.729318 -500.59625) (xy 8.760343 -500.682778) (xy 8.783816 -500.771653)
			(xy 8.799562 -500.862217) (xy 8.807464 -500.953799) (xy 8.807958 -500.99976) (xy 8.807464 -501.045721)
			(xy 8.799562 -501.137303) (xy 8.783816 -501.227867) (xy 8.760343 -501.316742) (xy 8.729318 -501.40327)
			(xy 8.690968 -501.48681) (xy 8.645579 -501.566745) (xy 8.593487 -501.642482) (xy 8.535076 -501.71346)
			(xy 8.470781 -501.779154) (xy 8.401075 -501.839078) (xy 8.326477 -501.892788) (xy 8.247537 -501.939887)
			(xy 8.164841 -501.980025) (xy 8.079001 -502.012905) (xy 7.990652 -502.038285) (xy 7.900448 -502.055975)
			(xy 7.809057 -502.065846) (xy 7.717156 -502.067824) (xy 7.625425 -502.061894) (xy 7.534544 -502.0481)
			(xy 7.445185 -502.026546) (xy 7.358009 -501.997389) (xy 7.273663 -501.960846) (xy 7.19277 -501.917187)
			(xy 7.11593 -501.866736) (xy 7.043711 -501.809866) (xy 6.976649 -501.746999) (xy 6.915239 -501.678599)
			(xy 6.859936 -501.605174) (xy 6.81115 -501.527266) (xy 6.769242 -501.445453) (xy 6.734522 -501.360339)
			(xy 6.707248 -501.272557) (xy 6.687621 -501.182754) (xy 6.675786 -501.091597) (xy 6.671831 -500.99976)
			(xy 1.525016 -500.99976) (xy 1.525016 -502.513362) (xy 29.519874 -502.513362) (xy 29.519874 -502.426462)
			(xy 29.527892 -502.339933) (xy 29.54386 -502.254513) (xy 29.567641 -502.170931) (xy 29.599033 -502.089899)
			(xy 29.637767 -502.01211) (xy 29.683514 -501.938226) (xy 29.735883 -501.868879) (xy 29.794427 -501.804659)
			(xy 29.858647 -501.746115) (xy 29.927994 -501.693746) (xy 30.001878 -501.647999) (xy 30.079667 -501.609265)
			(xy 30.160699 -501.577873) (xy 30.244281 -501.554092) (xy 30.329701 -501.538124) (xy 30.41623 -501.530106)
			(xy 30.50313 -501.530106) (xy 30.589659 -501.538124) (xy 30.675079 -501.554092) (xy 30.758661 -501.577873)
			(xy 30.839693 -501.609265) (xy 30.917482 -501.647999) (xy 30.991366 -501.693746) (xy 31.060713 -501.746115)
			(xy 31.124933 -501.804659) (xy 31.183477 -501.868879) (xy 31.235846 -501.938226) (xy 31.281593 -502.01211)
			(xy 31.320327 -502.089899) (xy 31.351719 -502.170931) (xy 31.3755 -502.254513) (xy 31.391468 -502.339933)
			(xy 31.399486 -502.426462) (xy 31.399988 -502.469912) (xy 31.399486 -502.513362) (xy 34.599874 -502.513362)
			(xy 34.599874 -502.426462) (xy 34.607892 -502.339933) (xy 34.62386 -502.254513) (xy 34.647641 -502.170931)
			(xy 34.679033 -502.089899) (xy 34.717767 -502.01211) (xy 34.763514 -501.938226) (xy 34.815883 -501.868879)
			(xy 34.874427 -501.804659) (xy 34.938647 -501.746115) (xy 35.007994 -501.693746) (xy 35.081878 -501.647999)
			(xy 35.159667 -501.609265) (xy 35.240699 -501.577873) (xy 35.324281 -501.554092) (xy 35.409701 -501.538124)
			(xy 35.49623 -501.530106) (xy 35.58313 -501.530106) (xy 35.669659 -501.538124) (xy 35.755079 -501.554092)
			(xy 35.838661 -501.577873) (xy 35.919693 -501.609265) (xy 35.997482 -501.647999) (xy 36.071366 -501.693746)
			(xy 36.140713 -501.746115) (xy 36.204933 -501.804659) (xy 36.263477 -501.868879) (xy 36.315846 -501.938226)
			(xy 36.361593 -502.01211) (xy 36.400327 -502.089899) (xy 36.431719 -502.170931) (xy 36.4555 -502.254513)
			(xy 36.471468 -502.339933) (xy 36.479486 -502.426462) (xy 36.479988 -502.469912) (xy 36.479486 -502.513362)
			(xy 36.471468 -502.599891) (xy 36.4555 -502.685311) (xy 36.431719 -502.768893) (xy 36.400327 -502.849925)
			(xy 36.361593 -502.927714) (xy 36.315846 -503.001598) (xy 36.263477 -503.070945) (xy 36.204933 -503.135165)
			(xy 36.140713 -503.193709) (xy 36.071366 -503.246078) (xy 35.997482 -503.291825) (xy 35.919693 -503.330559)
			(xy 35.838661 -503.361951) (xy 35.755079 -503.385732) (xy 35.669659 -503.4017) (xy 35.58313 -503.409718)
			(xy 35.49623 -503.409718) (xy 35.409701 -503.4017) (xy 35.324281 -503.385732) (xy 35.240699 -503.361951)
			(xy 35.159667 -503.330559) (xy 35.081878 -503.291825) (xy 35.007994 -503.246078) (xy 34.938647 -503.193709)
			(xy 34.874427 -503.135165) (xy 34.815883 -503.070945) (xy 34.763514 -503.001598) (xy 34.717767 -502.927714)
			(xy 34.679033 -502.849925) (xy 34.647641 -502.768893) (xy 34.62386 -502.685311) (xy 34.607892 -502.599891)
			(xy 34.599874 -502.513362) (xy 31.399486 -502.513362) (xy 31.391468 -502.599891) (xy 31.3755 -502.685311)
			(xy 31.351719 -502.768893) (xy 31.320327 -502.849925) (xy 31.281593 -502.927714) (xy 31.235846 -503.001598)
			(xy 31.183477 -503.070945) (xy 31.124933 -503.135165) (xy 31.060713 -503.193709) (xy 30.991366 -503.246078)
			(xy 30.917482 -503.291825) (xy 30.839693 -503.330559) (xy 30.758661 -503.361951) (xy 30.675079 -503.385732)
			(xy 30.589659 -503.4017) (xy 30.50313 -503.409718) (xy 30.41623 -503.409718) (xy 30.329701 -503.4017)
			(xy 30.244281 -503.385732) (xy 30.160699 -503.361951) (xy 30.079667 -503.330559) (xy 30.001878 -503.291825)
			(xy 29.927994 -503.246078) (xy 29.858647 -503.193709) (xy 29.794427 -503.135165) (xy 29.735883 -503.070945)
			(xy 29.683514 -503.001598) (xy 29.637767 -502.927714) (xy 29.599033 -502.849925) (xy 29.567641 -502.768893)
			(xy 29.54386 -502.685311) (xy 29.527892 -502.599891) (xy 29.519874 -502.513362) (xy 1.525016 -502.513362)
			(xy 1.525016 -505.053362) (xy 29.519874 -505.053362) (xy 29.519874 -504.966462) (xy 29.527892 -504.879933)
			(xy 29.54386 -504.794513) (xy 29.567641 -504.710931) (xy 29.599033 -504.629899) (xy 29.637767 -504.55211)
			(xy 29.683514 -504.478226) (xy 29.735883 -504.408879) (xy 29.794427 -504.344659) (xy 29.858647 -504.286115)
			(xy 29.927994 -504.233746) (xy 30.001878 -504.187999) (xy 30.079667 -504.149265) (xy 30.160699 -504.117873)
			(xy 30.244281 -504.094092) (xy 30.329701 -504.078124) (xy 30.41623 -504.070106) (xy 30.50313 -504.070106)
			(xy 30.589659 -504.078124) (xy 30.675079 -504.094092) (xy 30.758661 -504.117873) (xy 30.839693 -504.149265)
			(xy 30.917482 -504.187999) (xy 30.991366 -504.233746) (xy 31.060713 -504.286115) (xy 31.124933 -504.344659)
			(xy 31.183477 -504.408879) (xy 31.235846 -504.478226) (xy 31.281593 -504.55211) (xy 31.320327 -504.629899)
			(xy 31.351719 -504.710931) (xy 31.3755 -504.794513) (xy 31.391468 -504.879933) (xy 31.399486 -504.966462)
			(xy 31.399988 -505.009912) (xy 31.399486 -505.053362) (xy 34.599874 -505.053362) (xy 34.599874 -504.966462)
			(xy 34.607892 -504.879933) (xy 34.62386 -504.794513) (xy 34.647641 -504.710931) (xy 34.679033 -504.629899)
			(xy 34.717767 -504.55211) (xy 34.763514 -504.478226) (xy 34.815883 -504.408879) (xy 34.874427 -504.344659)
			(xy 34.938647 -504.286115) (xy 35.007994 -504.233746) (xy 35.081878 -504.187999) (xy 35.159667 -504.149265)
			(xy 35.240699 -504.117873) (xy 35.324281 -504.094092) (xy 35.409701 -504.078124) (xy 35.49623 -504.070106)
			(xy 35.58313 -504.070106) (xy 35.669659 -504.078124) (xy 35.755079 -504.094092) (xy 35.838661 -504.117873)
			(xy 35.919693 -504.149265) (xy 35.997482 -504.187999) (xy 36.071366 -504.233746) (xy 36.140713 -504.286115)
			(xy 36.204933 -504.344659) (xy 36.263477 -504.408879) (xy 36.315846 -504.478226) (xy 36.361593 -504.55211)
			(xy 36.400327 -504.629899) (xy 36.431719 -504.710931) (xy 36.4555 -504.794513) (xy 36.471468 -504.879933)
			(xy 36.479486 -504.966462) (xy 36.479988 -505.009912) (xy 36.479486 -505.053362) (xy 36.471468 -505.139891)
			(xy 36.4555 -505.225311) (xy 36.431719 -505.308893) (xy 36.400327 -505.389925) (xy 36.361593 -505.467714)
			(xy 36.315846 -505.541598) (xy 36.263477 -505.610945) (xy 36.204933 -505.675165) (xy 36.140713 -505.733709)
			(xy 36.071366 -505.786078) (xy 35.997482 -505.831825) (xy 35.919693 -505.870559) (xy 35.838661 -505.901951)
			(xy 35.755079 -505.925732) (xy 35.669659 -505.9417) (xy 35.58313 -505.949718) (xy 35.49623 -505.949718)
			(xy 35.409701 -505.9417) (xy 35.324281 -505.925732) (xy 35.240699 -505.901951) (xy 35.159667 -505.870559)
			(xy 35.081878 -505.831825) (xy 35.007994 -505.786078) (xy 34.938647 -505.733709) (xy 34.874427 -505.675165)
			(xy 34.815883 -505.610945) (xy 34.763514 -505.541598) (xy 34.717767 -505.467714) (xy 34.679033 -505.389925)
			(xy 34.647641 -505.308893) (xy 34.62386 -505.225311) (xy 34.607892 -505.139891) (xy 34.599874 -505.053362)
			(xy 31.399486 -505.053362) (xy 31.391468 -505.139891) (xy 31.3755 -505.225311) (xy 31.351719 -505.308893)
			(xy 31.320327 -505.389925) (xy 31.281593 -505.467714) (xy 31.235846 -505.541598) (xy 31.183477 -505.610945)
			(xy 31.124933 -505.675165) (xy 31.060713 -505.733709) (xy 30.991366 -505.786078) (xy 30.917482 -505.831825)
			(xy 30.839693 -505.870559) (xy 30.758661 -505.901951) (xy 30.675079 -505.925732) (xy 30.589659 -505.9417)
			(xy 30.50313 -505.949718) (xy 30.41623 -505.949718) (xy 30.329701 -505.9417) (xy 30.244281 -505.925732)
			(xy 30.160699 -505.901951) (xy 30.079667 -505.870559) (xy 30.001878 -505.831825) (xy 29.927994 -505.786078)
			(xy 29.858647 -505.733709) (xy 29.794427 -505.675165) (xy 29.735883 -505.610945) (xy 29.683514 -505.541598)
			(xy 29.637767 -505.467714) (xy 29.599033 -505.389925) (xy 29.567641 -505.308893) (xy 29.54386 -505.225311)
			(xy 29.527892 -505.139891) (xy 29.519874 -505.053362) (xy 1.525016 -505.053362) (xy 1.525016 -507.593362)
			(xy 29.519874 -507.593362) (xy 29.519874 -507.506462) (xy 29.527892 -507.419933) (xy 29.54386 -507.334513)
			(xy 29.567641 -507.250931) (xy 29.599033 -507.169899) (xy 29.637767 -507.09211) (xy 29.683514 -507.018226)
			(xy 29.735883 -506.948879) (xy 29.794427 -506.884659) (xy 29.858647 -506.826115) (xy 29.927994 -506.773746)
			(xy 30.001878 -506.727999) (xy 30.079667 -506.689265) (xy 30.160699 -506.657873) (xy 30.244281 -506.634092)
			(xy 30.329701 -506.618124) (xy 30.41623 -506.610106) (xy 30.50313 -506.610106) (xy 30.589659 -506.618124)
			(xy 30.675079 -506.634092) (xy 30.758661 -506.657873) (xy 30.839693 -506.689265) (xy 30.917482 -506.727999)
			(xy 30.991366 -506.773746) (xy 31.060713 -506.826115) (xy 31.124933 -506.884659) (xy 31.183477 -506.948879)
			(xy 31.235846 -507.018226) (xy 31.281593 -507.09211) (xy 31.320327 -507.169899) (xy 31.351719 -507.250931)
			(xy 31.3755 -507.334513) (xy 31.391468 -507.419933) (xy 31.399486 -507.506462) (xy 31.399988 -507.549912)
			(xy 31.399486 -507.593362) (xy 34.599874 -507.593362) (xy 34.599874 -507.506462) (xy 34.607892 -507.419933)
			(xy 34.62386 -507.334513) (xy 34.647641 -507.250931) (xy 34.679033 -507.169899) (xy 34.717767 -507.09211)
			(xy 34.763514 -507.018226) (xy 34.815883 -506.948879) (xy 34.874427 -506.884659) (xy 34.938647 -506.826115)
			(xy 35.007994 -506.773746) (xy 35.081878 -506.727999) (xy 35.159667 -506.689265) (xy 35.240699 -506.657873)
			(xy 35.324281 -506.634092) (xy 35.409701 -506.618124) (xy 35.49623 -506.610106) (xy 35.58313 -506.610106)
			(xy 35.669659 -506.618124) (xy 35.755079 -506.634092) (xy 35.838661 -506.657873) (xy 35.919693 -506.689265)
			(xy 35.997482 -506.727999) (xy 36.071366 -506.773746) (xy 36.140713 -506.826115) (xy 36.168463 -506.851412)
			(xy 51.474116 -506.851412) (xy 53.125624 -506.851412) (xy 53.125624 -508.503428) (xy 51.474116 -508.503428)
			(xy 51.474116 -506.851412) (xy 36.168463 -506.851412) (xy 36.204933 -506.884659) (xy 36.263477 -506.948879)
			(xy 36.315846 -507.018226) (xy 36.361593 -507.09211) (xy 36.400327 -507.169899) (xy 36.431719 -507.250931)
			(xy 36.4555 -507.334513) (xy 36.471468 -507.419933) (xy 36.479486 -507.506462) (xy 36.479988 -507.549912)
			(xy 36.479486 -507.593362) (xy 36.471468 -507.679891) (xy 36.464349 -507.717975) (xy 47.97424 -507.717975)
			(xy 47.97424 -507.636865) (xy 47.98219 -507.556146) (xy 47.998013 -507.476595) (xy 48.021558 -507.398979)
			(xy 48.052597 -507.324043) (xy 48.090832 -507.252511) (xy 48.135894 -507.185071) (xy 48.187349 -507.122372)
			(xy 48.244702 -507.065019) (xy 48.307401 -507.013564) (xy 48.374841 -506.968502) (xy 48.446373 -506.930267)
			(xy 48.521309 -506.899228) (xy 48.598925 -506.875683) (xy 48.678476 -506.85986) (xy 48.759195 -506.85191)
			(xy 48.840305 -506.85191) (xy 48.921024 -506.85986) (xy 49.000575 -506.875683) (xy 49.078191 -506.899228)
			(xy 49.153127 -506.930267) (xy 49.224659 -506.968502) (xy 49.292099 -507.013564) (xy 49.354798 -507.065019)
			(xy 49.412151 -507.122372) (xy 49.463606 -507.185071) (xy 49.508668 -507.252511) (xy 49.546903 -507.324043)
			(xy 49.577942 -507.398979) (xy 49.601487 -507.476595) (xy 49.61731 -507.556146) (xy 49.62526 -507.636865)
			(xy 49.625758 -507.67742) (xy 49.62526 -507.717975) (xy 49.61731 -507.798694) (xy 49.601487 -507.878245)
			(xy 49.577942 -507.955861) (xy 49.546903 -508.030797) (xy 49.508668 -508.102329) (xy 49.463606 -508.169769)
			(xy 49.412151 -508.232468) (xy 49.354798 -508.289821) (xy 49.292099 -508.341276) (xy 49.224659 -508.386338)
			(xy 49.153127 -508.424573) (xy 49.078191 -508.455612) (xy 49.000575 -508.479157) (xy 48.921024 -508.49498)
			(xy 48.840305 -508.50293) (xy 48.759195 -508.50293) (xy 48.678476 -508.49498) (xy 48.598925 -508.479157)
			(xy 48.521309 -508.455612) (xy 48.446373 -508.424573) (xy 48.374841 -508.386338) (xy 48.307401 -508.341276)
			(xy 48.244702 -508.289821) (xy 48.187349 -508.232468) (xy 48.135894 -508.169769) (xy 48.090832 -508.102329)
			(xy 48.052597 -508.030797) (xy 48.021558 -507.955861) (xy 47.998013 -507.878245) (xy 47.98219 -507.798694)
			(xy 47.97424 -507.717975) (xy 36.464349 -507.717975) (xy 36.4555 -507.765311) (xy 36.431719 -507.848893)
			(xy 36.400327 -507.929925) (xy 36.361593 -508.007714) (xy 36.315846 -508.081598) (xy 36.263477 -508.150945)
			(xy 36.204933 -508.215165) (xy 36.140713 -508.273709) (xy 36.071366 -508.326078) (xy 35.997482 -508.371825)
			(xy 35.919693 -508.410559) (xy 35.838661 -508.441951) (xy 35.755079 -508.465732) (xy 35.669659 -508.4817)
			(xy 35.58313 -508.489718) (xy 35.49623 -508.489718) (xy 35.409701 -508.4817) (xy 35.324281 -508.465732)
			(xy 35.240699 -508.441951) (xy 35.159667 -508.410559) (xy 35.081878 -508.371825) (xy 35.007994 -508.326078)
			(xy 34.938647 -508.273709) (xy 34.874427 -508.215165) (xy 34.815883 -508.150945) (xy 34.763514 -508.081598)
			(xy 34.717767 -508.007714) (xy 34.679033 -507.929925) (xy 34.647641 -507.848893) (xy 34.62386 -507.765311)
			(xy 34.607892 -507.679891) (xy 34.599874 -507.593362) (xy 31.399486 -507.593362) (xy 31.391468 -507.679891)
			(xy 31.3755 -507.765311) (xy 31.351719 -507.848893) (xy 31.320327 -507.929925) (xy 31.281593 -508.007714)
			(xy 31.235846 -508.081598) (xy 31.183477 -508.150945) (xy 31.124933 -508.215165) (xy 31.060713 -508.273709)
			(xy 30.991366 -508.326078) (xy 30.917482 -508.371825) (xy 30.839693 -508.410559) (xy 30.758661 -508.441951)
			(xy 30.675079 -508.465732) (xy 30.589659 -508.4817) (xy 30.50313 -508.489718) (xy 30.41623 -508.489718)
			(xy 30.329701 -508.4817) (xy 30.244281 -508.465732) (xy 30.160699 -508.441951) (xy 30.079667 -508.410559)
			(xy 30.001878 -508.371825) (xy 29.927994 -508.326078) (xy 29.858647 -508.273709) (xy 29.794427 -508.215165)
			(xy 29.735883 -508.150945) (xy 29.683514 -508.081598) (xy 29.637767 -508.007714) (xy 29.599033 -507.929925)
			(xy 29.567641 -507.848893) (xy 29.54386 -507.765311) (xy 29.527892 -507.679891) (xy 29.519874 -507.593362)
			(xy 1.525016 -507.593362) (xy 1.525016 -508.96012) (xy 86.39887 -508.96012) (xy 86.402874 -508.760022)
			(xy 86.414881 -508.560244) (xy 86.434872 -508.361107) (xy 86.462814 -508.162929) (xy 86.498662 -507.966027)
			(xy 86.54236 -507.770718) (xy 86.593837 -507.577313) (xy 86.653011 -507.386123) (xy 86.719787 -507.197453)
			(xy 86.794059 -507.011606) (xy 86.875706 -506.828879) (xy 86.964599 -506.649566) (xy 87.060595 -506.473952)
			(xy 87.16354 -506.30232) (xy 87.27327 -506.134944) (xy 87.389608 -505.972093) (xy 87.512369 -505.814026)
			(xy 87.641356 -505.660998) (xy 87.776363 -505.513253) (xy 87.917172 -505.371027) (xy 88.063559 -505.23455)
			(xy 88.215289 -505.104038) (xy 88.37212 -504.979702) (xy 88.533799 -504.86174) (xy 88.700069 -504.750341)
			(xy 88.870662 -504.645684) (xy 89.045306 -504.547936) (xy 89.223722 -504.457253) (xy 89.405622 -504.373782)
			(xy 89.590717 -504.297655) (xy 89.778709 -504.228995) (xy 89.969298 -504.167911) (xy 90.162178 -504.114501)
			(xy 90.35704 -504.068852) (xy 90.553573 -504.031035) (xy 90.751462 -504.001111) (xy 90.950389 -503.979129)
			(xy 91.150037 -503.965124) (xy 91.350085 -503.959118) (xy 91.550213 -503.96112) (xy 91.750101 -503.971128)
			(xy 91.949428 -503.989125) (xy 92.147876 -504.015083) (xy 92.345126 -504.04896) (xy 92.540863 -504.090702)
			(xy 92.734773 -504.140241) (xy 92.926546 -504.197499) (xy 93.115875 -504.262384) (xy 93.302455 -504.334792)
			(xy 93.48599 -504.414608) (xy 93.666184 -504.501702) (xy 93.842749 -504.595936) (xy 94.015402 -504.697159)
			(xy 94.183867 -504.805209) (xy 94.347875 -504.919912) (xy 94.507162 -505.041086) (xy 94.661473 -505.168535)
			(xy 94.810561 -505.302056) (xy 94.954188 -505.441436) (xy 95.092124 -505.58645) (xy 95.224147 -505.736867)
			(xy 95.350046 -505.892445) (xy 95.46962 -506.052937) (xy 95.582676 -506.218083) (xy 95.689035 -506.387621)
			(xy 95.788526 -506.561279) (xy 95.880989 -506.738778) (xy 95.966276 -506.919834) (xy 96.044251 -507.104158)
			(xy 96.114788 -507.291454) (xy 96.177776 -507.481422) (xy 96.233113 -507.673758) (xy 96.28071 -507.868154)
			(xy 96.320491 -508.064299) (xy 96.352393 -508.261878) (xy 96.376364 -508.460575) (xy 96.392366 -508.660073)
			(xy 96.400373 -508.860051) (xy 96.400874 -508.96012) (xy 96.400373 -509.060189) (xy 96.392366 -509.260167)
			(xy 96.376364 -509.459665) (xy 96.352393 -509.658362) (xy 96.320491 -509.855941) (xy 96.28071 -510.052086)
			(xy 96.233113 -510.246482) (xy 96.177776 -510.438818) (xy 96.114788 -510.628786) (xy 96.044251 -510.816082)
			(xy 95.966276 -511.000406) (xy 95.880989 -511.181462) (xy 95.788526 -511.358961) (xy 95.689035 -511.532619)
			(xy 95.582676 -511.702157) (xy 95.46962 -511.867303) (xy 95.350046 -512.027795) (xy 95.224147 -512.183373)
			(xy 95.092124 -512.33379) (xy 94.954188 -512.478804) (xy 94.810561 -512.618184) (xy 94.661473 -512.751705)
			(xy 94.507162 -512.879154) (xy 94.347875 -513.000328) (xy 94.183867 -513.115031) (xy 94.015402 -513.223081)
			(xy 93.842749 -513.324304) (xy 93.666184 -513.418538) (xy 93.48599 -513.505632) (xy 93.302455 -513.585448)
			(xy 93.115875 -513.657856) (xy 92.926546 -513.722741) (xy 92.734773 -513.779999) (xy 92.540863 -513.829538)
			(xy 92.345126 -513.87128) (xy 92.147876 -513.905157) (xy 91.949428 -513.931115) (xy 91.750101 -513.949112)
			(xy 91.550213 -513.95912) (xy 91.350085 -513.961122) (xy 91.150037 -513.955116) (xy 90.950389 -513.941111)
			(xy 90.751462 -513.919129) (xy 90.553573 -513.889205) (xy 90.35704 -513.851388) (xy 90.162178 -513.805739)
			(xy 89.969298 -513.752329) (xy 89.778709 -513.691245) (xy 89.590717 -513.622585) (xy 89.405622 -513.546458)
			(xy 89.223722 -513.462987) (xy 89.045306 -513.372304) (xy 88.870662 -513.274556) (xy 88.700069 -513.169899)
			(xy 88.533799 -513.0585) (xy 88.37212 -512.940538) (xy 88.215289 -512.816202) (xy 88.063559 -512.68569)
			(xy 87.917172 -512.549213) (xy 87.776363 -512.406987) (xy 87.641356 -512.259242) (xy 87.512369 -512.106214)
			(xy 87.389608 -511.948147) (xy 87.27327 -511.785296) (xy 87.16354 -511.61792) (xy 87.060595 -511.446288)
			(xy 86.964599 -511.270674) (xy 86.875706 -511.091361) (xy 86.794059 -510.908634) (xy 86.719787 -510.722787)
			(xy 86.653011 -510.534117) (xy 86.593837 -510.342927) (xy 86.54236 -510.149522) (xy 86.498662 -509.954213)
			(xy 86.462814 -509.757311) (xy 86.434872 -509.559133) (xy 86.414881 -509.359996) (xy 86.402874 -509.160218)
			(xy 86.39887 -508.96012) (xy 1.525016 -508.96012) (xy 1.525016 -511.049778) (xy 6.671831 -511.049778)
			(xy 6.675786 -510.957941) (xy 6.687621 -510.866784) (xy 6.707248 -510.776981) (xy 6.734522 -510.689199)
			(xy 6.769242 -510.604085) (xy 6.81115 -510.522272) (xy 6.859936 -510.444364) (xy 6.915239 -510.370939)
			(xy 6.976649 -510.302539) (xy 7.043711 -510.239672) (xy 7.11593 -510.182802) (xy 7.19277 -510.132351)
			(xy 7.273663 -510.088692) (xy 7.358009 -510.052149) (xy 7.445185 -510.022992) (xy 7.534544 -510.001438)
			(xy 7.625425 -509.987644) (xy 7.717156 -509.981714) (xy 7.809057 -509.983692) (xy 7.900448 -509.993563)
			(xy 7.990652 -510.011253) (xy 8.079001 -510.036633) (xy 8.164841 -510.069513) (xy 8.247537 -510.109651)
			(xy 8.287278 -510.133362) (xy 29.519874 -510.133362) (xy 29.519874 -510.046462) (xy 29.527892 -509.959933)
			(xy 29.54386 -509.874513) (xy 29.567641 -509.790931) (xy 29.599033 -509.709899) (xy 29.637767 -509.63211)
			(xy 29.683514 -509.558226) (xy 29.735883 -509.488879) (xy 29.794427 -509.424659) (xy 29.858647 -509.366115)
			(xy 29.927994 -509.313746) (xy 30.001878 -509.267999) (xy 30.079667 -509.229265) (xy 30.160699 -509.197873)
			(xy 30.244281 -509.174092) (xy 30.329701 -509.158124) (xy 30.41623 -509.150106) (xy 30.50313 -509.150106)
			(xy 30.589659 -509.158124) (xy 30.675079 -509.174092) (xy 30.758661 -509.197873) (xy 30.839693 -509.229265)
			(xy 30.917482 -509.267999) (xy 30.991366 -509.313746) (xy 31.060713 -509.366115) (xy 31.124933 -509.424659)
			(xy 31.183477 -509.488879) (xy 31.235846 -509.558226) (xy 31.281593 -509.63211) (xy 31.320327 -509.709899)
			(xy 31.351719 -509.790931) (xy 31.3755 -509.874513) (xy 31.391468 -509.959933) (xy 31.399486 -510.046462)
			(xy 31.399988 -510.089912) (xy 31.399486 -510.133362) (xy 34.599874 -510.133362) (xy 34.599874 -510.046462)
			(xy 34.607892 -509.959933) (xy 34.62386 -509.874513) (xy 34.647641 -509.790931) (xy 34.679033 -509.709899)
			(xy 34.717767 -509.63211) (xy 34.763514 -509.558226) (xy 34.815883 -509.488879) (xy 34.874427 -509.424659)
			(xy 34.938647 -509.366115) (xy 35.007994 -509.313746) (xy 35.081878 -509.267999) (xy 35.159667 -509.229265)
			(xy 35.240699 -509.197873) (xy 35.324281 -509.174092) (xy 35.409701 -509.158124) (xy 35.49623 -509.150106)
			(xy 35.58313 -509.150106) (xy 35.669659 -509.158124) (xy 35.755079 -509.174092) (xy 35.838661 -509.197873)
			(xy 35.919693 -509.229265) (xy 35.997482 -509.267999) (xy 36.071366 -509.313746) (xy 36.140713 -509.366115)
			(xy 36.204933 -509.424659) (xy 36.263477 -509.488879) (xy 36.315846 -509.558226) (xy 36.361593 -509.63211)
			(xy 36.400327 -509.709899) (xy 36.431719 -509.790931) (xy 36.4555 -509.874513) (xy 36.471468 -509.959933)
			(xy 36.479486 -510.046462) (xy 36.479988 -510.089912) (xy 36.479486 -510.133362) (xy 36.471468 -510.219891)
			(xy 36.4555 -510.305311) (xy 36.431719 -510.388893) (xy 36.400327 -510.469925) (xy 36.361593 -510.547714)
			(xy 36.315846 -510.621598) (xy 36.263477 -510.690945) (xy 36.204933 -510.755165) (xy 36.140713 -510.813709)
			(xy 36.071366 -510.866078) (xy 35.997482 -510.911825) (xy 35.919693 -510.950559) (xy 35.838661 -510.981951)
			(xy 35.755079 -511.005732) (xy 35.669659 -511.0217) (xy 35.58313 -511.029718) (xy 35.49623 -511.029718)
			(xy 35.409701 -511.0217) (xy 35.324281 -511.005732) (xy 35.240699 -510.981951) (xy 35.159667 -510.950559)
			(xy 35.081878 -510.911825) (xy 35.007994 -510.866078) (xy 34.938647 -510.813709) (xy 34.874427 -510.755165)
			(xy 34.815883 -510.690945) (xy 34.763514 -510.621598) (xy 34.717767 -510.547714) (xy 34.679033 -510.469925)
			(xy 34.647641 -510.388893) (xy 34.62386 -510.305311) (xy 34.607892 -510.219891) (xy 34.599874 -510.133362)
			(xy 31.399486 -510.133362) (xy 31.391468 -510.219891) (xy 31.3755 -510.305311) (xy 31.351719 -510.388893)
			(xy 31.320327 -510.469925) (xy 31.281593 -510.547714) (xy 31.235846 -510.621598) (xy 31.183477 -510.690945)
			(xy 31.124933 -510.755165) (xy 31.060713 -510.813709) (xy 30.991366 -510.866078) (xy 30.917482 -510.911825)
			(xy 30.839693 -510.950559) (xy 30.758661 -510.981951) (xy 30.675079 -511.005732) (xy 30.589659 -511.0217)
			(xy 30.50313 -511.029718) (xy 30.41623 -511.029718) (xy 30.329701 -511.0217) (xy 30.244281 -511.005732)
			(xy 30.160699 -510.981951) (xy 30.079667 -510.950559) (xy 30.001878 -510.911825) (xy 29.927994 -510.866078)
			(xy 29.858647 -510.813709) (xy 29.794427 -510.755165) (xy 29.735883 -510.690945) (xy 29.683514 -510.621598)
			(xy 29.637767 -510.547714) (xy 29.599033 -510.469925) (xy 29.567641 -510.388893) (xy 29.54386 -510.305311)
			(xy 29.527892 -510.219891) (xy 29.519874 -510.133362) (xy 8.287278 -510.133362) (xy 8.326477 -510.15675)
			(xy 8.401075 -510.21046) (xy 8.470781 -510.270384) (xy 8.535076 -510.336078) (xy 8.593487 -510.407056)
			(xy 8.645579 -510.482793) (xy 8.690968 -510.562728) (xy 8.729318 -510.646268) (xy 8.760343 -510.732796)
			(xy 8.783816 -510.821671) (xy 8.799562 -510.912235) (xy 8.807464 -511.003817) (xy 8.807958 -511.049778)
			(xy 8.807464 -511.095739) (xy 8.799562 -511.187321) (xy 8.783816 -511.277885) (xy 8.760343 -511.36676)
			(xy 8.729318 -511.453288) (xy 8.690968 -511.536828) (xy 8.645579 -511.616763) (xy 8.593487 -511.6925)
			(xy 8.535076 -511.763478) (xy 8.470781 -511.829172) (xy 8.401075 -511.889096) (xy 8.326477 -511.942806)
			(xy 8.247537 -511.989905) (xy 8.164841 -512.030043) (xy 8.079001 -512.062923) (xy 7.990652 -512.088303)
			(xy 7.900448 -512.105993) (xy 7.809057 -512.115864) (xy 7.717156 -512.117842) (xy 7.625425 -512.111912)
			(xy 7.534544 -512.098118) (xy 7.445185 -512.076564) (xy 7.358009 -512.047407) (xy 7.273663 -512.010864)
			(xy 7.19277 -511.967205) (xy 7.11593 -511.916754) (xy 7.043711 -511.859884) (xy 6.976649 -511.797017)
			(xy 6.915239 -511.728617) (xy 6.859936 -511.655192) (xy 6.81115 -511.577284) (xy 6.769242 -511.495471)
			(xy 6.734522 -511.410357) (xy 6.707248 -511.322575) (xy 6.687621 -511.232772) (xy 6.675786 -511.141615)
			(xy 6.671831 -511.049778) (xy 1.525016 -511.049778) (xy 1.525016 -512.673362) (xy 29.519874 -512.673362)
			(xy 29.519874 -512.586462) (xy 29.527892 -512.499933) (xy 29.54386 -512.414513) (xy 29.567641 -512.330931)
			(xy 29.599033 -512.249899) (xy 29.637767 -512.17211) (xy 29.683514 -512.098226) (xy 29.735883 -512.028879)
			(xy 29.794427 -511.964659) (xy 29.858647 -511.906115) (xy 29.927994 -511.853746) (xy 30.001878 -511.807999)
			(xy 30.079667 -511.769265) (xy 30.160699 -511.737873) (xy 30.244281 -511.714092) (xy 30.329701 -511.698124)
			(xy 30.41623 -511.690106) (xy 30.50313 -511.690106) (xy 30.589659 -511.698124) (xy 30.675079 -511.714092)
			(xy 30.758661 -511.737873) (xy 30.839693 -511.769265) (xy 30.917482 -511.807999) (xy 30.991366 -511.853746)
			(xy 31.060713 -511.906115) (xy 31.124933 -511.964659) (xy 31.183477 -512.028879) (xy 31.235846 -512.098226)
			(xy 31.281593 -512.17211) (xy 31.320327 -512.249899) (xy 31.351719 -512.330931) (xy 31.3755 -512.414513)
			(xy 31.391468 -512.499933) (xy 31.399486 -512.586462) (xy 31.399988 -512.629912) (xy 31.399486 -512.673362)
			(xy 34.599874 -512.673362) (xy 34.599874 -512.586462) (xy 34.607892 -512.499933) (xy 34.62386 -512.414513)
			(xy 34.647641 -512.330931) (xy 34.679033 -512.249899) (xy 34.717767 -512.17211) (xy 34.763514 -512.098226)
			(xy 34.815883 -512.028879) (xy 34.874427 -511.964659) (xy 34.938647 -511.906115) (xy 35.007994 -511.853746)
			(xy 35.081878 -511.807999) (xy 35.159667 -511.769265) (xy 35.240699 -511.737873) (xy 35.324281 -511.714092)
			(xy 35.409701 -511.698124) (xy 35.49623 -511.690106) (xy 35.58313 -511.690106) (xy 35.669659 -511.698124)
			(xy 35.755079 -511.714092) (xy 35.838661 -511.737873) (xy 35.919693 -511.769265) (xy 35.997482 -511.807999)
			(xy 36.071366 -511.853746) (xy 36.140713 -511.906115) (xy 36.204933 -511.964659) (xy 36.263477 -512.028879)
			(xy 36.315846 -512.098226) (xy 36.361593 -512.17211) (xy 36.400327 -512.249899) (xy 36.431719 -512.330931)
			(xy 36.4555 -512.414513) (xy 36.471468 -512.499933) (xy 36.479486 -512.586462) (xy 36.479988 -512.629912)
			(xy 36.479486 -512.673362) (xy 36.471468 -512.759891) (xy 36.4555 -512.845311) (xy 36.431719 -512.928893)
			(xy 36.400327 -513.009925) (xy 36.361593 -513.087714) (xy 36.315846 -513.161598) (xy 36.263477 -513.230945)
			(xy 36.204933 -513.295165) (xy 36.172085 -513.32511) (xy 55.897524 -513.32511) (xy 55.901595 -513.269488)
			(xy 55.913721 -513.215051) (xy 55.933644 -513.16296) (xy 55.96094 -513.114325) (xy 55.995026 -513.070182)
			(xy 56.035175 -513.031473) (xy 56.080533 -512.999022) (xy 56.130133 -512.973521) (xy 56.182917 -512.955514)
			(xy 56.23776 -512.945384) (xy 56.293494 -512.943347) (xy 56.348931 -512.949447) (xy 56.402888 -512.963553)
			(xy 56.454217 -512.985365) (xy 56.501823 -513.014419) (xy 56.544691 -513.050094) (xy 56.581908 -513.091631)
			(xy 56.612681 -513.138144) (xy 56.636353 -513.188641) (xy 56.652421 -513.242048) (xy 56.660541 -513.297224)
			(xy 56.66105 -513.32511) (xy 57.167524 -513.32511) (xy 57.171595 -513.269488) (xy 57.183721 -513.215051)
			(xy 57.203644 -513.16296) (xy 57.23094 -513.114325) (xy 57.265026 -513.070182) (xy 57.305175 -513.031473)
			(xy 57.350533 -512.999022) (xy 57.400133 -512.973521) (xy 57.452917 -512.955514) (xy 57.50776 -512.945384)
			(xy 57.563494 -512.943347) (xy 57.618931 -512.949447) (xy 57.672888 -512.963553) (xy 57.724217 -512.985365)
			(xy 57.771823 -513.014419) (xy 57.814691 -513.050094) (xy 57.851908 -513.091631) (xy 57.882681 -513.138144)
			(xy 57.906353 -513.188641) (xy 57.922421 -513.242048) (xy 57.930541 -513.297224) (xy 57.93105 -513.32511)
			(xy 58.429396 -513.32511) (xy 58.433467 -513.269488) (xy 58.445593 -513.215051) (xy 58.465516 -513.16296)
			(xy 58.492812 -513.114325) (xy 58.526898 -513.070182) (xy 58.567047 -513.031473) (xy 58.612405 -512.999022)
			(xy 58.662005 -512.973521) (xy 58.714789 -512.955514) (xy 58.769632 -512.945384) (xy 58.825366 -512.943347)
			(xy 58.880803 -512.949447) (xy 58.93476 -512.963553) (xy 58.986089 -512.985365) (xy 59.033695 -513.014419)
			(xy 59.076563 -513.050094) (xy 59.11378 -513.091631) (xy 59.144553 -513.138144) (xy 59.168225 -513.188641)
			(xy 59.184293 -513.242048) (xy 59.192413 -513.297224) (xy 59.192922 -513.32511) (xy 59.699396 -513.32511)
			(xy 59.703467 -513.269488) (xy 59.715593 -513.215051) (xy 59.735516 -513.16296) (xy 59.762812 -513.114325)
			(xy 59.796898 -513.070182) (xy 59.837047 -513.031473) (xy 59.882405 -512.999022) (xy 59.932005 -512.973521)
			(xy 59.984789 -512.955514) (xy 60.039632 -512.945384) (xy 60.095366 -512.943347) (xy 60.150803 -512.949447)
			(xy 60.20476 -512.963553) (xy 60.256089 -512.985365) (xy 60.303695 -513.014419) (xy 60.346563 -513.050094)
			(xy 60.38378 -513.091631) (xy 60.414553 -513.138144) (xy 60.438225 -513.188641) (xy 60.454293 -513.242048)
			(xy 60.462413 -513.297224) (xy 60.462922 -513.32511) (xy 61.23381 -513.32511) (xy 61.237881 -513.269488)
			(xy 61.250007 -513.215051) (xy 61.26993 -513.16296) (xy 61.297226 -513.114325) (xy 61.331312 -513.070182)
			(xy 61.371461 -513.031473) (xy 61.416819 -512.999022) (xy 61.466419 -512.973521) (xy 61.519203 -512.955514)
			(xy 61.574046 -512.945384) (xy 61.62978 -512.943347) (xy 61.685217 -512.949447) (xy 61.739174 -512.963553)
			(xy 61.790503 -512.985365) (xy 61.838109 -513.014419) (xy 61.880977 -513.050094) (xy 61.918194 -513.091631)
			(xy 61.948967 -513.138144) (xy 61.972639 -513.188641) (xy 61.988707 -513.242048) (xy 61.996827 -513.297224)
			(xy 61.997336 -513.32511) (xy 62.50381 -513.32511) (xy 62.507881 -513.269488) (xy 62.520007 -513.215051)
			(xy 62.53993 -513.16296) (xy 62.567226 -513.114325) (xy 62.601312 -513.070182) (xy 62.641461 -513.031473)
			(xy 62.686819 -512.999022) (xy 62.736419 -512.973521) (xy 62.789203 -512.955514) (xy 62.844046 -512.945384)
			(xy 62.89978 -512.943347) (xy 62.955217 -512.949447) (xy 63.009174 -512.963553) (xy 63.060503 -512.985365)
			(xy 63.108109 -513.014419) (xy 63.150977 -513.050094) (xy 63.188194 -513.091631) (xy 63.218967 -513.138144)
			(xy 63.242639 -513.188641) (xy 63.258707 -513.242048) (xy 63.266827 -513.297224) (xy 63.267336 -513.32511)
			(xy 64.47358 -513.32511) (xy 64.477651 -513.269488) (xy 64.489777 -513.215051) (xy 64.5097 -513.16296)
			(xy 64.536996 -513.114325) (xy 64.571082 -513.070182) (xy 64.611231 -513.031473) (xy 64.656589 -512.999022)
			(xy 64.706189 -512.973521) (xy 64.758973 -512.955514) (xy 64.813816 -512.945384) (xy 64.86955 -512.943347)
			(xy 64.924987 -512.949447) (xy 64.978944 -512.963553) (xy 65.030273 -512.985365) (xy 65.077879 -513.014419)
			(xy 65.120747 -513.050094) (xy 65.157964 -513.091631) (xy 65.188737 -513.138144) (xy 65.212409 -513.188641)
			(xy 65.228477 -513.242048) (xy 65.236597 -513.297224) (xy 65.237106 -513.32511) (xy 65.74358 -513.32511)
			(xy 65.747651 -513.269488) (xy 65.759777 -513.215051) (xy 65.7797 -513.16296) (xy 65.806996 -513.114325)
			(xy 65.841082 -513.070182) (xy 65.881231 -513.031473) (xy 65.926589 -512.999022) (xy 65.976189 -512.973521)
			(xy 66.028973 -512.955514) (xy 66.083816 -512.945384) (xy 66.13955 -512.943347) (xy 66.194987 -512.949447)
			(xy 66.248944 -512.963553) (xy 66.300273 -512.985365) (xy 66.347879 -513.014419) (xy 66.390747 -513.050094)
			(xy 66.427964 -513.091631) (xy 66.458737 -513.138144) (xy 66.482409 -513.188641) (xy 66.498477 -513.242048)
			(xy 66.506597 -513.297224) (xy 66.507106 -513.32511) (xy 67.465192 -513.32511) (xy 67.469263 -513.269488)
			(xy 67.481389 -513.215051) (xy 67.501312 -513.16296) (xy 67.528608 -513.114325) (xy 67.562694 -513.070182)
			(xy 67.602843 -513.031473) (xy 67.648201 -512.999022) (xy 67.697801 -512.973521) (xy 67.750585 -512.955514)
			(xy 67.805428 -512.945384) (xy 67.861162 -512.943347) (xy 67.916599 -512.949447) (xy 67.970556 -512.963553)
			(xy 68.021885 -512.985365) (xy 68.069491 -513.014419) (xy 68.112359 -513.050094) (xy 68.149576 -513.091631)
			(xy 68.180349 -513.138144) (xy 68.204021 -513.188641) (xy 68.220089 -513.242048) (xy 68.228209 -513.297224)
			(xy 68.228718 -513.32511) (xy 68.735192 -513.32511) (xy 68.739263 -513.269488) (xy 68.751389 -513.215051)
			(xy 68.771312 -513.16296) (xy 68.798608 -513.114325) (xy 68.832694 -513.070182) (xy 68.872843 -513.031473)
			(xy 68.918201 -512.999022) (xy 68.967801 -512.973521) (xy 69.020585 -512.955514) (xy 69.075428 -512.945384)
			(xy 69.131162 -512.943347) (xy 69.186599 -512.949447) (xy 69.240556 -512.963553) (xy 69.291885 -512.985365)
			(xy 69.339491 -513.014419) (xy 69.382359 -513.050094) (xy 69.419576 -513.091631) (xy 69.450349 -513.138144)
			(xy 69.474021 -513.188641) (xy 69.490089 -513.242048) (xy 69.498209 -513.297224) (xy 69.498718 -513.32511)
			(xy 69.498209 -513.352996) (xy 69.490089 -513.408172) (xy 69.474021 -513.461579) (xy 69.450349 -513.512076)
			(xy 69.419576 -513.558589) (xy 69.382359 -513.600126) (xy 69.339491 -513.635801) (xy 69.291885 -513.664855)
			(xy 69.240556 -513.686667) (xy 69.186599 -513.700773) (xy 69.131162 -513.706873) (xy 69.075428 -513.704836)
			(xy 69.020585 -513.694706) (xy 68.967801 -513.676699) (xy 68.918201 -513.651198) (xy 68.872843 -513.618747)
			(xy 68.832694 -513.580038) (xy 68.798608 -513.535895) (xy 68.771312 -513.48726) (xy 68.751389 -513.435169)
			(xy 68.739263 -513.380732) (xy 68.735192 -513.32511) (xy 68.228718 -513.32511) (xy 68.228209 -513.352996)
			(xy 68.220089 -513.408172) (xy 68.204021 -513.461579) (xy 68.180349 -513.512076) (xy 68.149576 -513.558589)
			(xy 68.112359 -513.600126) (xy 68.069491 -513.635801) (xy 68.021885 -513.664855) (xy 67.970556 -513.686667)
			(xy 67.916599 -513.700773) (xy 67.861162 -513.706873) (xy 67.805428 -513.704836) (xy 67.750585 -513.694706)
			(xy 67.697801 -513.676699) (xy 67.648201 -513.651198) (xy 67.602843 -513.618747) (xy 67.562694 -513.580038)
			(xy 67.528608 -513.535895) (xy 67.501312 -513.48726) (xy 67.481389 -513.435169) (xy 67.469263 -513.380732)
			(xy 67.465192 -513.32511) (xy 66.507106 -513.32511) (xy 66.506597 -513.352996) (xy 66.498477 -513.408172)
			(xy 66.482409 -513.461579) (xy 66.458737 -513.512076) (xy 66.427964 -513.558589) (xy 66.390747 -513.600126)
			(xy 66.347879 -513.635801) (xy 66.300273 -513.664855) (xy 66.248944 -513.686667) (xy 66.194987 -513.700773)
			(xy 66.13955 -513.706873) (xy 66.083816 -513.704836) (xy 66.028973 -513.694706) (xy 65.976189 -513.676699)
			(xy 65.926589 -513.651198) (xy 65.881231 -513.618747) (xy 65.841082 -513.580038) (xy 65.806996 -513.535895)
			(xy 65.7797 -513.48726) (xy 65.759777 -513.435169) (xy 65.747651 -513.380732) (xy 65.74358 -513.32511)
			(xy 65.237106 -513.32511) (xy 65.236597 -513.352996) (xy 65.228477 -513.408172) (xy 65.212409 -513.461579)
			(xy 65.188737 -513.512076) (xy 65.157964 -513.558589) (xy 65.120747 -513.600126) (xy 65.077879 -513.635801)
			(xy 65.030273 -513.664855) (xy 64.978944 -513.686667) (xy 64.924987 -513.700773) (xy 64.86955 -513.706873)
			(xy 64.813816 -513.704836) (xy 64.758973 -513.694706) (xy 64.706189 -513.676699) (xy 64.656589 -513.651198)
			(xy 64.611231 -513.618747) (xy 64.571082 -513.580038) (xy 64.536996 -513.535895) (xy 64.5097 -513.48726)
			(xy 64.489777 -513.435169) (xy 64.477651 -513.380732) (xy 64.47358 -513.32511) (xy 63.267336 -513.32511)
			(xy 63.266827 -513.352996) (xy 63.258707 -513.408172) (xy 63.242639 -513.461579) (xy 63.218967 -513.512076)
			(xy 63.188194 -513.558589) (xy 63.150977 -513.600126) (xy 63.108109 -513.635801) (xy 63.060503 -513.664855)
			(xy 63.009174 -513.686667) (xy 62.955217 -513.700773) (xy 62.89978 -513.706873) (xy 62.844046 -513.704836)
			(xy 62.789203 -513.694706) (xy 62.736419 -513.676699) (xy 62.686819 -513.651198) (xy 62.641461 -513.618747)
			(xy 62.601312 -513.580038) (xy 62.567226 -513.535895) (xy 62.53993 -513.48726) (xy 62.520007 -513.435169)
			(xy 62.507881 -513.380732) (xy 62.50381 -513.32511) (xy 61.997336 -513.32511) (xy 61.996827 -513.352996)
			(xy 61.988707 -513.408172) (xy 61.972639 -513.461579) (xy 61.948967 -513.512076) (xy 61.918194 -513.558589)
			(xy 61.880977 -513.600126) (xy 61.838109 -513.635801) (xy 61.790503 -513.664855) (xy 61.739174 -513.686667)
			(xy 61.685217 -513.700773) (xy 61.62978 -513.706873) (xy 61.574046 -513.704836) (xy 61.519203 -513.694706)
			(xy 61.466419 -513.676699) (xy 61.416819 -513.651198) (xy 61.371461 -513.618747) (xy 61.331312 -513.580038)
			(xy 61.297226 -513.535895) (xy 61.26993 -513.48726) (xy 61.250007 -513.435169) (xy 61.237881 -513.380732)
			(xy 61.23381 -513.32511) (xy 60.462922 -513.32511) (xy 60.462413 -513.352996) (xy 60.454293 -513.408172)
			(xy 60.438225 -513.461579) (xy 60.414553 -513.512076) (xy 60.38378 -513.558589) (xy 60.346563 -513.600126)
			(xy 60.303695 -513.635801) (xy 60.256089 -513.664855) (xy 60.20476 -513.686667) (xy 60.150803 -513.700773)
			(xy 60.095366 -513.706873) (xy 60.039632 -513.704836) (xy 59.984789 -513.694706) (xy 59.932005 -513.676699)
			(xy 59.882405 -513.651198) (xy 59.837047 -513.618747) (xy 59.796898 -513.580038) (xy 59.762812 -513.535895)
			(xy 59.735516 -513.48726) (xy 59.715593 -513.435169) (xy 59.703467 -513.380732) (xy 59.699396 -513.32511)
			(xy 59.192922 -513.32511) (xy 59.192413 -513.352996) (xy 59.184293 -513.408172) (xy 59.168225 -513.461579)
			(xy 59.144553 -513.512076) (xy 59.11378 -513.558589) (xy 59.076563 -513.600126) (xy 59.033695 -513.635801)
			(xy 58.986089 -513.664855) (xy 58.93476 -513.686667) (xy 58.880803 -513.700773) (xy 58.825366 -513.706873)
			(xy 58.769632 -513.704836) (xy 58.714789 -513.694706) (xy 58.662005 -513.676699) (xy 58.612405 -513.651198)
			(xy 58.567047 -513.618747) (xy 58.526898 -513.580038) (xy 58.492812 -513.535895) (xy 58.465516 -513.48726)
			(xy 58.445593 -513.435169) (xy 58.433467 -513.380732) (xy 58.429396 -513.32511) (xy 57.93105 -513.32511)
			(xy 57.930541 -513.352996) (xy 57.922421 -513.408172) (xy 57.906353 -513.461579) (xy 57.882681 -513.512076)
			(xy 57.851908 -513.558589) (xy 57.814691 -513.600126) (xy 57.771823 -513.635801) (xy 57.724217 -513.664855)
			(xy 57.672888 -513.686667) (xy 57.618931 -513.700773) (xy 57.563494 -513.706873) (xy 57.50776 -513.704836)
			(xy 57.452917 -513.694706) (xy 57.400133 -513.676699) (xy 57.350533 -513.651198) (xy 57.305175 -513.618747)
			(xy 57.265026 -513.580038) (xy 57.23094 -513.535895) (xy 57.203644 -513.48726) (xy 57.183721 -513.435169)
			(xy 57.171595 -513.380732) (xy 57.167524 -513.32511) (xy 56.66105 -513.32511) (xy 56.660541 -513.352996)
			(xy 56.652421 -513.408172) (xy 56.636353 -513.461579) (xy 56.612681 -513.512076) (xy 56.581908 -513.558589)
			(xy 56.544691 -513.600126) (xy 56.501823 -513.635801) (xy 56.454217 -513.664855) (xy 56.402888 -513.686667)
			(xy 56.348931 -513.700773) (xy 56.293494 -513.706873) (xy 56.23776 -513.704836) (xy 56.182917 -513.694706)
			(xy 56.130133 -513.676699) (xy 56.080533 -513.651198) (xy 56.035175 -513.618747) (xy 55.995026 -513.580038)
			(xy 55.96094 -513.535895) (xy 55.933644 -513.48726) (xy 55.913721 -513.435169) (xy 55.901595 -513.380732)
			(xy 55.897524 -513.32511) (xy 36.172085 -513.32511) (xy 36.140713 -513.353709) (xy 36.071366 -513.406078)
			(xy 35.997482 -513.451825) (xy 35.919693 -513.490559) (xy 35.838661 -513.521951) (xy 35.755079 -513.545732)
			(xy 35.669659 -513.5617) (xy 35.58313 -513.569718) (xy 35.49623 -513.569718) (xy 35.409701 -513.5617)
			(xy 35.324281 -513.545732) (xy 35.240699 -513.521951) (xy 35.159667 -513.490559) (xy 35.081878 -513.451825)
			(xy 35.007994 -513.406078) (xy 34.938647 -513.353709) (xy 34.874427 -513.295165) (xy 34.815883 -513.230945)
			(xy 34.763514 -513.161598) (xy 34.717767 -513.087714) (xy 34.679033 -513.009925) (xy 34.647641 -512.928893)
			(xy 34.62386 -512.845311) (xy 34.607892 -512.759891) (xy 34.599874 -512.673362) (xy 31.399486 -512.673362)
			(xy 31.391468 -512.759891) (xy 31.3755 -512.845311) (xy 31.351719 -512.928893) (xy 31.320327 -513.009925)
			(xy 31.281593 -513.087714) (xy 31.235846 -513.161598) (xy 31.183477 -513.230945) (xy 31.124933 -513.295165)
			(xy 31.060713 -513.353709) (xy 30.991366 -513.406078) (xy 30.917482 -513.451825) (xy 30.839693 -513.490559)
			(xy 30.758661 -513.521951) (xy 30.675079 -513.545732) (xy 30.589659 -513.5617) (xy 30.50313 -513.569718)
			(xy 30.41623 -513.569718) (xy 30.329701 -513.5617) (xy 30.244281 -513.545732) (xy 30.160699 -513.521951)
			(xy 30.079667 -513.490559) (xy 30.001878 -513.451825) (xy 29.927994 -513.406078) (xy 29.858647 -513.353709)
			(xy 29.794427 -513.295165) (xy 29.735883 -513.230945) (xy 29.683514 -513.161598) (xy 29.637767 -513.087714)
			(xy 29.599033 -513.009925) (xy 29.567641 -512.928893) (xy 29.54386 -512.845311) (xy 29.527892 -512.759891)
			(xy 29.519874 -512.673362) (xy 1.525016 -512.673362) (xy 1.525016 -515.213362) (xy 29.519874 -515.213362)
			(xy 29.519874 -515.126462) (xy 29.527892 -515.039933) (xy 29.54386 -514.954513) (xy 29.567641 -514.870931)
			(xy 29.599033 -514.789899) (xy 29.637767 -514.71211) (xy 29.683514 -514.638226) (xy 29.735883 -514.568879)
			(xy 29.794427 -514.504659) (xy 29.858647 -514.446115) (xy 29.927994 -514.393746) (xy 30.001878 -514.347999)
			(xy 30.079667 -514.309265) (xy 30.160699 -514.277873) (xy 30.244281 -514.254092) (xy 30.329701 -514.238124)
			(xy 30.41623 -514.230106) (xy 30.50313 -514.230106) (xy 30.589659 -514.238124) (xy 30.675079 -514.254092)
			(xy 30.758661 -514.277873) (xy 30.839693 -514.309265) (xy 30.917482 -514.347999) (xy 30.991366 -514.393746)
			(xy 31.060713 -514.446115) (xy 31.124933 -514.504659) (xy 31.183477 -514.568879) (xy 31.235846 -514.638226)
			(xy 31.281593 -514.71211) (xy 31.320327 -514.789899) (xy 31.351719 -514.870931) (xy 31.3755 -514.954513)
			(xy 31.391468 -515.039933) (xy 31.399486 -515.126462) (xy 31.399988 -515.169912) (xy 31.399486 -515.213362)
			(xy 34.599874 -515.213362) (xy 34.599874 -515.126462) (xy 34.607892 -515.039933) (xy 34.62386 -514.954513)
			(xy 34.647641 -514.870931) (xy 34.679033 -514.789899) (xy 34.717767 -514.71211) (xy 34.763514 -514.638226)
			(xy 34.815883 -514.568879) (xy 34.874427 -514.504659) (xy 34.938647 -514.446115) (xy 35.007994 -514.393746)
			(xy 35.081878 -514.347999) (xy 35.159667 -514.309265) (xy 35.240699 -514.277873) (xy 35.324281 -514.254092)
			(xy 35.409701 -514.238124) (xy 35.49623 -514.230106) (xy 35.58313 -514.230106) (xy 35.669659 -514.238124)
			(xy 35.755079 -514.254092) (xy 35.838661 -514.277873) (xy 35.919693 -514.309265) (xy 35.997482 -514.347999)
			(xy 36.071366 -514.393746) (xy 36.140713 -514.446115) (xy 36.204933 -514.504659) (xy 36.263477 -514.568879)
			(xy 36.315846 -514.638226) (xy 36.361593 -514.71211) (xy 36.400327 -514.789899) (xy 36.431719 -514.870931)
			(xy 36.4555 -514.954513) (xy 36.471468 -515.039933) (xy 36.479486 -515.126462) (xy 36.479988 -515.169912)
			(xy 36.479486 -515.213362) (xy 36.471468 -515.299891) (xy 36.4555 -515.385311) (xy 36.431719 -515.468893)
			(xy 36.400327 -515.549925) (xy 36.361593 -515.627714) (xy 36.315846 -515.701598) (xy 36.263477 -515.770945)
			(xy 36.204933 -515.835165) (xy 36.140713 -515.893709) (xy 36.071366 -515.946078) (xy 35.997482 -515.991825)
			(xy 35.989258 -515.99592) (xy 55.897524 -515.99592) (xy 55.901595 -515.940298) (xy 55.913721 -515.885861)
			(xy 55.933644 -515.83377) (xy 55.96094 -515.785135) (xy 55.995026 -515.740992) (xy 56.035175 -515.702283)
			(xy 56.080533 -515.669832) (xy 56.130133 -515.644331) (xy 56.182917 -515.626324) (xy 56.23776 -515.616194)
			(xy 56.293494 -515.614157) (xy 56.348931 -515.620257) (xy 56.402888 -515.634363) (xy 56.454217 -515.656175)
			(xy 56.501823 -515.685229) (xy 56.544691 -515.720904) (xy 56.581908 -515.762441) (xy 56.612681 -515.808954)
			(xy 56.636353 -515.859451) (xy 56.652421 -515.912858) (xy 56.660541 -515.968034) (xy 56.66105 -515.99592)
			(xy 57.167524 -515.99592) (xy 57.171595 -515.940298) (xy 57.183721 -515.885861) (xy 57.203644 -515.83377)
			(xy 57.23094 -515.785135) (xy 57.265026 -515.740992) (xy 57.305175 -515.702283) (xy 57.350533 -515.669832)
			(xy 57.400133 -515.644331) (xy 57.452917 -515.626324) (xy 57.50776 -515.616194) (xy 57.563494 -515.614157)
			(xy 57.618931 -515.620257) (xy 57.672888 -515.634363) (xy 57.724217 -515.656175) (xy 57.771823 -515.685229)
			(xy 57.814691 -515.720904) (xy 57.851908 -515.762441) (xy 57.882681 -515.808954) (xy 57.906353 -515.859451)
			(xy 57.922421 -515.912858) (xy 57.930541 -515.968034) (xy 57.93105 -515.99592) (xy 58.429396 -515.99592)
			(xy 58.433467 -515.940298) (xy 58.445593 -515.885861) (xy 58.465516 -515.83377) (xy 58.492812 -515.785135)
			(xy 58.526898 -515.740992) (xy 58.567047 -515.702283) (xy 58.612405 -515.669832) (xy 58.662005 -515.644331)
			(xy 58.714789 -515.626324) (xy 58.769632 -515.616194) (xy 58.825366 -515.614157) (xy 58.880803 -515.620257)
			(xy 58.93476 -515.634363) (xy 58.986089 -515.656175) (xy 59.033695 -515.685229) (xy 59.076563 -515.720904)
			(xy 59.11378 -515.762441) (xy 59.144553 -515.808954) (xy 59.168225 -515.859451) (xy 59.184293 -515.912858)
			(xy 59.192413 -515.968034) (xy 59.192922 -515.99592) (xy 59.699396 -515.99592) (xy 59.703467 -515.940298)
			(xy 59.715593 -515.885861) (xy 59.735516 -515.83377) (xy 59.762812 -515.785135) (xy 59.796898 -515.740992)
			(xy 59.837047 -515.702283) (xy 59.882405 -515.669832) (xy 59.932005 -515.644331) (xy 59.984789 -515.626324)
			(xy 60.039632 -515.616194) (xy 60.095366 -515.614157) (xy 60.150803 -515.620257) (xy 60.20476 -515.634363)
			(xy 60.256089 -515.656175) (xy 60.303695 -515.685229) (xy 60.346563 -515.720904) (xy 60.38378 -515.762441)
			(xy 60.414553 -515.808954) (xy 60.438225 -515.859451) (xy 60.454293 -515.912858) (xy 60.462413 -515.968034)
			(xy 60.462922 -515.99592) (xy 61.23381 -515.99592) (xy 61.237881 -515.940298) (xy 61.250007 -515.885861)
			(xy 61.26993 -515.83377) (xy 61.297226 -515.785135) (xy 61.331312 -515.740992) (xy 61.371461 -515.702283)
			(xy 61.416819 -515.669832) (xy 61.466419 -515.644331) (xy 61.519203 -515.626324) (xy 61.574046 -515.616194)
			(xy 61.62978 -515.614157) (xy 61.685217 -515.620257) (xy 61.739174 -515.634363) (xy 61.790503 -515.656175)
			(xy 61.838109 -515.685229) (xy 61.880977 -515.720904) (xy 61.918194 -515.762441) (xy 61.948967 -515.808954)
			(xy 61.972639 -515.859451) (xy 61.988707 -515.912858) (xy 61.996827 -515.968034) (xy 61.997336 -515.99592)
			(xy 62.50381 -515.99592) (xy 62.507881 -515.940298) (xy 62.520007 -515.885861) (xy 62.53993 -515.83377)
			(xy 62.567226 -515.785135) (xy 62.601312 -515.740992) (xy 62.641461 -515.702283) (xy 62.686819 -515.669832)
			(xy 62.736419 -515.644331) (xy 62.789203 -515.626324) (xy 62.844046 -515.616194) (xy 62.89978 -515.614157)
			(xy 62.955217 -515.620257) (xy 63.009174 -515.634363) (xy 63.060503 -515.656175) (xy 63.108109 -515.685229)
			(xy 63.150977 -515.720904) (xy 63.188194 -515.762441) (xy 63.218967 -515.808954) (xy 63.242639 -515.859451)
			(xy 63.258707 -515.912858) (xy 63.266827 -515.968034) (xy 63.267336 -515.99592) (xy 64.47358 -515.99592)
			(xy 64.477651 -515.940298) (xy 64.489777 -515.885861) (xy 64.5097 -515.83377) (xy 64.536996 -515.785135)
			(xy 64.571082 -515.740992) (xy 64.611231 -515.702283) (xy 64.656589 -515.669832) (xy 64.706189 -515.644331)
			(xy 64.758973 -515.626324) (xy 64.813816 -515.616194) (xy 64.86955 -515.614157) (xy 64.924987 -515.620257)
			(xy 64.978944 -515.634363) (xy 65.030273 -515.656175) (xy 65.077879 -515.685229) (xy 65.120747 -515.720904)
			(xy 65.157964 -515.762441) (xy 65.188737 -515.808954) (xy 65.212409 -515.859451) (xy 65.228477 -515.912858)
			(xy 65.236597 -515.968034) (xy 65.237106 -515.99592) (xy 65.74358 -515.99592) (xy 65.747651 -515.940298)
			(xy 65.759777 -515.885861) (xy 65.7797 -515.83377) (xy 65.806996 -515.785135) (xy 65.841082 -515.740992)
			(xy 65.881231 -515.702283) (xy 65.926589 -515.669832) (xy 65.976189 -515.644331) (xy 66.028973 -515.626324)
			(xy 66.083816 -515.616194) (xy 66.13955 -515.614157) (xy 66.194987 -515.620257) (xy 66.248944 -515.634363)
			(xy 66.300273 -515.656175) (xy 66.347879 -515.685229) (xy 66.390747 -515.720904) (xy 66.427964 -515.762441)
			(xy 66.458737 -515.808954) (xy 66.482409 -515.859451) (xy 66.498477 -515.912858) (xy 66.506597 -515.968034)
			(xy 66.507106 -515.99592) (xy 67.465192 -515.99592) (xy 67.469263 -515.940298) (xy 67.481389 -515.885861)
			(xy 67.501312 -515.83377) (xy 67.528608 -515.785135) (xy 67.562694 -515.740992) (xy 67.602843 -515.702283)
			(xy 67.648201 -515.669832) (xy 67.697801 -515.644331) (xy 67.750585 -515.626324) (xy 67.805428 -515.616194)
			(xy 67.861162 -515.614157) (xy 67.916599 -515.620257) (xy 67.970556 -515.634363) (xy 68.021885 -515.656175)
			(xy 68.069491 -515.685229) (xy 68.112359 -515.720904) (xy 68.149576 -515.762441) (xy 68.180349 -515.808954)
			(xy 68.204021 -515.859451) (xy 68.220089 -515.912858) (xy 68.228209 -515.968034) (xy 68.228718 -515.99592)
			(xy 68.735192 -515.99592) (xy 68.739263 -515.940298) (xy 68.751389 -515.885861) (xy 68.771312 -515.83377)
			(xy 68.798608 -515.785135) (xy 68.832694 -515.740992) (xy 68.872843 -515.702283) (xy 68.918201 -515.669832)
			(xy 68.967801 -515.644331) (xy 69.020585 -515.626324) (xy 69.075428 -515.616194) (xy 69.131162 -515.614157)
			(xy 69.186599 -515.620257) (xy 69.240556 -515.634363) (xy 69.291885 -515.656175) (xy 69.339491 -515.685229)
			(xy 69.382359 -515.720904) (xy 69.419576 -515.762441) (xy 69.450349 -515.808954) (xy 69.474021 -515.859451)
			(xy 69.490089 -515.912858) (xy 69.498209 -515.968034) (xy 69.498718 -515.99592) (xy 69.498209 -516.023806)
			(xy 69.490089 -516.078982) (xy 69.474021 -516.132389) (xy 69.450349 -516.182886) (xy 69.419576 -516.229399)
			(xy 69.382359 -516.270936) (xy 69.339491 -516.306611) (xy 69.291885 -516.335665) (xy 69.240556 -516.357477)
			(xy 69.186599 -516.371583) (xy 69.131162 -516.377683) (xy 69.075428 -516.375646) (xy 69.020585 -516.365516)
			(xy 68.967801 -516.347509) (xy 68.918201 -516.322008) (xy 68.872843 -516.289557) (xy 68.832694 -516.250848)
			(xy 68.798608 -516.206705) (xy 68.771312 -516.15807) (xy 68.751389 -516.105979) (xy 68.739263 -516.051542)
			(xy 68.735192 -515.99592) (xy 68.228718 -515.99592) (xy 68.228209 -516.023806) (xy 68.220089 -516.078982)
			(xy 68.204021 -516.132389) (xy 68.180349 -516.182886) (xy 68.149576 -516.229399) (xy 68.112359 -516.270936)
			(xy 68.069491 -516.306611) (xy 68.021885 -516.335665) (xy 67.970556 -516.357477) (xy 67.916599 -516.371583)
			(xy 67.861162 -516.377683) (xy 67.805428 -516.375646) (xy 67.750585 -516.365516) (xy 67.697801 -516.347509)
			(xy 67.648201 -516.322008) (xy 67.602843 -516.289557) (xy 67.562694 -516.250848) (xy 67.528608 -516.206705)
			(xy 67.501312 -516.15807) (xy 67.481389 -516.105979) (xy 67.469263 -516.051542) (xy 67.465192 -515.99592)
			(xy 66.507106 -515.99592) (xy 66.506597 -516.023806) (xy 66.498477 -516.078982) (xy 66.482409 -516.132389)
			(xy 66.458737 -516.182886) (xy 66.427964 -516.229399) (xy 66.390747 -516.270936) (xy 66.347879 -516.306611)
			(xy 66.300273 -516.335665) (xy 66.248944 -516.357477) (xy 66.194987 -516.371583) (xy 66.13955 -516.377683)
			(xy 66.083816 -516.375646) (xy 66.028973 -516.365516) (xy 65.976189 -516.347509) (xy 65.926589 -516.322008)
			(xy 65.881231 -516.289557) (xy 65.841082 -516.250848) (xy 65.806996 -516.206705) (xy 65.7797 -516.15807)
			(xy 65.759777 -516.105979) (xy 65.747651 -516.051542) (xy 65.74358 -515.99592) (xy 65.237106 -515.99592)
			(xy 65.236597 -516.023806) (xy 65.228477 -516.078982) (xy 65.212409 -516.132389) (xy 65.188737 -516.182886)
			(xy 65.157964 -516.229399) (xy 65.120747 -516.270936) (xy 65.077879 -516.306611) (xy 65.030273 -516.335665)
			(xy 64.978944 -516.357477) (xy 64.924987 -516.371583) (xy 64.86955 -516.377683) (xy 64.813816 -516.375646)
			(xy 64.758973 -516.365516) (xy 64.706189 -516.347509) (xy 64.656589 -516.322008) (xy 64.611231 -516.289557)
			(xy 64.571082 -516.250848) (xy 64.536996 -516.206705) (xy 64.5097 -516.15807) (xy 64.489777 -516.105979)
			(xy 64.477651 -516.051542) (xy 64.47358 -515.99592) (xy 63.267336 -515.99592) (xy 63.266827 -516.023806)
			(xy 63.258707 -516.078982) (xy 63.242639 -516.132389) (xy 63.218967 -516.182886) (xy 63.188194 -516.229399)
			(xy 63.150977 -516.270936) (xy 63.108109 -516.306611) (xy 63.060503 -516.335665) (xy 63.009174 -516.357477)
			(xy 62.955217 -516.371583) (xy 62.89978 -516.377683) (xy 62.844046 -516.375646) (xy 62.789203 -516.365516)
			(xy 62.736419 -516.347509) (xy 62.686819 -516.322008) (xy 62.641461 -516.289557) (xy 62.601312 -516.250848)
			(xy 62.567226 -516.206705) (xy 62.53993 -516.15807) (xy 62.520007 -516.105979) (xy 62.507881 -516.051542)
			(xy 62.50381 -515.99592) (xy 61.997336 -515.99592) (xy 61.996827 -516.023806) (xy 61.988707 -516.078982)
			(xy 61.972639 -516.132389) (xy 61.948967 -516.182886) (xy 61.918194 -516.229399) (xy 61.880977 -516.270936)
			(xy 61.838109 -516.306611) (xy 61.790503 -516.335665) (xy 61.739174 -516.357477) (xy 61.685217 -516.371583)
			(xy 61.62978 -516.377683) (xy 61.574046 -516.375646) (xy 61.519203 -516.365516) (xy 61.466419 -516.347509)
			(xy 61.416819 -516.322008) (xy 61.371461 -516.289557) (xy 61.331312 -516.250848) (xy 61.297226 -516.206705)
			(xy 61.26993 -516.15807) (xy 61.250007 -516.105979) (xy 61.237881 -516.051542) (xy 61.23381 -515.99592)
			(xy 60.462922 -515.99592) (xy 60.462413 -516.023806) (xy 60.454293 -516.078982) (xy 60.438225 -516.132389)
			(xy 60.414553 -516.182886) (xy 60.38378 -516.229399) (xy 60.346563 -516.270936) (xy 60.303695 -516.306611)
			(xy 60.256089 -516.335665) (xy 60.20476 -516.357477) (xy 60.150803 -516.371583) (xy 60.095366 -516.377683)
			(xy 60.039632 -516.375646) (xy 59.984789 -516.365516) (xy 59.932005 -516.347509) (xy 59.882405 -516.322008)
			(xy 59.837047 -516.289557) (xy 59.796898 -516.250848) (xy 59.762812 -516.206705) (xy 59.735516 -516.15807)
			(xy 59.715593 -516.105979) (xy 59.703467 -516.051542) (xy 59.699396 -515.99592) (xy 59.192922 -515.99592)
			(xy 59.192413 -516.023806) (xy 59.184293 -516.078982) (xy 59.168225 -516.132389) (xy 59.144553 -516.182886)
			(xy 59.11378 -516.229399) (xy 59.076563 -516.270936) (xy 59.033695 -516.306611) (xy 58.986089 -516.335665)
			(xy 58.93476 -516.357477) (xy 58.880803 -516.371583) (xy 58.825366 -516.377683) (xy 58.769632 -516.375646)
			(xy 58.714789 -516.365516) (xy 58.662005 -516.347509) (xy 58.612405 -516.322008) (xy 58.567047 -516.289557)
			(xy 58.526898 -516.250848) (xy 58.492812 -516.206705) (xy 58.465516 -516.15807) (xy 58.445593 -516.105979)
			(xy 58.433467 -516.051542) (xy 58.429396 -515.99592) (xy 57.93105 -515.99592) (xy 57.930541 -516.023806)
			(xy 57.922421 -516.078982) (xy 57.906353 -516.132389) (xy 57.882681 -516.182886) (xy 57.851908 -516.229399)
			(xy 57.814691 -516.270936) (xy 57.771823 -516.306611) (xy 57.724217 -516.335665) (xy 57.672888 -516.357477)
			(xy 57.618931 -516.371583) (xy 57.563494 -516.377683) (xy 57.50776 -516.375646) (xy 57.452917 -516.365516)
			(xy 57.400133 -516.347509) (xy 57.350533 -516.322008) (xy 57.305175 -516.289557) (xy 57.265026 -516.250848)
			(xy 57.23094 -516.206705) (xy 57.203644 -516.15807) (xy 57.183721 -516.105979) (xy 57.171595 -516.051542)
			(xy 57.167524 -515.99592) (xy 56.66105 -515.99592) (xy 56.660541 -516.023806) (xy 56.652421 -516.078982)
			(xy 56.636353 -516.132389) (xy 56.612681 -516.182886) (xy 56.581908 -516.229399) (xy 56.544691 -516.270936)
			(xy 56.501823 -516.306611) (xy 56.454217 -516.335665) (xy 56.402888 -516.357477) (xy 56.348931 -516.371583)
			(xy 56.293494 -516.377683) (xy 56.23776 -516.375646) (xy 56.182917 -516.365516) (xy 56.130133 -516.347509)
			(xy 56.080533 -516.322008) (xy 56.035175 -516.289557) (xy 55.995026 -516.250848) (xy 55.96094 -516.206705)
			(xy 55.933644 -516.15807) (xy 55.913721 -516.105979) (xy 55.901595 -516.051542) (xy 55.897524 -515.99592)
			(xy 35.989258 -515.99592) (xy 35.919693 -516.030559) (xy 35.838661 -516.061951) (xy 35.755079 -516.085732)
			(xy 35.669659 -516.1017) (xy 35.58313 -516.109718) (xy 35.49623 -516.109718) (xy 35.409701 -516.1017)
			(xy 35.324281 -516.085732) (xy 35.240699 -516.061951) (xy 35.159667 -516.030559) (xy 35.081878 -515.991825)
			(xy 35.007994 -515.946078) (xy 34.938647 -515.893709) (xy 34.874427 -515.835165) (xy 34.815883 -515.770945)
			(xy 34.763514 -515.701598) (xy 34.717767 -515.627714) (xy 34.679033 -515.549925) (xy 34.647641 -515.468893)
			(xy 34.62386 -515.385311) (xy 34.607892 -515.299891) (xy 34.599874 -515.213362) (xy 31.399486 -515.213362)
			(xy 31.391468 -515.299891) (xy 31.3755 -515.385311) (xy 31.351719 -515.468893) (xy 31.320327 -515.549925)
			(xy 31.281593 -515.627714) (xy 31.235846 -515.701598) (xy 31.183477 -515.770945) (xy 31.124933 -515.835165)
			(xy 31.060713 -515.893709) (xy 30.991366 -515.946078) (xy 30.917482 -515.991825) (xy 30.839693 -516.030559)
			(xy 30.758661 -516.061951) (xy 30.675079 -516.085732) (xy 30.589659 -516.1017) (xy 30.50313 -516.109718)
			(xy 30.41623 -516.109718) (xy 30.329701 -516.1017) (xy 30.244281 -516.085732) (xy 30.160699 -516.061951)
			(xy 30.079667 -516.030559) (xy 30.001878 -515.991825) (xy 29.927994 -515.946078) (xy 29.858647 -515.893709)
			(xy 29.794427 -515.835165) (xy 29.735883 -515.770945) (xy 29.683514 -515.701598) (xy 29.637767 -515.627714)
			(xy 29.599033 -515.549925) (xy 29.567641 -515.468893) (xy 29.54386 -515.385311) (xy 29.527892 -515.299891)
			(xy 29.519874 -515.213362) (xy 1.525016 -515.213362) (xy 1.525016 -516.122412) (xy 4.852416 -516.122412)
			(xy 6.707632 -516.122412) (xy 6.707632 -517.753362) (xy 29.519874 -517.753362) (xy 29.519874 -517.666462)
			(xy 29.527892 -517.579933) (xy 29.54386 -517.494513) (xy 29.567641 -517.410931) (xy 29.599033 -517.329899)
			(xy 29.637767 -517.25211) (xy 29.683514 -517.178226) (xy 29.735883 -517.108879) (xy 29.794427 -517.044659)
			(xy 29.858647 -516.986115) (xy 29.927994 -516.933746) (xy 30.001878 -516.887999) (xy 30.079667 -516.849265)
			(xy 30.160699 -516.817873) (xy 30.244281 -516.794092) (xy 30.329701 -516.778124) (xy 30.41623 -516.770106)
			(xy 30.50313 -516.770106) (xy 30.589659 -516.778124) (xy 30.675079 -516.794092) (xy 30.758661 -516.817873)
			(xy 30.839693 -516.849265) (xy 30.917482 -516.887999) (xy 30.991366 -516.933746) (xy 31.060713 -516.986115)
			(xy 31.124933 -517.044659) (xy 31.183477 -517.108879) (xy 31.235846 -517.178226) (xy 31.281593 -517.25211)
			(xy 31.320327 -517.329899) (xy 31.351719 -517.410931) (xy 31.3755 -517.494513) (xy 31.391468 -517.579933)
			(xy 31.399486 -517.666462) (xy 31.399988 -517.709912) (xy 31.399486 -517.753362) (xy 34.599874 -517.753362)
			(xy 34.599874 -517.666462) (xy 34.607892 -517.579933) (xy 34.62386 -517.494513) (xy 34.647641 -517.410931)
			(xy 34.679033 -517.329899) (xy 34.717767 -517.25211) (xy 34.763514 -517.178226) (xy 34.815883 -517.108879)
			(xy 34.874427 -517.044659) (xy 34.938647 -516.986115) (xy 35.007994 -516.933746) (xy 35.081878 -516.887999)
			(xy 35.159667 -516.849265) (xy 35.240699 -516.817873) (xy 35.324281 -516.794092) (xy 35.409701 -516.778124)
			(xy 35.49623 -516.770106) (xy 35.58313 -516.770106) (xy 35.669659 -516.778124) (xy 35.755079 -516.794092)
			(xy 35.838661 -516.817873) (xy 35.919693 -516.849265) (xy 35.997482 -516.887999) (xy 36.071366 -516.933746)
			(xy 36.140713 -516.986115) (xy 36.204933 -517.044659) (xy 36.263477 -517.108879) (xy 36.315846 -517.178226)
			(xy 36.361593 -517.25211) (xy 36.400327 -517.329899) (xy 36.431719 -517.410931) (xy 36.4555 -517.494513)
			(xy 36.471468 -517.579933) (xy 36.479486 -517.666462) (xy 36.479988 -517.709912) (xy 36.479486 -517.753362)
			(xy 36.471468 -517.839891) (xy 36.4555 -517.925311) (xy 36.431719 -518.008893) (xy 36.400327 -518.089925)
			(xy 36.361593 -518.167714) (xy 36.344981 -518.194544) (xy 51.322732 -518.194544) (xy 52.974748 -518.194544)
			(xy 52.974748 -518.66419) (xy 55.897524 -518.66419) (xy 55.901595 -518.608568) (xy 55.913721 -518.554131)
			(xy 55.933644 -518.50204) (xy 55.96094 -518.453405) (xy 55.995026 -518.409262) (xy 56.035175 -518.370553)
			(xy 56.080533 -518.338102) (xy 56.130133 -518.312601) (xy 56.182917 -518.294594) (xy 56.23776 -518.284464)
			(xy 56.293494 -518.282427) (xy 56.348931 -518.288527) (xy 56.402888 -518.302633) (xy 56.454217 -518.324445)
			(xy 56.501823 -518.353499) (xy 56.544691 -518.389174) (xy 56.581908 -518.430711) (xy 56.612681 -518.477224)
			(xy 56.636353 -518.527721) (xy 56.652421 -518.581128) (xy 56.660541 -518.636304) (xy 56.66105 -518.66419)
			(xy 57.167524 -518.66419) (xy 57.171595 -518.608568) (xy 57.183721 -518.554131) (xy 57.203644 -518.50204)
			(xy 57.23094 -518.453405) (xy 57.265026 -518.409262) (xy 57.305175 -518.370553) (xy 57.350533 -518.338102)
			(xy 57.400133 -518.312601) (xy 57.452917 -518.294594) (xy 57.50776 -518.284464) (xy 57.563494 -518.282427)
			(xy 57.618931 -518.288527) (xy 57.672888 -518.302633) (xy 57.724217 -518.324445) (xy 57.771823 -518.353499)
			(xy 57.814691 -518.389174) (xy 57.851908 -518.430711) (xy 57.882681 -518.477224) (xy 57.906353 -518.527721)
			(xy 57.922421 -518.581128) (xy 57.930541 -518.636304) (xy 57.93105 -518.66419) (xy 58.429396 -518.66419)
			(xy 58.433467 -518.608568) (xy 58.445593 -518.554131) (xy 58.465516 -518.50204) (xy 58.492812 -518.453405)
			(xy 58.526898 -518.409262) (xy 58.567047 -518.370553) (xy 58.612405 -518.338102) (xy 58.662005 -518.312601)
			(xy 58.714789 -518.294594) (xy 58.769632 -518.284464) (xy 58.825366 -518.282427) (xy 58.880803 -518.288527)
			(xy 58.93476 -518.302633) (xy 58.986089 -518.324445) (xy 59.033695 -518.353499) (xy 59.076563 -518.389174)
			(xy 59.11378 -518.430711) (xy 59.144553 -518.477224) (xy 59.168225 -518.527721) (xy 59.184293 -518.581128)
			(xy 59.192413 -518.636304) (xy 59.192922 -518.66419) (xy 59.699396 -518.66419) (xy 59.703467 -518.608568)
			(xy 59.715593 -518.554131) (xy 59.735516 -518.50204) (xy 59.762812 -518.453405) (xy 59.796898 -518.409262)
			(xy 59.837047 -518.370553) (xy 59.882405 -518.338102) (xy 59.932005 -518.312601) (xy 59.984789 -518.294594)
			(xy 60.039632 -518.284464) (xy 60.095366 -518.282427) (xy 60.150803 -518.288527) (xy 60.20476 -518.302633)
			(xy 60.256089 -518.324445) (xy 60.303695 -518.353499) (xy 60.346563 -518.389174) (xy 60.38378 -518.430711)
			(xy 60.414553 -518.477224) (xy 60.438225 -518.527721) (xy 60.454293 -518.581128) (xy 60.462413 -518.636304)
			(xy 60.462922 -518.66419) (xy 61.23381 -518.66419) (xy 61.237881 -518.608568) (xy 61.250007 -518.554131)
			(xy 61.26993 -518.50204) (xy 61.297226 -518.453405) (xy 61.331312 -518.409262) (xy 61.371461 -518.370553)
			(xy 61.416819 -518.338102) (xy 61.466419 -518.312601) (xy 61.519203 -518.294594) (xy 61.574046 -518.284464)
			(xy 61.62978 -518.282427) (xy 61.685217 -518.288527) (xy 61.739174 -518.302633) (xy 61.790503 -518.324445)
			(xy 61.838109 -518.353499) (xy 61.880977 -518.389174) (xy 61.918194 -518.430711) (xy 61.948967 -518.477224)
			(xy 61.972639 -518.527721) (xy 61.988707 -518.581128) (xy 61.996827 -518.636304) (xy 61.997336 -518.66419)
			(xy 62.50381 -518.66419) (xy 62.507881 -518.608568) (xy 62.520007 -518.554131) (xy 62.53993 -518.50204)
			(xy 62.567226 -518.453405) (xy 62.601312 -518.409262) (xy 62.641461 -518.370553) (xy 62.686819 -518.338102)
			(xy 62.736419 -518.312601) (xy 62.789203 -518.294594) (xy 62.844046 -518.284464) (xy 62.89978 -518.282427)
			(xy 62.955217 -518.288527) (xy 63.009174 -518.302633) (xy 63.060503 -518.324445) (xy 63.108109 -518.353499)
			(xy 63.150977 -518.389174) (xy 63.188194 -518.430711) (xy 63.218967 -518.477224) (xy 63.242639 -518.527721)
			(xy 63.258707 -518.581128) (xy 63.266827 -518.636304) (xy 63.267336 -518.66419) (xy 64.47358 -518.66419)
			(xy 64.477651 -518.608568) (xy 64.489777 -518.554131) (xy 64.5097 -518.50204) (xy 64.536996 -518.453405)
			(xy 64.571082 -518.409262) (xy 64.611231 -518.370553) (xy 64.656589 -518.338102) (xy 64.706189 -518.312601)
			(xy 64.758973 -518.294594) (xy 64.813816 -518.284464) (xy 64.86955 -518.282427) (xy 64.924987 -518.288527)
			(xy 64.978944 -518.302633) (xy 65.030273 -518.324445) (xy 65.077879 -518.353499) (xy 65.120747 -518.389174)
			(xy 65.157964 -518.430711) (xy 65.188737 -518.477224) (xy 65.212409 -518.527721) (xy 65.228477 -518.581128)
			(xy 65.236597 -518.636304) (xy 65.237106 -518.66419) (xy 65.74358 -518.66419) (xy 65.747651 -518.608568)
			(xy 65.759777 -518.554131) (xy 65.7797 -518.50204) (xy 65.806996 -518.453405) (xy 65.841082 -518.409262)
			(xy 65.881231 -518.370553) (xy 65.926589 -518.338102) (xy 65.976189 -518.312601) (xy 66.028973 -518.294594)
			(xy 66.083816 -518.284464) (xy 66.13955 -518.282427) (xy 66.194987 -518.288527) (xy 66.248944 -518.302633)
			(xy 66.300273 -518.324445) (xy 66.347879 -518.353499) (xy 66.390747 -518.389174) (xy 66.427964 -518.430711)
			(xy 66.458737 -518.477224) (xy 66.482409 -518.527721) (xy 66.498477 -518.581128) (xy 66.506597 -518.636304)
			(xy 66.507106 -518.66419) (xy 67.465192 -518.66419) (xy 67.469263 -518.608568) (xy 67.481389 -518.554131)
			(xy 67.501312 -518.50204) (xy 67.528608 -518.453405) (xy 67.562694 -518.409262) (xy 67.602843 -518.370553)
			(xy 67.648201 -518.338102) (xy 67.697801 -518.312601) (xy 67.750585 -518.294594) (xy 67.805428 -518.284464)
			(xy 67.861162 -518.282427) (xy 67.916599 -518.288527) (xy 67.970556 -518.302633) (xy 68.021885 -518.324445)
			(xy 68.069491 -518.353499) (xy 68.112359 -518.389174) (xy 68.149576 -518.430711) (xy 68.180349 -518.477224)
			(xy 68.204021 -518.527721) (xy 68.220089 -518.581128) (xy 68.228209 -518.636304) (xy 68.228718 -518.66419)
			(xy 68.735192 -518.66419) (xy 68.739263 -518.608568) (xy 68.751389 -518.554131) (xy 68.771312 -518.50204)
			(xy 68.798608 -518.453405) (xy 68.832694 -518.409262) (xy 68.872843 -518.370553) (xy 68.918201 -518.338102)
			(xy 68.967801 -518.312601) (xy 69.020585 -518.294594) (xy 69.075428 -518.284464) (xy 69.131162 -518.282427)
			(xy 69.186599 -518.288527) (xy 69.240556 -518.302633) (xy 69.291885 -518.324445) (xy 69.339491 -518.353499)
			(xy 69.382359 -518.389174) (xy 69.419576 -518.430711) (xy 69.450349 -518.477224) (xy 69.474021 -518.527721)
			(xy 69.490089 -518.581128) (xy 69.498209 -518.636304) (xy 69.498718 -518.66419) (xy 69.498209 -518.692076)
			(xy 69.490089 -518.747252) (xy 69.474021 -518.800659) (xy 69.450349 -518.851156) (xy 69.419576 -518.897669)
			(xy 69.382359 -518.939206) (xy 69.339491 -518.974881) (xy 69.291885 -519.003935) (xy 69.240556 -519.025747)
			(xy 69.186599 -519.039853) (xy 69.131162 -519.045953) (xy 69.075428 -519.043916) (xy 69.020585 -519.033786)
			(xy 68.967801 -519.015779) (xy 68.918201 -518.990278) (xy 68.872843 -518.957827) (xy 68.832694 -518.919118)
			(xy 68.798608 -518.874975) (xy 68.771312 -518.82634) (xy 68.751389 -518.774249) (xy 68.739263 -518.719812)
			(xy 68.735192 -518.66419) (xy 68.228718 -518.66419) (xy 68.228209 -518.692076) (xy 68.220089 -518.747252)
			(xy 68.204021 -518.800659) (xy 68.180349 -518.851156) (xy 68.149576 -518.897669) (xy 68.112359 -518.939206)
			(xy 68.069491 -518.974881) (xy 68.021885 -519.003935) (xy 67.970556 -519.025747) (xy 67.916599 -519.039853)
			(xy 67.861162 -519.045953) (xy 67.805428 -519.043916) (xy 67.750585 -519.033786) (xy 67.697801 -519.015779)
			(xy 67.648201 -518.990278) (xy 67.602843 -518.957827) (xy 67.562694 -518.919118) (xy 67.528608 -518.874975)
			(xy 67.501312 -518.82634) (xy 67.481389 -518.774249) (xy 67.469263 -518.719812) (xy 67.465192 -518.66419)
			(xy 66.507106 -518.66419) (xy 66.506597 -518.692076) (xy 66.498477 -518.747252) (xy 66.482409 -518.800659)
			(xy 66.458737 -518.851156) (xy 66.427964 -518.897669) (xy 66.390747 -518.939206) (xy 66.347879 -518.974881)
			(xy 66.300273 -519.003935) (xy 66.248944 -519.025747) (xy 66.194987 -519.039853) (xy 66.13955 -519.045953)
			(xy 66.083816 -519.043916) (xy 66.028973 -519.033786) (xy 65.976189 -519.015779) (xy 65.926589 -518.990278)
			(xy 65.881231 -518.957827) (xy 65.841082 -518.919118) (xy 65.806996 -518.874975) (xy 65.7797 -518.82634)
			(xy 65.759777 -518.774249) (xy 65.747651 -518.719812) (xy 65.74358 -518.66419) (xy 65.237106 -518.66419)
			(xy 65.236597 -518.692076) (xy 65.228477 -518.747252) (xy 65.212409 -518.800659) (xy 65.188737 -518.851156)
			(xy 65.157964 -518.897669) (xy 65.120747 -518.939206) (xy 65.077879 -518.974881) (xy 65.030273 -519.003935)
			(xy 64.978944 -519.025747) (xy 64.924987 -519.039853) (xy 64.86955 -519.045953) (xy 64.813816 -519.043916)
			(xy 64.758973 -519.033786) (xy 64.706189 -519.015779) (xy 64.656589 -518.990278) (xy 64.611231 -518.957827)
			(xy 64.571082 -518.919118) (xy 64.536996 -518.874975) (xy 64.5097 -518.82634) (xy 64.489777 -518.774249)
			(xy 64.477651 -518.719812) (xy 64.47358 -518.66419) (xy 63.267336 -518.66419) (xy 63.266827 -518.692076)
			(xy 63.258707 -518.747252) (xy 63.242639 -518.800659) (xy 63.218967 -518.851156) (xy 63.188194 -518.897669)
			(xy 63.150977 -518.939206) (xy 63.108109 -518.974881) (xy 63.060503 -519.003935) (xy 63.009174 -519.025747)
			(xy 62.955217 -519.039853) (xy 62.89978 -519.045953) (xy 62.844046 -519.043916) (xy 62.789203 -519.033786)
			(xy 62.736419 -519.015779) (xy 62.686819 -518.990278) (xy 62.641461 -518.957827) (xy 62.601312 -518.919118)
			(xy 62.567226 -518.874975) (xy 62.53993 -518.82634) (xy 62.520007 -518.774249) (xy 62.507881 -518.719812)
			(xy 62.50381 -518.66419) (xy 61.997336 -518.66419) (xy 61.996827 -518.692076) (xy 61.988707 -518.747252)
			(xy 61.972639 -518.800659) (xy 61.948967 -518.851156) (xy 61.918194 -518.897669) (xy 61.880977 -518.939206)
			(xy 61.838109 -518.974881) (xy 61.790503 -519.003935) (xy 61.739174 -519.025747) (xy 61.685217 -519.039853)
			(xy 61.62978 -519.045953) (xy 61.574046 -519.043916) (xy 61.519203 -519.033786) (xy 61.466419 -519.015779)
			(xy 61.416819 -518.990278) (xy 61.371461 -518.957827) (xy 61.331312 -518.919118) (xy 61.297226 -518.874975)
			(xy 61.26993 -518.82634) (xy 61.250007 -518.774249) (xy 61.237881 -518.719812) (xy 61.23381 -518.66419)
			(xy 60.462922 -518.66419) (xy 60.462413 -518.692076) (xy 60.454293 -518.747252) (xy 60.438225 -518.800659)
			(xy 60.414553 -518.851156) (xy 60.38378 -518.897669) (xy 60.346563 -518.939206) (xy 60.303695 -518.974881)
			(xy 60.256089 -519.003935) (xy 60.20476 -519.025747) (xy 60.150803 -519.039853) (xy 60.095366 -519.045953)
			(xy 60.039632 -519.043916) (xy 59.984789 -519.033786) (xy 59.932005 -519.015779) (xy 59.882405 -518.990278)
			(xy 59.837047 -518.957827) (xy 59.796898 -518.919118) (xy 59.762812 -518.874975) (xy 59.735516 -518.82634)
			(xy 59.715593 -518.774249) (xy 59.703467 -518.719812) (xy 59.699396 -518.66419) (xy 59.192922 -518.66419)
			(xy 59.192413 -518.692076) (xy 59.184293 -518.747252) (xy 59.168225 -518.800659) (xy 59.144553 -518.851156)
			(xy 59.11378 -518.897669) (xy 59.076563 -518.939206) (xy 59.033695 -518.974881) (xy 58.986089 -519.003935)
			(xy 58.93476 -519.025747) (xy 58.880803 -519.039853) (xy 58.825366 -519.045953) (xy 58.769632 -519.043916)
			(xy 58.714789 -519.033786) (xy 58.662005 -519.015779) (xy 58.612405 -518.990278) (xy 58.567047 -518.957827)
			(xy 58.526898 -518.919118) (xy 58.492812 -518.874975) (xy 58.465516 -518.82634) (xy 58.445593 -518.774249)
			(xy 58.433467 -518.719812) (xy 58.429396 -518.66419) (xy 57.93105 -518.66419) (xy 57.930541 -518.692076)
			(xy 57.922421 -518.747252) (xy 57.906353 -518.800659) (xy 57.882681 -518.851156) (xy 57.851908 -518.897669)
			(xy 57.814691 -518.939206) (xy 57.771823 -518.974881) (xy 57.724217 -519.003935) (xy 57.672888 -519.025747)
			(xy 57.618931 -519.039853) (xy 57.563494 -519.045953) (xy 57.50776 -519.043916) (xy 57.452917 -519.033786)
			(xy 57.400133 -519.015779) (xy 57.350533 -518.990278) (xy 57.305175 -518.957827) (xy 57.265026 -518.919118)
			(xy 57.23094 -518.874975) (xy 57.203644 -518.82634) (xy 57.183721 -518.774249) (xy 57.171595 -518.719812)
			(xy 57.167524 -518.66419) (xy 56.66105 -518.66419) (xy 56.660541 -518.692076) (xy 56.652421 -518.747252)
			(xy 56.636353 -518.800659) (xy 56.612681 -518.851156) (xy 56.581908 -518.897669) (xy 56.544691 -518.939206)
			(xy 56.501823 -518.974881) (xy 56.454217 -519.003935) (xy 56.402888 -519.025747) (xy 56.348931 -519.039853)
			(xy 56.293494 -519.045953) (xy 56.23776 -519.043916) (xy 56.182917 -519.033786) (xy 56.130133 -519.015779)
			(xy 56.080533 -518.990278) (xy 56.035175 -518.957827) (xy 55.995026 -518.919118) (xy 55.96094 -518.874975)
			(xy 55.933644 -518.82634) (xy 55.913721 -518.774249) (xy 55.901595 -518.719812) (xy 55.897524 -518.66419)
			(xy 52.974748 -518.66419) (xy 52.974748 -519.050016) (xy 72.998846 -519.050016) (xy 73.00285 -518.849918)
			(xy 73.014857 -518.65014) (xy 73.034848 -518.451003) (xy 73.06279 -518.252825) (xy 73.098638 -518.055923)
			(xy 73.142336 -517.860614) (xy 73.193813 -517.667209) (xy 73.252987 -517.476019) (xy 73.319763 -517.287349)
			(xy 73.394035 -517.101502) (xy 73.475682 -516.918775) (xy 73.564575 -516.739462) (xy 73.660571 -516.563848)
			(xy 73.763516 -516.392216) (xy 73.873246 -516.22484) (xy 73.989584 -516.061989) (xy 74.112345 -515.903922)
			(xy 74.241332 -515.750894) (xy 74.376339 -515.603149) (xy 74.517148 -515.460923) (xy 74.663535 -515.324446)
			(xy 74.815265 -515.193934) (xy 74.972096 -515.069598) (xy 75.133775 -514.951636) (xy 75.300045 -514.840237)
			(xy 75.470638 -514.73558) (xy 75.645282 -514.637832) (xy 75.823698 -514.547149) (xy 76.005598 -514.463678)
			(xy 76.190693 -514.387551) (xy 76.378685 -514.318891) (xy 76.569274 -514.257807) (xy 76.762154 -514.204397)
			(xy 76.957016 -514.158748) (xy 77.153549 -514.120931) (xy 77.351438 -514.091007) (xy 77.550365 -514.069025)
			(xy 77.750013 -514.05502) (xy 77.950061 -514.049014) (xy 78.150189 -514.051016) (xy 78.350077 -514.061024)
			(xy 78.549404 -514.079021) (xy 78.747852 -514.104979) (xy 78.945102 -514.138856) (xy 79.140839 -514.180598)
			(xy 79.334749 -514.230137) (xy 79.526522 -514.287395) (xy 79.715851 -514.35228) (xy 79.902431 -514.424688)
			(xy 80.085966 -514.504504) (xy 80.26616 -514.591598) (xy 80.442725 -514.685832) (xy 80.615378 -514.787055)
			(xy 80.783843 -514.895105) (xy 80.947851 -515.009808) (xy 81.107138 -515.130982) (xy 81.261449 -515.258431)
			(xy 81.410537 -515.391952) (xy 81.554164 -515.531332) (xy 81.6921 -515.676346) (xy 81.824123 -515.826763)
			(xy 81.950022 -515.982341) (xy 82.069596 -516.142833) (xy 82.182652 -516.307979) (xy 82.289011 -516.477517)
			(xy 82.388502 -516.651175) (xy 82.480965 -516.828674) (xy 82.566252 -517.00973) (xy 82.568632 -517.015357)
			(xy 85.959938 -517.015357) (xy 85.959938 -516.901803) (xy 85.967859 -516.788527) (xy 85.983662 -516.676079)
			(xy 86.007271 -516.565008) (xy 86.038571 -516.455853) (xy 86.077408 -516.349148) (xy 86.123594 -516.245413)
			(xy 86.176904 -516.145151) (xy 86.237078 -516.048853) (xy 86.303823 -515.956987) (xy 86.376813 -515.87)
			(xy 86.455694 -515.788317) (xy 86.54008 -515.712335) (xy 86.629561 -515.642425) (xy 86.723701 -515.578927)
			(xy 86.822041 -515.52215) (xy 86.924101 -515.472372) (xy 87.029386 -515.429834) (xy 87.137381 -515.394744)
			(xy 87.247561 -515.367273) (xy 87.359389 -515.347555) (xy 87.47232 -515.335685) (xy 87.585804 -515.331723)
			(xy 87.699288 -515.335685) (xy 87.812219 -515.347555) (xy 87.924047 -515.367273) (xy 88.034227 -515.394744)
			(xy 88.142222 -515.429834) (xy 88.247507 -515.472372) (xy 88.349567 -515.52215) (xy 88.447907 -515.578927)
			(xy 88.542047 -515.642425) (xy 88.631528 -515.712335) (xy 88.715914 -515.788317) (xy 88.794795 -515.87)
			(xy 88.867785 -515.956987) (xy 88.93453 -516.048853) (xy 88.994704 -516.145151) (xy 89.048014 -516.245413)
			(xy 89.0942 -516.349148) (xy 89.133037 -516.455853) (xy 89.164337 -516.565008) (xy 89.187946 -516.676079)
			(xy 89.203749 -516.788527) (xy 89.21167 -516.901803) (xy 89.212166 -516.95858) (xy 89.21167 -517.015357)
			(xy 89.203749 -517.128633) (xy 89.187946 -517.241081) (xy 89.164337 -517.352152) (xy 89.133037 -517.461307)
			(xy 89.0942 -517.568012) (xy 89.048014 -517.671747) (xy 88.994704 -517.772009) (xy 88.93453 -517.868307)
			(xy 88.867785 -517.960173) (xy 88.794795 -518.04716) (xy 88.715914 -518.128843) (xy 88.631528 -518.204825)
			(xy 88.542047 -518.274735) (xy 88.447907 -518.338233) (xy 88.349567 -518.39501) (xy 88.247507 -518.444788)
			(xy 88.142222 -518.487326) (xy 88.034227 -518.522416) (xy 87.924047 -518.549887) (xy 87.812219 -518.569605)
			(xy 87.699288 -518.581475) (xy 87.585804 -518.585438) (xy 87.47232 -518.581475) (xy 87.359389 -518.569605)
			(xy 87.247561 -518.549887) (xy 87.137381 -518.522416) (xy 87.029386 -518.487326) (xy 86.924101 -518.444788)
			(xy 86.822041 -518.39501) (xy 86.723701 -518.338233) (xy 86.629561 -518.274735) (xy 86.54008 -518.204825)
			(xy 86.455694 -518.128843) (xy 86.376813 -518.04716) (xy 86.303823 -517.960173) (xy 86.237078 -517.868307)
			(xy 86.176904 -517.772009) (xy 86.123594 -517.671747) (xy 86.077408 -517.568012) (xy 86.038571 -517.461307)
			(xy 86.007271 -517.352152) (xy 85.983662 -517.241081) (xy 85.967859 -517.128633) (xy 85.959938 -517.015357)
			(xy 82.568632 -517.015357) (xy 82.644227 -517.194054) (xy 82.714764 -517.38135) (xy 82.777752 -517.571318)
			(xy 82.833089 -517.763654) (xy 82.880686 -517.95805) (xy 82.920467 -518.154195) (xy 82.952369 -518.351774)
			(xy 82.97634 -518.550471) (xy 82.992342 -518.749969) (xy 83.000349 -518.949947) (xy 83.00085 -519.050016)
			(xy 83.000349 -519.150085) (xy 82.992342 -519.350063) (xy 82.97634 -519.549561) (xy 82.952369 -519.748258)
			(xy 82.920467 -519.945837) (xy 82.880686 -520.141982) (xy 82.833089 -520.336378) (xy 82.777752 -520.528714)
			(xy 82.714764 -520.718682) (xy 82.644227 -520.905978) (xy 82.566252 -521.090302) (xy 82.480965 -521.271358)
			(xy 82.388502 -521.448857) (xy 82.289011 -521.622515) (xy 82.182652 -521.792053) (xy 82.069596 -521.957199)
			(xy 81.950022 -522.117691) (xy 81.824123 -522.273269) (xy 81.6921 -522.423686) (xy 81.554164 -522.5687)
			(xy 81.410537 -522.70808) (xy 81.261449 -522.841601) (xy 81.107138 -522.96905) (xy 80.947851 -523.090224)
			(xy 80.783843 -523.204927) (xy 80.615378 -523.312977) (xy 80.442725 -523.4142) (xy 80.26616 -523.508434)
			(xy 80.085966 -523.595528) (xy 79.902431 -523.675344) (xy 79.715851 -523.747752) (xy 79.526522 -523.812637)
			(xy 79.334749 -523.869895) (xy 79.140839 -523.919434) (xy 78.945102 -523.961176) (xy 78.747852 -523.995053)
			(xy 78.549404 -524.021011) (xy 78.350077 -524.039008) (xy 78.150189 -524.049016) (xy 77.950061 -524.051018)
			(xy 77.750013 -524.045012) (xy 77.550365 -524.031007) (xy 77.351438 -524.009025) (xy 77.153549 -523.979101)
			(xy 76.957016 -523.941284) (xy 76.762154 -523.895635) (xy 76.569274 -523.842225) (xy 76.378685 -523.781141)
			(xy 76.190693 -523.712481) (xy 76.005598 -523.636354) (xy 75.823698 -523.552883) (xy 75.645282 -523.4622)
			(xy 75.470638 -523.364452) (xy 75.300045 -523.259795) (xy 75.133775 -523.148396) (xy 74.972096 -523.030434)
			(xy 74.815265 -522.906098) (xy 74.663535 -522.775586) (xy 74.517148 -522.639109) (xy 74.376339 -522.496883)
			(xy 74.241332 -522.349138) (xy 74.112345 -522.19611) (xy 73.989584 -522.038043) (xy 73.873246 -521.875192)
			(xy 73.763516 -521.707816) (xy 73.660571 -521.536184) (xy 73.564575 -521.36057) (xy 73.475682 -521.181257)
			(xy 73.394035 -520.99853) (xy 73.319763 -520.812683) (xy 73.252987 -520.624013) (xy 73.193813 -520.432823)
			(xy 73.142336 -520.239418) (xy 73.098638 -520.044109) (xy 73.06279 -519.847207) (xy 73.034848 -519.649029)
			(xy 73.014857 -519.449892) (xy 73.00285 -519.250114) (xy 72.998846 -519.050016) (xy 52.974748 -519.050016)
			(xy 52.974748 -519.84656) (xy 51.322732 -519.84656) (xy 51.322732 -518.194544) (xy 36.344981 -518.194544)
			(xy 36.315846 -518.241598) (xy 36.263477 -518.310945) (xy 36.204933 -518.375165) (xy 36.140713 -518.433709)
			(xy 36.071366 -518.486078) (xy 35.997482 -518.531825) (xy 35.919693 -518.570559) (xy 35.838661 -518.601951)
			(xy 35.755079 -518.625732) (xy 35.669659 -518.6417) (xy 35.58313 -518.649718) (xy 35.49623 -518.649718)
			(xy 35.409701 -518.6417) (xy 35.324281 -518.625732) (xy 35.240699 -518.601951) (xy 35.159667 -518.570559)
			(xy 35.081878 -518.531825) (xy 35.007994 -518.486078) (xy 34.938647 -518.433709) (xy 34.874427 -518.375165)
			(xy 34.815883 -518.310945) (xy 34.763514 -518.241598) (xy 34.717767 -518.167714) (xy 34.679033 -518.089925)
			(xy 34.647641 -518.008893) (xy 34.62386 -517.925311) (xy 34.607892 -517.839891) (xy 34.599874 -517.753362)
			(xy 31.399486 -517.753362) (xy 31.391468 -517.839891) (xy 31.3755 -517.925311) (xy 31.351719 -518.008893)
			(xy 31.320327 -518.089925) (xy 31.281593 -518.167714) (xy 31.235846 -518.241598) (xy 31.183477 -518.310945)
			(xy 31.124933 -518.375165) (xy 31.060713 -518.433709) (xy 30.991366 -518.486078) (xy 30.917482 -518.531825)
			(xy 30.839693 -518.570559) (xy 30.758661 -518.601951) (xy 30.675079 -518.625732) (xy 30.589659 -518.6417)
			(xy 30.50313 -518.649718) (xy 30.41623 -518.649718) (xy 30.329701 -518.6417) (xy 30.244281 -518.625732)
			(xy 30.160699 -518.601951) (xy 30.079667 -518.570559) (xy 30.001878 -518.531825) (xy 29.927994 -518.486078)
			(xy 29.858647 -518.433709) (xy 29.794427 -518.375165) (xy 29.735883 -518.310945) (xy 29.683514 -518.241598)
			(xy 29.637767 -518.167714) (xy 29.599033 -518.089925) (xy 29.567641 -518.008893) (xy 29.54386 -517.925311)
			(xy 29.527892 -517.839891) (xy 29.519874 -517.753362) (xy 6.707632 -517.753362) (xy 6.707632 -517.97712)
			(xy 4.852416 -517.97712) (xy 4.852416 -516.122412) (xy 1.525016 -516.122412) (xy 1.525016 -520.04976)
			(xy 6.671831 -520.04976) (xy 6.675786 -519.957923) (xy 6.687621 -519.866766) (xy 6.707248 -519.776963)
			(xy 6.734522 -519.689181) (xy 6.769242 -519.604067) (xy 6.81115 -519.522254) (xy 6.859936 -519.444346)
			(xy 6.915239 -519.370921) (xy 6.976649 -519.302521) (xy 7.043711 -519.239654) (xy 7.11593 -519.182784)
			(xy 7.19277 -519.132333) (xy 7.273663 -519.088674) (xy 7.358009 -519.052131) (xy 7.445185 -519.022974)
			(xy 7.534544 -519.00142) (xy 7.625425 -518.987626) (xy 7.717156 -518.981696) (xy 7.809057 -518.983674)
			(xy 7.900448 -518.993545) (xy 7.990652 -519.011235) (xy 8.079001 -519.036615) (xy 8.142942 -519.061107)
			(xy 47.82311 -519.061107) (xy 47.82311 -518.979997) (xy 47.83106 -518.899278) (xy 47.846883 -518.819727)
			(xy 47.870428 -518.742111) (xy 47.901467 -518.667175) (xy 47.939702 -518.595643) (xy 47.984764 -518.528203)
			(xy 48.036219 -518.465504) (xy 48.093572 -518.408151) (xy 48.156271 -518.356696) (xy 48.223711 -518.311634)
			(xy 48.295243 -518.273399) (xy 48.370179 -518.24236) (xy 48.447795 -518.218815) (xy 48.527346 -518.202992)
			(xy 48.608065 -518.195042) (xy 48.689175 -518.195042) (xy 48.769894 -518.202992) (xy 48.849445 -518.218815)
			(xy 48.927061 -518.24236) (xy 49.001997 -518.273399) (xy 49.073529 -518.311634) (xy 49.140969 -518.356696)
			(xy 49.203668 -518.408151) (xy 49.261021 -518.465504) (xy 49.312476 -518.528203) (xy 49.357538 -518.595643)
			(xy 49.395773 -518.667175) (xy 49.426812 -518.742111) (xy 49.450357 -518.819727) (xy 49.46618 -518.899278)
			(xy 49.47413 -518.979997) (xy 49.474628 -519.020552) (xy 49.47413 -519.061107) (xy 49.46618 -519.141826)
			(xy 49.450357 -519.221377) (xy 49.426812 -519.298993) (xy 49.395773 -519.373929) (xy 49.357538 -519.445461)
			(xy 49.312476 -519.512901) (xy 49.261021 -519.5756) (xy 49.203668 -519.632953) (xy 49.140969 -519.684408)
			(xy 49.073529 -519.72947) (xy 49.001997 -519.767705) (xy 48.927061 -519.798744) (xy 48.849445 -519.822289)
			(xy 48.769894 -519.838112) (xy 48.689175 -519.846062) (xy 48.608065 -519.846062) (xy 48.527346 -519.838112)
			(xy 48.447795 -519.822289) (xy 48.370179 -519.798744) (xy 48.295243 -519.767705) (xy 48.223711 -519.72947)
			(xy 48.156271 -519.684408) (xy 48.093572 -519.632953) (xy 48.036219 -519.5756) (xy 47.984764 -519.512901)
			(xy 47.939702 -519.445461) (xy 47.901467 -519.373929) (xy 47.870428 -519.298993) (xy 47.846883 -519.221377)
			(xy 47.83106 -519.141826) (xy 47.82311 -519.061107) (xy 8.142942 -519.061107) (xy 8.164841 -519.069495)
			(xy 8.247537 -519.109633) (xy 8.326477 -519.156732) (xy 8.401075 -519.210442) (xy 8.470781 -519.270366)
			(xy 8.535076 -519.33606) (xy 8.593487 -519.407038) (xy 8.645579 -519.482775) (xy 8.690968 -519.56271)
			(xy 8.729318 -519.64625) (xy 8.760343 -519.732778) (xy 8.783816 -519.821653) (xy 8.799562 -519.912217)
			(xy 8.807464 -520.003799) (xy 8.807958 -520.04976) (xy 8.807464 -520.095721) (xy 8.799562 -520.187303)
			(xy 8.783816 -520.277867) (xy 8.779724 -520.293362) (xy 29.519874 -520.293362) (xy 29.519874 -520.206462)
			(xy 29.527892 -520.119933) (xy 29.54386 -520.034513) (xy 29.567641 -519.950931) (xy 29.599033 -519.869899)
			(xy 29.637767 -519.79211) (xy 29.683514 -519.718226) (xy 29.735883 -519.648879) (xy 29.794427 -519.584659)
			(xy 29.858647 -519.526115) (xy 29.927994 -519.473746) (xy 30.001878 -519.427999) (xy 30.079667 -519.389265)
			(xy 30.160699 -519.357873) (xy 30.244281 -519.334092) (xy 30.329701 -519.318124) (xy 30.41623 -519.310106)
			(xy 30.50313 -519.310106) (xy 30.589659 -519.318124) (xy 30.675079 -519.334092) (xy 30.758661 -519.357873)
			(xy 30.839693 -519.389265) (xy 30.917482 -519.427999) (xy 30.991366 -519.473746) (xy 31.060713 -519.526115)
			(xy 31.124933 -519.584659) (xy 31.183477 -519.648879) (xy 31.235846 -519.718226) (xy 31.281593 -519.79211)
			(xy 31.320327 -519.869899) (xy 31.351719 -519.950931) (xy 31.3755 -520.034513) (xy 31.391468 -520.119933)
			(xy 31.399486 -520.206462) (xy 31.399988 -520.249912) (xy 31.399486 -520.293362) (xy 34.599874 -520.293362)
			(xy 34.599874 -520.206462) (xy 34.607892 -520.119933) (xy 34.62386 -520.034513) (xy 34.647641 -519.950931)
			(xy 34.679033 -519.869899) (xy 34.717767 -519.79211) (xy 34.763514 -519.718226) (xy 34.815883 -519.648879)
			(xy 34.874427 -519.584659) (xy 34.938647 -519.526115) (xy 35.007994 -519.473746) (xy 35.081878 -519.427999)
			(xy 35.159667 -519.389265) (xy 35.240699 -519.357873) (xy 35.324281 -519.334092) (xy 35.409701 -519.318124)
			(xy 35.49623 -519.310106) (xy 35.58313 -519.310106) (xy 35.669659 -519.318124) (xy 35.755079 -519.334092)
			(xy 35.838661 -519.357873) (xy 35.919693 -519.389265) (xy 35.997482 -519.427999) (xy 36.071366 -519.473746)
			(xy 36.140713 -519.526115) (xy 36.204933 -519.584659) (xy 36.263477 -519.648879) (xy 36.315846 -519.718226)
			(xy 36.361593 -519.79211) (xy 36.400327 -519.869899) (xy 36.431719 -519.950931) (xy 36.4555 -520.034513)
			(xy 36.471468 -520.119933) (xy 36.479486 -520.206462) (xy 36.479988 -520.249912) (xy 36.479486 -520.293362)
			(xy 36.471468 -520.379891) (xy 36.4555 -520.465311) (xy 36.431719 -520.548893) (xy 36.400327 -520.629925)
			(xy 36.361593 -520.707714) (xy 36.315846 -520.781598) (xy 36.263477 -520.850945) (xy 36.204933 -520.915165)
			(xy 36.140713 -520.973709) (xy 36.071366 -521.026078) (xy 36.055684 -521.035788) (xy 55.897524 -521.035788)
			(xy 55.901595 -520.980166) (xy 55.913721 -520.925729) (xy 55.933644 -520.873638) (xy 55.96094 -520.825003)
			(xy 55.995026 -520.78086) (xy 56.035175 -520.742151) (xy 56.080533 -520.7097) (xy 56.130133 -520.684199)
			(xy 56.182917 -520.666192) (xy 56.23776 -520.656062) (xy 56.293494 -520.654025) (xy 56.348931 -520.660125)
			(xy 56.402888 -520.674231) (xy 56.454217 -520.696043) (xy 56.501823 -520.725097) (xy 56.544691 -520.760772)
			(xy 56.581908 -520.802309) (xy 56.612681 -520.848822) (xy 56.636353 -520.899319) (xy 56.652421 -520.952726)
			(xy 56.660541 -521.007902) (xy 56.66105 -521.035788) (xy 57.167524 -521.035788) (xy 57.171595 -520.980166)
			(xy 57.183721 -520.925729) (xy 57.203644 -520.873638) (xy 57.23094 -520.825003) (xy 57.265026 -520.78086)
			(xy 57.305175 -520.742151) (xy 57.350533 -520.7097) (xy 57.400133 -520.684199) (xy 57.452917 -520.666192)
			(xy 57.50776 -520.656062) (xy 57.563494 -520.654025) (xy 57.618931 -520.660125) (xy 57.672888 -520.674231)
			(xy 57.724217 -520.696043) (xy 57.771823 -520.725097) (xy 57.814691 -520.760772) (xy 57.851908 -520.802309)
			(xy 57.882681 -520.848822) (xy 57.906353 -520.899319) (xy 57.922421 -520.952726) (xy 57.930541 -521.007902)
			(xy 57.93105 -521.035788) (xy 58.429396 -521.035788) (xy 58.433467 -520.980166) (xy 58.445593 -520.925729)
			(xy 58.465516 -520.873638) (xy 58.492812 -520.825003) (xy 58.526898 -520.78086) (xy 58.567047 -520.742151)
			(xy 58.612405 -520.7097) (xy 58.662005 -520.684199) (xy 58.714789 -520.666192) (xy 58.769632 -520.656062)
			(xy 58.825366 -520.654025) (xy 58.880803 -520.660125) (xy 58.93476 -520.674231) (xy 58.986089 -520.696043)
			(xy 59.033695 -520.725097) (xy 59.076563 -520.760772) (xy 59.11378 -520.802309) (xy 59.144553 -520.848822)
			(xy 59.168225 -520.899319) (xy 59.184293 -520.952726) (xy 59.192413 -521.007902) (xy 59.192922 -521.035788)
			(xy 59.699396 -521.035788) (xy 59.703467 -520.980166) (xy 59.715593 -520.925729) (xy 59.735516 -520.873638)
			(xy 59.762812 -520.825003) (xy 59.796898 -520.78086) (xy 59.837047 -520.742151) (xy 59.882405 -520.7097)
			(xy 59.932005 -520.684199) (xy 59.984789 -520.666192) (xy 60.039632 -520.656062) (xy 60.095366 -520.654025)
			(xy 60.150803 -520.660125) (xy 60.20476 -520.674231) (xy 60.256089 -520.696043) (xy 60.303695 -520.725097)
			(xy 60.346563 -520.760772) (xy 60.38378 -520.802309) (xy 60.414553 -520.848822) (xy 60.438225 -520.899319)
			(xy 60.454293 -520.952726) (xy 60.462413 -521.007902) (xy 60.462922 -521.035788) (xy 61.23381 -521.035788)
			(xy 61.237881 -520.980166) (xy 61.250007 -520.925729) (xy 61.26993 -520.873638) (xy 61.297226 -520.825003)
			(xy 61.331312 -520.78086) (xy 61.371461 -520.742151) (xy 61.416819 -520.7097) (xy 61.466419 -520.684199)
			(xy 61.519203 -520.666192) (xy 61.574046 -520.656062) (xy 61.62978 -520.654025) (xy 61.685217 -520.660125)
			(xy 61.739174 -520.674231) (xy 61.790503 -520.696043) (xy 61.838109 -520.725097) (xy 61.880977 -520.760772)
			(xy 61.918194 -520.802309) (xy 61.948967 -520.848822) (xy 61.972639 -520.899319) (xy 61.988707 -520.952726)
			(xy 61.996827 -521.007902) (xy 61.997336 -521.035788) (xy 62.50381 -521.035788) (xy 62.507881 -520.980166)
			(xy 62.520007 -520.925729) (xy 62.53993 -520.873638) (xy 62.567226 -520.825003) (xy 62.601312 -520.78086)
			(xy 62.641461 -520.742151) (xy 62.686819 -520.7097) (xy 62.736419 -520.684199) (xy 62.789203 -520.666192)
			(xy 62.844046 -520.656062) (xy 62.89978 -520.654025) (xy 62.955217 -520.660125) (xy 63.009174 -520.674231)
			(xy 63.060503 -520.696043) (xy 63.108109 -520.725097) (xy 63.150977 -520.760772) (xy 63.188194 -520.802309)
			(xy 63.218967 -520.848822) (xy 63.242639 -520.899319) (xy 63.258707 -520.952726) (xy 63.266827 -521.007902)
			(xy 63.267336 -521.035788) (xy 64.47358 -521.035788) (xy 64.477651 -520.980166) (xy 64.489777 -520.925729)
			(xy 64.5097 -520.873638) (xy 64.536996 -520.825003) (xy 64.571082 -520.78086) (xy 64.611231 -520.742151)
			(xy 64.656589 -520.7097) (xy 64.706189 -520.684199) (xy 64.758973 -520.666192) (xy 64.813816 -520.656062)
			(xy 64.86955 -520.654025) (xy 64.924987 -520.660125) (xy 64.978944 -520.674231) (xy 65.030273 -520.696043)
			(xy 65.077879 -520.725097) (xy 65.120747 -520.760772) (xy 65.157964 -520.802309) (xy 65.188737 -520.848822)
			(xy 65.212409 -520.899319) (xy 65.228477 -520.952726) (xy 65.236597 -521.007902) (xy 65.237106 -521.035788)
			(xy 65.74358 -521.035788) (xy 65.747651 -520.980166) (xy 65.759777 -520.925729) (xy 65.7797 -520.873638)
			(xy 65.806996 -520.825003) (xy 65.841082 -520.78086) (xy 65.881231 -520.742151) (xy 65.926589 -520.7097)
			(xy 65.976189 -520.684199) (xy 66.028973 -520.666192) (xy 66.083816 -520.656062) (xy 66.13955 -520.654025)
			(xy 66.194987 -520.660125) (xy 66.248944 -520.674231) (xy 66.300273 -520.696043) (xy 66.347879 -520.725097)
			(xy 66.390747 -520.760772) (xy 66.427964 -520.802309) (xy 66.458737 -520.848822) (xy 66.482409 -520.899319)
			(xy 66.498477 -520.952726) (xy 66.506597 -521.007902) (xy 66.507106 -521.035788) (xy 67.465192 -521.035788)
			(xy 67.469263 -520.980166) (xy 67.481389 -520.925729) (xy 67.501312 -520.873638) (xy 67.528608 -520.825003)
			(xy 67.562694 -520.78086) (xy 67.602843 -520.742151) (xy 67.648201 -520.7097) (xy 67.697801 -520.684199)
			(xy 67.750585 -520.666192) (xy 67.805428 -520.656062) (xy 67.861162 -520.654025) (xy 67.916599 -520.660125)
			(xy 67.970556 -520.674231) (xy 68.021885 -520.696043) (xy 68.069491 -520.725097) (xy 68.112359 -520.760772)
			(xy 68.149576 -520.802309) (xy 68.180349 -520.848822) (xy 68.204021 -520.899319) (xy 68.220089 -520.952726)
			(xy 68.228209 -521.007902) (xy 68.228718 -521.035788) (xy 68.735192 -521.035788) (xy 68.739263 -520.980166)
			(xy 68.751389 -520.925729) (xy 68.771312 -520.873638) (xy 68.798608 -520.825003) (xy 68.832694 -520.78086)
			(xy 68.872843 -520.742151) (xy 68.918201 -520.7097) (xy 68.967801 -520.684199) (xy 69.020585 -520.666192)
			(xy 69.075428 -520.656062) (xy 69.131162 -520.654025) (xy 69.186599 -520.660125) (xy 69.240556 -520.674231)
			(xy 69.291885 -520.696043) (xy 69.339491 -520.725097) (xy 69.382359 -520.760772) (xy 69.419576 -520.802309)
			(xy 69.450349 -520.848822) (xy 69.474021 -520.899319) (xy 69.490089 -520.952726) (xy 69.498209 -521.007902)
			(xy 69.498718 -521.035788) (xy 69.498209 -521.063674) (xy 69.490089 -521.11885) (xy 69.474021 -521.172257)
			(xy 69.450349 -521.222754) (xy 69.419576 -521.269267) (xy 69.382359 -521.310804) (xy 69.339491 -521.346479)
			(xy 69.291885 -521.375533) (xy 69.240556 -521.397345) (xy 69.186599 -521.411451) (xy 69.131162 -521.417551)
			(xy 69.075428 -521.415514) (xy 69.020585 -521.405384) (xy 68.967801 -521.387377) (xy 68.918201 -521.361876)
			(xy 68.872843 -521.329425) (xy 68.832694 -521.290716) (xy 68.798608 -521.246573) (xy 68.771312 -521.197938)
			(xy 68.751389 -521.145847) (xy 68.739263 -521.09141) (xy 68.735192 -521.035788) (xy 68.228718 -521.035788)
			(xy 68.228209 -521.063674) (xy 68.220089 -521.11885) (xy 68.204021 -521.172257) (xy 68.180349 -521.222754)
			(xy 68.149576 -521.269267) (xy 68.112359 -521.310804) (xy 68.069491 -521.346479) (xy 68.021885 -521.375533)
			(xy 67.970556 -521.397345) (xy 67.916599 -521.411451) (xy 67.861162 -521.417551) (xy 67.805428 -521.415514)
			(xy 67.750585 -521.405384) (xy 67.697801 -521.387377) (xy 67.648201 -521.361876) (xy 67.602843 -521.329425)
			(xy 67.562694 -521.290716) (xy 67.528608 -521.246573) (xy 67.501312 -521.197938) (xy 67.481389 -521.145847)
			(xy 67.469263 -521.09141) (xy 67.465192 -521.035788) (xy 66.507106 -521.035788) (xy 66.506597 -521.063674)
			(xy 66.498477 -521.11885) (xy 66.482409 -521.172257) (xy 66.458737 -521.222754) (xy 66.427964 -521.269267)
			(xy 66.390747 -521.310804) (xy 66.347879 -521.346479) (xy 66.300273 -521.375533) (xy 66.248944 -521.397345)
			(xy 66.194987 -521.411451) (xy 66.13955 -521.417551) (xy 66.083816 -521.415514) (xy 66.028973 -521.405384)
			(xy 65.976189 -521.387377) (xy 65.926589 -521.361876) (xy 65.881231 -521.329425) (xy 65.841082 -521.290716)
			(xy 65.806996 -521.246573) (xy 65.7797 -521.197938) (xy 65.759777 -521.145847) (xy 65.747651 -521.09141)
			(xy 65.74358 -521.035788) (xy 65.237106 -521.035788) (xy 65.236597 -521.063674) (xy 65.228477 -521.11885)
			(xy 65.212409 -521.172257) (xy 65.188737 -521.222754) (xy 65.157964 -521.269267) (xy 65.120747 -521.310804)
			(xy 65.077879 -521.346479) (xy 65.030273 -521.375533) (xy 64.978944 -521.397345) (xy 64.924987 -521.411451)
			(xy 64.86955 -521.417551) (xy 64.813816 -521.415514) (xy 64.758973 -521.405384) (xy 64.706189 -521.387377)
			(xy 64.656589 -521.361876) (xy 64.611231 -521.329425) (xy 64.571082 -521.290716) (xy 64.536996 -521.246573)
			(xy 64.5097 -521.197938) (xy 64.489777 -521.145847) (xy 64.477651 -521.09141) (xy 64.47358 -521.035788)
			(xy 63.267336 -521.035788) (xy 63.266827 -521.063674) (xy 63.258707 -521.11885) (xy 63.242639 -521.172257)
			(xy 63.218967 -521.222754) (xy 63.188194 -521.269267) (xy 63.150977 -521.310804) (xy 63.108109 -521.346479)
			(xy 63.060503 -521.375533) (xy 63.009174 -521.397345) (xy 62.955217 -521.411451) (xy 62.89978 -521.417551)
			(xy 62.844046 -521.415514) (xy 62.789203 -521.405384) (xy 62.736419 -521.387377) (xy 62.686819 -521.361876)
			(xy 62.641461 -521.329425) (xy 62.601312 -521.290716) (xy 62.567226 -521.246573) (xy 62.53993 -521.197938)
			(xy 62.520007 -521.145847) (xy 62.507881 -521.09141) (xy 62.50381 -521.035788) (xy 61.997336 -521.035788)
			(xy 61.996827 -521.063674) (xy 61.988707 -521.11885) (xy 61.972639 -521.172257) (xy 61.948967 -521.222754)
			(xy 61.918194 -521.269267) (xy 61.880977 -521.310804) (xy 61.838109 -521.346479) (xy 61.790503 -521.375533)
			(xy 61.739174 -521.397345) (xy 61.685217 -521.411451) (xy 61.62978 -521.417551) (xy 61.574046 -521.415514)
			(xy 61.519203 -521.405384) (xy 61.466419 -521.387377) (xy 61.416819 -521.361876) (xy 61.371461 -521.329425)
			(xy 61.331312 -521.290716) (xy 61.297226 -521.246573) (xy 61.26993 -521.197938) (xy 61.250007 -521.145847)
			(xy 61.237881 -521.09141) (xy 61.23381 -521.035788) (xy 60.462922 -521.035788) (xy 60.462413 -521.063674)
			(xy 60.454293 -521.11885) (xy 60.438225 -521.172257) (xy 60.414553 -521.222754) (xy 60.38378 -521.269267)
			(xy 60.346563 -521.310804) (xy 60.303695 -521.346479) (xy 60.256089 -521.375533) (xy 60.20476 -521.397345)
			(xy 60.150803 -521.411451) (xy 60.095366 -521.417551) (xy 60.039632 -521.415514) (xy 59.984789 -521.405384)
			(xy 59.932005 -521.387377) (xy 59.882405 -521.361876) (xy 59.837047 -521.329425) (xy 59.796898 -521.290716)
			(xy 59.762812 -521.246573) (xy 59.735516 -521.197938) (xy 59.715593 -521.145847) (xy 59.703467 -521.09141)
			(xy 59.699396 -521.035788) (xy 59.192922 -521.035788) (xy 59.192413 -521.063674) (xy 59.184293 -521.11885)
			(xy 59.168225 -521.172257) (xy 59.144553 -521.222754) (xy 59.11378 -521.269267) (xy 59.076563 -521.310804)
			(xy 59.033695 -521.346479) (xy 58.986089 -521.375533) (xy 58.93476 -521.397345) (xy 58.880803 -521.411451)
			(xy 58.825366 -521.417551) (xy 58.769632 -521.415514) (xy 58.714789 -521.405384) (xy 58.662005 -521.387377)
			(xy 58.612405 -521.361876) (xy 58.567047 -521.329425) (xy 58.526898 -521.290716) (xy 58.492812 -521.246573)
			(xy 58.465516 -521.197938) (xy 58.445593 -521.145847) (xy 58.433467 -521.09141) (xy 58.429396 -521.035788)
			(xy 57.93105 -521.035788) (xy 57.930541 -521.063674) (xy 57.922421 -521.11885) (xy 57.906353 -521.172257)
			(xy 57.882681 -521.222754) (xy 57.851908 -521.269267) (xy 57.814691 -521.310804) (xy 57.771823 -521.346479)
			(xy 57.724217 -521.375533) (xy 57.672888 -521.397345) (xy 57.618931 -521.411451) (xy 57.563494 -521.417551)
			(xy 57.50776 -521.415514) (xy 57.452917 -521.405384) (xy 57.400133 -521.387377) (xy 57.350533 -521.361876)
			(xy 57.305175 -521.329425) (xy 57.265026 -521.290716) (xy 57.23094 -521.246573) (xy 57.203644 -521.197938)
			(xy 57.183721 -521.145847) (xy 57.171595 -521.09141) (xy 57.167524 -521.035788) (xy 56.66105 -521.035788)
			(xy 56.660541 -521.063674) (xy 56.652421 -521.11885) (xy 56.636353 -521.172257) (xy 56.612681 -521.222754)
			(xy 56.581908 -521.269267) (xy 56.544691 -521.310804) (xy 56.501823 -521.346479) (xy 56.454217 -521.375533)
			(xy 56.402888 -521.397345) (xy 56.348931 -521.411451) (xy 56.293494 -521.417551) (xy 56.23776 -521.415514)
			(xy 56.182917 -521.405384) (xy 56.130133 -521.387377) (xy 56.080533 -521.361876) (xy 56.035175 -521.329425)
			(xy 55.995026 -521.290716) (xy 55.96094 -521.246573) (xy 55.933644 -521.197938) (xy 55.913721 -521.145847)
			(xy 55.901595 -521.09141) (xy 55.897524 -521.035788) (xy 36.055684 -521.035788) (xy 35.997482 -521.071825)
			(xy 35.919693 -521.110559) (xy 35.838661 -521.141951) (xy 35.755079 -521.165732) (xy 35.669659 -521.1817)
			(xy 35.58313 -521.189718) (xy 35.49623 -521.189718) (xy 35.409701 -521.1817) (xy 35.324281 -521.165732)
			(xy 35.240699 -521.141951) (xy 35.159667 -521.110559) (xy 35.081878 -521.071825) (xy 35.007994 -521.026078)
			(xy 34.938647 -520.973709) (xy 34.874427 -520.915165) (xy 34.815883 -520.850945) (xy 34.763514 -520.781598)
			(xy 34.717767 -520.707714) (xy 34.679033 -520.629925) (xy 34.647641 -520.548893) (xy 34.62386 -520.465311)
			(xy 34.607892 -520.379891) (xy 34.599874 -520.293362) (xy 31.399486 -520.293362) (xy 31.391468 -520.379891)
			(xy 31.3755 -520.465311) (xy 31.351719 -520.548893) (xy 31.320327 -520.629925) (xy 31.281593 -520.707714)
			(xy 31.235846 -520.781598) (xy 31.183477 -520.850945) (xy 31.124933 -520.915165) (xy 31.060713 -520.973709)
			(xy 30.991366 -521.026078) (xy 30.917482 -521.071825) (xy 30.839693 -521.110559) (xy 30.758661 -521.141951)
			(xy 30.675079 -521.165732) (xy 30.589659 -521.1817) (xy 30.50313 -521.189718) (xy 30.41623 -521.189718)
			(xy 30.329701 -521.1817) (xy 30.244281 -521.165732) (xy 30.160699 -521.141951) (xy 30.079667 -521.110559)
			(xy 30.001878 -521.071825) (xy 29.927994 -521.026078) (xy 29.858647 -520.973709) (xy 29.794427 -520.915165)
			(xy 29.735883 -520.850945) (xy 29.683514 -520.781598) (xy 29.637767 -520.707714) (xy 29.599033 -520.629925)
			(xy 29.567641 -520.548893) (xy 29.54386 -520.465311) (xy 29.527892 -520.379891) (xy 29.519874 -520.293362)
			(xy 8.779724 -520.293362) (xy 8.760343 -520.366742) (xy 8.729318 -520.45327) (xy 8.690968 -520.53681)
			(xy 8.645579 -520.616745) (xy 8.593487 -520.692482) (xy 8.535076 -520.76346) (xy 8.470781 -520.829154)
			(xy 8.401075 -520.889078) (xy 8.326477 -520.942788) (xy 8.247537 -520.989887) (xy 8.164841 -521.030025)
			(xy 8.079001 -521.062905) (xy 7.990652 -521.088285) (xy 7.900448 -521.105975) (xy 7.809057 -521.115846)
			(xy 7.717156 -521.117824) (xy 7.625425 -521.111894) (xy 7.534544 -521.0981) (xy 7.445185 -521.076546)
			(xy 7.358009 -521.047389) (xy 7.273663 -521.010846) (xy 7.19277 -520.967187) (xy 7.11593 -520.916736)
			(xy 7.043711 -520.859866) (xy 6.976649 -520.796999) (xy 6.915239 -520.728599) (xy 6.859936 -520.655174)
			(xy 6.81115 -520.577266) (xy 6.769242 -520.495453) (xy 6.734522 -520.410339) (xy 6.707248 -520.322557)
			(xy 6.687621 -520.232754) (xy 6.675786 -520.141597) (xy 6.671831 -520.04976) (xy 1.525016 -520.04976)
			(xy 1.525016 -522.833362) (xy 29.519874 -522.833362) (xy 29.519874 -522.746462) (xy 29.527892 -522.659933)
			(xy 29.54386 -522.574513) (xy 29.567641 -522.490931) (xy 29.599033 -522.409899) (xy 29.637767 -522.33211)
			(xy 29.683514 -522.258226) (xy 29.735883 -522.188879) (xy 29.794427 -522.124659) (xy 29.858647 -522.066115)
			(xy 29.927994 -522.013746) (xy 30.001878 -521.967999) (xy 30.079667 -521.929265) (xy 30.160699 -521.897873)
			(xy 30.244281 -521.874092) (xy 30.329701 -521.858124) (xy 30.41623 -521.850106) (xy 30.50313 -521.850106)
			(xy 30.589659 -521.858124) (xy 30.675079 -521.874092) (xy 30.758661 -521.897873) (xy 30.839693 -521.929265)
			(xy 30.917482 -521.967999) (xy 30.991366 -522.013746) (xy 31.060713 -522.066115) (xy 31.124933 -522.124659)
			(xy 31.183477 -522.188879) (xy 31.235846 -522.258226) (xy 31.281593 -522.33211) (xy 31.320327 -522.409899)
			(xy 31.351719 -522.490931) (xy 31.3755 -522.574513) (xy 31.391468 -522.659933) (xy 31.399486 -522.746462)
			(xy 31.399988 -522.789912) (xy 31.399486 -522.833362) (xy 34.599874 -522.833362) (xy 34.599874 -522.746462)
			(xy 34.607892 -522.659933) (xy 34.62386 -522.574513) (xy 34.647641 -522.490931) (xy 34.679033 -522.409899)
			(xy 34.717767 -522.33211) (xy 34.763514 -522.258226) (xy 34.815883 -522.188879) (xy 34.874427 -522.124659)
			(xy 34.938647 -522.066115) (xy 35.007994 -522.013746) (xy 35.081878 -521.967999) (xy 35.159667 -521.929265)
			(xy 35.240699 -521.897873) (xy 35.324281 -521.874092) (xy 35.409701 -521.858124) (xy 35.49623 -521.850106)
			(xy 35.58313 -521.850106) (xy 35.669659 -521.858124) (xy 35.755079 -521.874092) (xy 35.838661 -521.897873)
			(xy 35.919693 -521.929265) (xy 35.997482 -521.967999) (xy 36.071366 -522.013746) (xy 36.140713 -522.066115)
			(xy 36.204933 -522.124659) (xy 36.263477 -522.188879) (xy 36.315846 -522.258226) (xy 36.361593 -522.33211)
			(xy 36.400327 -522.409899) (xy 36.431719 -522.490931) (xy 36.4555 -522.574513) (xy 36.471468 -522.659933)
			(xy 36.479486 -522.746462) (xy 36.479988 -522.789912) (xy 36.479486 -522.833362) (xy 36.471468 -522.919891)
			(xy 36.456736 -522.9987) (xy 55.897524 -522.9987) (xy 55.901595 -522.943078) (xy 55.913721 -522.888641)
			(xy 55.933644 -522.83655) (xy 55.96094 -522.787915) (xy 55.995026 -522.743772) (xy 56.035175 -522.705063)
			(xy 56.080533 -522.672612) (xy 56.130133 -522.647111) (xy 56.182917 -522.629104) (xy 56.23776 -522.618974)
			(xy 56.293494 -522.616937) (xy 56.348931 -522.623037) (xy 56.402888 -522.637143) (xy 56.454217 -522.658955)
			(xy 56.501823 -522.688009) (xy 56.544691 -522.723684) (xy 56.581908 -522.765221) (xy 56.612681 -522.811734)
			(xy 56.636353 -522.862231) (xy 56.652421 -522.915638) (xy 56.660541 -522.970814) (xy 56.66105 -522.9987)
			(xy 57.167524 -522.9987) (xy 57.171595 -522.943078) (xy 57.183721 -522.888641) (xy 57.203644 -522.83655)
			(xy 57.23094 -522.787915) (xy 57.265026 -522.743772) (xy 57.305175 -522.705063) (xy 57.350533 -522.672612)
			(xy 57.400133 -522.647111) (xy 57.452917 -522.629104) (xy 57.50776 -522.618974) (xy 57.563494 -522.616937)
			(xy 57.618931 -522.623037) (xy 57.672888 -522.637143) (xy 57.724217 -522.658955) (xy 57.771823 -522.688009)
			(xy 57.814691 -522.723684) (xy 57.851908 -522.765221) (xy 57.882681 -522.811734) (xy 57.906353 -522.862231)
			(xy 57.922421 -522.915638) (xy 57.930541 -522.970814) (xy 57.93105 -522.9987) (xy 58.429396 -522.9987)
			(xy 58.433467 -522.943078) (xy 58.445593 -522.888641) (xy 58.465516 -522.83655) (xy 58.492812 -522.787915)
			(xy 58.526898 -522.743772) (xy 58.567047 -522.705063) (xy 58.612405 -522.672612) (xy 58.662005 -522.647111)
			(xy 58.714789 -522.629104) (xy 58.769632 -522.618974) (xy 58.825366 -522.616937) (xy 58.880803 -522.623037)
			(xy 58.93476 -522.637143) (xy 58.986089 -522.658955) (xy 59.033695 -522.688009) (xy 59.076563 -522.723684)
			(xy 59.11378 -522.765221) (xy 59.144553 -522.811734) (xy 59.168225 -522.862231) (xy 59.184293 -522.915638)
			(xy 59.192413 -522.970814) (xy 59.192922 -522.9987) (xy 59.699396 -522.9987) (xy 59.703467 -522.943078)
			(xy 59.715593 -522.888641) (xy 59.735516 -522.83655) (xy 59.762812 -522.787915) (xy 59.796898 -522.743772)
			(xy 59.837047 -522.705063) (xy 59.882405 -522.672612) (xy 59.932005 -522.647111) (xy 59.984789 -522.629104)
			(xy 60.039632 -522.618974) (xy 60.095366 -522.616937) (xy 60.150803 -522.623037) (xy 60.20476 -522.637143)
			(xy 60.256089 -522.658955) (xy 60.303695 -522.688009) (xy 60.346563 -522.723684) (xy 60.38378 -522.765221)
			(xy 60.414553 -522.811734) (xy 60.438225 -522.862231) (xy 60.454293 -522.915638) (xy 60.462413 -522.970814)
			(xy 60.462922 -522.9987) (xy 61.23381 -522.9987) (xy 61.237881 -522.943078) (xy 61.250007 -522.888641)
			(xy 61.26993 -522.83655) (xy 61.297226 -522.787915) (xy 61.331312 -522.743772) (xy 61.371461 -522.705063)
			(xy 61.416819 -522.672612) (xy 61.466419 -522.647111) (xy 61.519203 -522.629104) (xy 61.574046 -522.618974)
			(xy 61.62978 -522.616937) (xy 61.685217 -522.623037) (xy 61.739174 -522.637143) (xy 61.790503 -522.658955)
			(xy 61.838109 -522.688009) (xy 61.880977 -522.723684) (xy 61.918194 -522.765221) (xy 61.948967 -522.811734)
			(xy 61.972639 -522.862231) (xy 61.988707 -522.915638) (xy 61.996827 -522.970814) (xy 61.997336 -522.9987)
			(xy 62.50381 -522.9987) (xy 62.507881 -522.943078) (xy 62.520007 -522.888641) (xy 62.53993 -522.83655)
			(xy 62.567226 -522.787915) (xy 62.601312 -522.743772) (xy 62.641461 -522.705063) (xy 62.686819 -522.672612)
			(xy 62.736419 -522.647111) (xy 62.789203 -522.629104) (xy 62.844046 -522.618974) (xy 62.89978 -522.616937)
			(xy 62.955217 -522.623037) (xy 63.009174 -522.637143) (xy 63.060503 -522.658955) (xy 63.108109 -522.688009)
			(xy 63.150977 -522.723684) (xy 63.188194 -522.765221) (xy 63.218967 -522.811734) (xy 63.242639 -522.862231)
			(xy 63.258707 -522.915638) (xy 63.266827 -522.970814) (xy 63.267336 -522.9987) (xy 64.47358 -522.9987)
			(xy 64.477651 -522.943078) (xy 64.489777 -522.888641) (xy 64.5097 -522.83655) (xy 64.536996 -522.787915)
			(xy 64.571082 -522.743772) (xy 64.611231 -522.705063) (xy 64.656589 -522.672612) (xy 64.706189 -522.647111)
			(xy 64.758973 -522.629104) (xy 64.813816 -522.618974) (xy 64.86955 -522.616937) (xy 64.924987 -522.623037)
			(xy 64.978944 -522.637143) (xy 65.030273 -522.658955) (xy 65.077879 -522.688009) (xy 65.120747 -522.723684)
			(xy 65.157964 -522.765221) (xy 65.188737 -522.811734) (xy 65.212409 -522.862231) (xy 65.228477 -522.915638)
			(xy 65.236597 -522.970814) (xy 65.237106 -522.9987) (xy 65.74358 -522.9987) (xy 65.747651 -522.943078)
			(xy 65.759777 -522.888641) (xy 65.7797 -522.83655) (xy 65.806996 -522.787915) (xy 65.841082 -522.743772)
			(xy 65.881231 -522.705063) (xy 65.926589 -522.672612) (xy 65.976189 -522.647111) (xy 66.028973 -522.629104)
			(xy 66.083816 -522.618974) (xy 66.13955 -522.616937) (xy 66.194987 -522.623037) (xy 66.248944 -522.637143)
			(xy 66.300273 -522.658955) (xy 66.347879 -522.688009) (xy 66.390747 -522.723684) (xy 66.427964 -522.765221)
			(xy 66.458737 -522.811734) (xy 66.482409 -522.862231) (xy 66.498477 -522.915638) (xy 66.506597 -522.970814)
			(xy 66.507106 -522.9987) (xy 67.465192 -522.9987) (xy 67.469263 -522.943078) (xy 67.481389 -522.888641)
			(xy 67.501312 -522.83655) (xy 67.528608 -522.787915) (xy 67.562694 -522.743772) (xy 67.602843 -522.705063)
			(xy 67.648201 -522.672612) (xy 67.697801 -522.647111) (xy 67.750585 -522.629104) (xy 67.805428 -522.618974)
			(xy 67.861162 -522.616937) (xy 67.916599 -522.623037) (xy 67.970556 -522.637143) (xy 68.021885 -522.658955)
			(xy 68.069491 -522.688009) (xy 68.112359 -522.723684) (xy 68.149576 -522.765221) (xy 68.180349 -522.811734)
			(xy 68.204021 -522.862231) (xy 68.220089 -522.915638) (xy 68.228209 -522.970814) (xy 68.228718 -522.9987)
			(xy 68.735192 -522.9987) (xy 68.739263 -522.943078) (xy 68.751389 -522.888641) (xy 68.771312 -522.83655)
			(xy 68.798608 -522.787915) (xy 68.832694 -522.743772) (xy 68.872843 -522.705063) (xy 68.918201 -522.672612)
			(xy 68.967801 -522.647111) (xy 69.020585 -522.629104) (xy 69.075428 -522.618974) (xy 69.131162 -522.616937)
			(xy 69.186599 -522.623037) (xy 69.240556 -522.637143) (xy 69.291885 -522.658955) (xy 69.339491 -522.688009)
			(xy 69.382359 -522.723684) (xy 69.419576 -522.765221) (xy 69.450349 -522.811734) (xy 69.474021 -522.862231)
			(xy 69.490089 -522.915638) (xy 69.498209 -522.970814) (xy 69.498718 -522.9987) (xy 69.498209 -523.026586)
			(xy 69.490089 -523.081762) (xy 69.474021 -523.135169) (xy 69.450349 -523.185666) (xy 69.419576 -523.232179)
			(xy 69.382359 -523.273716) (xy 69.339491 -523.309391) (xy 69.291885 -523.338445) (xy 69.240556 -523.360257)
			(xy 69.186599 -523.374363) (xy 69.131162 -523.380463) (xy 69.075428 -523.378426) (xy 69.020585 -523.368296)
			(xy 68.967801 -523.350289) (xy 68.918201 -523.324788) (xy 68.872843 -523.292337) (xy 68.832694 -523.253628)
			(xy 68.798608 -523.209485) (xy 68.771312 -523.16085) (xy 68.751389 -523.108759) (xy 68.739263 -523.054322)
			(xy 68.735192 -522.9987) (xy 68.228718 -522.9987) (xy 68.228209 -523.026586) (xy 68.220089 -523.081762)
			(xy 68.204021 -523.135169) (xy 68.180349 -523.185666) (xy 68.149576 -523.232179) (xy 68.112359 -523.273716)
			(xy 68.069491 -523.309391) (xy 68.021885 -523.338445) (xy 67.970556 -523.360257) (xy 67.916599 -523.374363)
			(xy 67.861162 -523.380463) (xy 67.805428 -523.378426) (xy 67.750585 -523.368296) (xy 67.697801 -523.350289)
			(xy 67.648201 -523.324788) (xy 67.602843 -523.292337) (xy 67.562694 -523.253628) (xy 67.528608 -523.209485)
			(xy 67.501312 -523.16085) (xy 67.481389 -523.108759) (xy 67.469263 -523.054322) (xy 67.465192 -522.9987)
			(xy 66.507106 -522.9987) (xy 66.506597 -523.026586) (xy 66.498477 -523.081762) (xy 66.482409 -523.135169)
			(xy 66.458737 -523.185666) (xy 66.427964 -523.232179) (xy 66.390747 -523.273716) (xy 66.347879 -523.309391)
			(xy 66.300273 -523.338445) (xy 66.248944 -523.360257) (xy 66.194987 -523.374363) (xy 66.13955 -523.380463)
			(xy 66.083816 -523.378426) (xy 66.028973 -523.368296) (xy 65.976189 -523.350289) (xy 65.926589 -523.324788)
			(xy 65.881231 -523.292337) (xy 65.841082 -523.253628) (xy 65.806996 -523.209485) (xy 65.7797 -523.16085)
			(xy 65.759777 -523.108759) (xy 65.747651 -523.054322) (xy 65.74358 -522.9987) (xy 65.237106 -522.9987)
			(xy 65.236597 -523.026586) (xy 65.228477 -523.081762) (xy 65.212409 -523.135169) (xy 65.188737 -523.185666)
			(xy 65.157964 -523.232179) (xy 65.120747 -523.273716) (xy 65.077879 -523.309391) (xy 65.030273 -523.338445)
			(xy 64.978944 -523.360257) (xy 64.924987 -523.374363) (xy 64.86955 -523.380463) (xy 64.813816 -523.378426)
			(xy 64.758973 -523.368296) (xy 64.706189 -523.350289) (xy 64.656589 -523.324788) (xy 64.611231 -523.292337)
			(xy 64.571082 -523.253628) (xy 64.536996 -523.209485) (xy 64.5097 -523.16085) (xy 64.489777 -523.108759)
			(xy 64.477651 -523.054322) (xy 64.47358 -522.9987) (xy 63.267336 -522.9987) (xy 63.266827 -523.026586)
			(xy 63.258707 -523.081762) (xy 63.242639 -523.135169) (xy 63.218967 -523.185666) (xy 63.188194 -523.232179)
			(xy 63.150977 -523.273716) (xy 63.108109 -523.309391) (xy 63.060503 -523.338445) (xy 63.009174 -523.360257)
			(xy 62.955217 -523.374363) (xy 62.89978 -523.380463) (xy 62.844046 -523.378426) (xy 62.789203 -523.368296)
			(xy 62.736419 -523.350289) (xy 62.686819 -523.324788) (xy 62.641461 -523.292337) (xy 62.601312 -523.253628)
			(xy 62.567226 -523.209485) (xy 62.53993 -523.16085) (xy 62.520007 -523.108759) (xy 62.507881 -523.054322)
			(xy 62.50381 -522.9987) (xy 61.997336 -522.9987) (xy 61.996827 -523.026586) (xy 61.988707 -523.081762)
			(xy 61.972639 -523.135169) (xy 61.948967 -523.185666) (xy 61.918194 -523.232179) (xy 61.880977 -523.273716)
			(xy 61.838109 -523.309391) (xy 61.790503 -523.338445) (xy 61.739174 -523.360257) (xy 61.685217 -523.374363)
			(xy 61.62978 -523.380463) (xy 61.574046 -523.378426) (xy 61.519203 -523.368296) (xy 61.466419 -523.350289)
			(xy 61.416819 -523.324788) (xy 61.371461 -523.292337) (xy 61.331312 -523.253628) (xy 61.297226 -523.209485)
			(xy 61.26993 -523.16085) (xy 61.250007 -523.108759) (xy 61.237881 -523.054322) (xy 61.23381 -522.9987)
			(xy 60.462922 -522.9987) (xy 60.462413 -523.026586) (xy 60.454293 -523.081762) (xy 60.438225 -523.135169)
			(xy 60.414553 -523.185666) (xy 60.38378 -523.232179) (xy 60.346563 -523.273716) (xy 60.303695 -523.309391)
			(xy 60.256089 -523.338445) (xy 60.20476 -523.360257) (xy 60.150803 -523.374363) (xy 60.095366 -523.380463)
			(xy 60.039632 -523.378426) (xy 59.984789 -523.368296) (xy 59.932005 -523.350289) (xy 59.882405 -523.324788)
			(xy 59.837047 -523.292337) (xy 59.796898 -523.253628) (xy 59.762812 -523.209485) (xy 59.735516 -523.16085)
			(xy 59.715593 -523.108759) (xy 59.703467 -523.054322) (xy 59.699396 -522.9987) (xy 59.192922 -522.9987)
			(xy 59.192413 -523.026586) (xy 59.184293 -523.081762) (xy 59.168225 -523.135169) (xy 59.144553 -523.185666)
			(xy 59.11378 -523.232179) (xy 59.076563 -523.273716) (xy 59.033695 -523.309391) (xy 58.986089 -523.338445)
			(xy 58.93476 -523.360257) (xy 58.880803 -523.374363) (xy 58.825366 -523.380463) (xy 58.769632 -523.378426)
			(xy 58.714789 -523.368296) (xy 58.662005 -523.350289) (xy 58.612405 -523.324788) (xy 58.567047 -523.292337)
			(xy 58.526898 -523.253628) (xy 58.492812 -523.209485) (xy 58.465516 -523.16085) (xy 58.445593 -523.108759)
			(xy 58.433467 -523.054322) (xy 58.429396 -522.9987) (xy 57.93105 -522.9987) (xy 57.930541 -523.026586)
			(xy 57.922421 -523.081762) (xy 57.906353 -523.135169) (xy 57.882681 -523.185666) (xy 57.851908 -523.232179)
			(xy 57.814691 -523.273716) (xy 57.771823 -523.309391) (xy 57.724217 -523.338445) (xy 57.672888 -523.360257)
			(xy 57.618931 -523.374363) (xy 57.563494 -523.380463) (xy 57.50776 -523.378426) (xy 57.452917 -523.368296)
			(xy 57.400133 -523.350289) (xy 57.350533 -523.324788) (xy 57.305175 -523.292337) (xy 57.265026 -523.253628)
			(xy 57.23094 -523.209485) (xy 57.203644 -523.16085) (xy 57.183721 -523.108759) (xy 57.171595 -523.054322)
			(xy 57.167524 -522.9987) (xy 56.66105 -522.9987) (xy 56.660541 -523.026586) (xy 56.652421 -523.081762)
			(xy 56.636353 -523.135169) (xy 56.612681 -523.185666) (xy 56.581908 -523.232179) (xy 56.544691 -523.273716)
			(xy 56.501823 -523.309391) (xy 56.454217 -523.338445) (xy 56.402888 -523.360257) (xy 56.348931 -523.374363)
			(xy 56.293494 -523.380463) (xy 56.23776 -523.378426) (xy 56.182917 -523.368296) (xy 56.130133 -523.350289)
			(xy 56.080533 -523.324788) (xy 56.035175 -523.292337) (xy 55.995026 -523.253628) (xy 55.96094 -523.209485)
			(xy 55.933644 -523.16085) (xy 55.913721 -523.108759) (xy 55.901595 -523.054322) (xy 55.897524 -522.9987)
			(xy 36.456736 -522.9987) (xy 36.4555 -523.005311) (xy 36.431719 -523.088893) (xy 36.400327 -523.169925)
			(xy 36.361593 -523.247714) (xy 36.315846 -523.321598) (xy 36.263477 -523.390945) (xy 36.204933 -523.455165)
			(xy 36.140713 -523.513709) (xy 36.071366 -523.566078) (xy 35.997482 -523.611825) (xy 35.919693 -523.650559)
			(xy 35.838661 -523.681951) (xy 35.755079 -523.705732) (xy 35.669659 -523.7217) (xy 35.58313 -523.729718)
			(xy 35.49623 -523.729718) (xy 35.409701 -523.7217) (xy 35.324281 -523.705732) (xy 35.240699 -523.681951)
			(xy 35.159667 -523.650559) (xy 35.081878 -523.611825) (xy 35.007994 -523.566078) (xy 34.938647 -523.513709)
			(xy 34.874427 -523.455165) (xy 34.815883 -523.390945) (xy 34.763514 -523.321598) (xy 34.717767 -523.247714)
			(xy 34.679033 -523.169925) (xy 34.647641 -523.088893) (xy 34.62386 -523.005311) (xy 34.607892 -522.919891)
			(xy 34.599874 -522.833362) (xy 31.399486 -522.833362) (xy 31.391468 -522.919891) (xy 31.3755 -523.005311)
			(xy 31.351719 -523.088893) (xy 31.320327 -523.169925) (xy 31.281593 -523.247714) (xy 31.235846 -523.321598)
			(xy 31.183477 -523.390945) (xy 31.124933 -523.455165) (xy 31.060713 -523.513709) (xy 30.991366 -523.566078)
			(xy 30.917482 -523.611825) (xy 30.839693 -523.650559) (xy 30.758661 -523.681951) (xy 30.675079 -523.705732)
			(xy 30.589659 -523.7217) (xy 30.50313 -523.729718) (xy 30.41623 -523.729718) (xy 30.329701 -523.7217)
			(xy 30.244281 -523.705732) (xy 30.160699 -523.681951) (xy 30.079667 -523.650559) (xy 30.001878 -523.611825)
			(xy 29.927994 -523.566078) (xy 29.858647 -523.513709) (xy 29.794427 -523.455165) (xy 29.735883 -523.390945)
			(xy 29.683514 -523.321598) (xy 29.637767 -523.247714) (xy 29.599033 -523.169925) (xy 29.567641 -523.088893)
			(xy 29.54386 -523.005311) (xy 29.527892 -522.919891) (xy 29.519874 -522.833362) (xy 1.525016 -522.833362)
			(xy 1.525016 -524.347948) (xy 1.52551 -524.364603) (xy 1.532209 -524.389604) (xy 29.519372 -524.389604)
			(xy 31.399988 -524.389604) (xy 31.399988 -525.373362) (xy 34.599874 -525.373362) (xy 34.599874 -525.286462)
			(xy 34.607892 -525.199933) (xy 34.62386 -525.114513) (xy 34.647641 -525.030931) (xy 34.679033 -524.949899)
			(xy 34.717767 -524.87211) (xy 34.763514 -524.798226) (xy 34.815883 -524.728879) (xy 34.874427 -524.664659)
			(xy 34.938647 -524.606115) (xy 35.007994 -524.553746) (xy 35.081878 -524.507999) (xy 35.159667 -524.469265)
			(xy 35.240699 -524.437873) (xy 35.324281 -524.414092) (xy 35.409701 -524.398124) (xy 35.49623 -524.390106)
			(xy 35.58313 -524.390106) (xy 35.669659 -524.398124) (xy 35.755079 -524.414092) (xy 35.838661 -524.437873)
			(xy 35.919693 -524.469265) (xy 35.997482 -524.507999) (xy 36.071366 -524.553746) (xy 36.140713 -524.606115)
			(xy 36.204933 -524.664659) (xy 36.263477 -524.728879) (xy 36.315846 -524.798226) (xy 36.361593 -524.87211)
			(xy 36.400327 -524.949899) (xy 36.431719 -525.030931) (xy 36.4555 -525.114513) (xy 36.460677 -525.142206)
			(xy 55.897524 -525.142206) (xy 55.901595 -525.086584) (xy 55.913721 -525.032147) (xy 55.933644 -524.980056)
			(xy 55.96094 -524.931421) (xy 55.995026 -524.887278) (xy 56.035175 -524.848569) (xy 56.080533 -524.816118)
			(xy 56.130133 -524.790617) (xy 56.182917 -524.77261) (xy 56.23776 -524.76248) (xy 56.293494 -524.760443)
			(xy 56.348931 -524.766543) (xy 56.402888 -524.780649) (xy 56.454217 -524.802461) (xy 56.501823 -524.831515)
			(xy 56.544691 -524.86719) (xy 56.581908 -524.908727) (xy 56.612681 -524.95524) (xy 56.636353 -525.005737)
			(xy 56.652421 -525.059144) (xy 56.660541 -525.11432) (xy 56.66105 -525.142206) (xy 57.167524 -525.142206)
			(xy 57.171595 -525.086584) (xy 57.183721 -525.032147) (xy 57.203644 -524.980056) (xy 57.23094 -524.931421)
			(xy 57.265026 -524.887278) (xy 57.305175 -524.848569) (xy 57.350533 -524.816118) (xy 57.400133 -524.790617)
			(xy 57.452917 -524.77261) (xy 57.50776 -524.76248) (xy 57.563494 -524.760443) (xy 57.618931 -524.766543)
			(xy 57.672888 -524.780649) (xy 57.724217 -524.802461) (xy 57.771823 -524.831515) (xy 57.814691 -524.86719)
			(xy 57.851908 -524.908727) (xy 57.882681 -524.95524) (xy 57.906353 -525.005737) (xy 57.922421 -525.059144)
			(xy 57.930541 -525.11432) (xy 57.93105 -525.142206) (xy 58.429396 -525.142206) (xy 58.433467 -525.086584)
			(xy 58.445593 -525.032147) (xy 58.465516 -524.980056) (xy 58.492812 -524.931421) (xy 58.526898 -524.887278)
			(xy 58.567047 -524.848569) (xy 58.612405 -524.816118) (xy 58.662005 -524.790617) (xy 58.714789 -524.77261)
			(xy 58.769632 -524.76248) (xy 58.825366 -524.760443) (xy 58.880803 -524.766543) (xy 58.93476 -524.780649)
			(xy 58.986089 -524.802461) (xy 59.033695 -524.831515) (xy 59.076563 -524.86719) (xy 59.11378 -524.908727)
			(xy 59.144553 -524.95524) (xy 59.168225 -525.005737) (xy 59.184293 -525.059144) (xy 59.192413 -525.11432)
			(xy 59.192922 -525.142206) (xy 59.699396 -525.142206) (xy 59.703467 -525.086584) (xy 59.715593 -525.032147)
			(xy 59.735516 -524.980056) (xy 59.762812 -524.931421) (xy 59.796898 -524.887278) (xy 59.837047 -524.848569)
			(xy 59.882405 -524.816118) (xy 59.932005 -524.790617) (xy 59.984789 -524.77261) (xy 60.039632 -524.76248)
			(xy 60.095366 -524.760443) (xy 60.150803 -524.766543) (xy 60.20476 -524.780649) (xy 60.256089 -524.802461)
			(xy 60.303695 -524.831515) (xy 60.346563 -524.86719) (xy 60.38378 -524.908727) (xy 60.414553 -524.95524)
			(xy 60.438225 -525.005737) (xy 60.454293 -525.059144) (xy 60.462413 -525.11432) (xy 60.462922 -525.142206)
			(xy 61.23381 -525.142206) (xy 61.237881 -525.086584) (xy 61.250007 -525.032147) (xy 61.26993 -524.980056)
			(xy 61.297226 -524.931421) (xy 61.331312 -524.887278) (xy 61.371461 -524.848569) (xy 61.416819 -524.816118)
			(xy 61.466419 -524.790617) (xy 61.519203 -524.77261) (xy 61.574046 -524.76248) (xy 61.62978 -524.760443)
			(xy 61.685217 -524.766543) (xy 61.739174 -524.780649) (xy 61.790503 -524.802461) (xy 61.838109 -524.831515)
			(xy 61.880977 -524.86719) (xy 61.918194 -524.908727) (xy 61.948967 -524.95524) (xy 61.972639 -525.005737)
			(xy 61.988707 -525.059144) (xy 61.996827 -525.11432) (xy 61.997336 -525.142206) (xy 62.50381 -525.142206)
			(xy 62.507881 -525.086584) (xy 62.520007 -525.032147) (xy 62.53993 -524.980056) (xy 62.567226 -524.931421)
			(xy 62.601312 -524.887278) (xy 62.641461 -524.848569) (xy 62.686819 -524.816118) (xy 62.736419 -524.790617)
			(xy 62.789203 -524.77261) (xy 62.844046 -524.76248) (xy 62.89978 -524.760443) (xy 62.955217 -524.766543)
			(xy 63.009174 -524.780649) (xy 63.060503 -524.802461) (xy 63.108109 -524.831515) (xy 63.150977 -524.86719)
			(xy 63.188194 -524.908727) (xy 63.218967 -524.95524) (xy 63.242639 -525.005737) (xy 63.258707 -525.059144)
			(xy 63.266827 -525.11432) (xy 63.267336 -525.142206) (xy 64.47358 -525.142206) (xy 64.477651 -525.086584)
			(xy 64.489777 -525.032147) (xy 64.5097 -524.980056) (xy 64.536996 -524.931421) (xy 64.571082 -524.887278)
			(xy 64.611231 -524.848569) (xy 64.656589 -524.816118) (xy 64.706189 -524.790617) (xy 64.758973 -524.77261)
			(xy 64.813816 -524.76248) (xy 64.86955 -524.760443) (xy 64.924987 -524.766543) (xy 64.978944 -524.780649)
			(xy 65.030273 -524.802461) (xy 65.077879 -524.831515) (xy 65.120747 -524.86719) (xy 65.157964 -524.908727)
			(xy 65.188737 -524.95524) (xy 65.212409 -525.005737) (xy 65.228477 -525.059144) (xy 65.236597 -525.11432)
			(xy 65.237106 -525.142206) (xy 65.74358 -525.142206) (xy 65.747651 -525.086584) (xy 65.759777 -525.032147)
			(xy 65.7797 -524.980056) (xy 65.806996 -524.931421) (xy 65.841082 -524.887278) (xy 65.881231 -524.848569)
			(xy 65.926589 -524.816118) (xy 65.976189 -524.790617) (xy 66.028973 -524.77261) (xy 66.083816 -524.76248)
			(xy 66.13955 -524.760443) (xy 66.194987 -524.766543) (xy 66.248944 -524.780649) (xy 66.300273 -524.802461)
			(xy 66.347879 -524.831515) (xy 66.390747 -524.86719) (xy 66.427964 -524.908727) (xy 66.458737 -524.95524)
			(xy 66.482409 -525.005737) (xy 66.498477 -525.059144) (xy 66.506597 -525.11432) (xy 66.507106 -525.142206)
			(xy 67.465192 -525.142206) (xy 67.469263 -525.086584) (xy 67.481389 -525.032147) (xy 67.501312 -524.980056)
			(xy 67.528608 -524.931421) (xy 67.562694 -524.887278) (xy 67.602843 -524.848569) (xy 67.648201 -524.816118)
			(xy 67.697801 -524.790617) (xy 67.750585 -524.77261) (xy 67.805428 -524.76248) (xy 67.861162 -524.760443)
			(xy 67.916599 -524.766543) (xy 67.970556 -524.780649) (xy 68.021885 -524.802461) (xy 68.069491 -524.831515)
			(xy 68.112359 -524.86719) (xy 68.149576 -524.908727) (xy 68.180349 -524.95524) (xy 68.204021 -525.005737)
			(xy 68.220089 -525.059144) (xy 68.228209 -525.11432) (xy 68.228718 -525.142206) (xy 68.735192 -525.142206)
			(xy 68.739263 -525.086584) (xy 68.751389 -525.032147) (xy 68.771312 -524.980056) (xy 68.798608 -524.931421)
			(xy 68.832694 -524.887278) (xy 68.872843 -524.848569) (xy 68.918201 -524.816118) (xy 68.967801 -524.790617)
			(xy 69.020585 -524.77261) (xy 69.075428 -524.76248) (xy 69.131162 -524.760443) (xy 69.186599 -524.766543)
			(xy 69.240556 -524.780649) (xy 69.291885 -524.802461) (xy 69.339491 -524.831515) (xy 69.382359 -524.86719)
			(xy 69.419576 -524.908727) (xy 69.450349 -524.95524) (xy 69.474021 -525.005737) (xy 69.490089 -525.059144)
			(xy 69.498209 -525.11432) (xy 69.498718 -525.142206) (xy 69.498209 -525.170092) (xy 69.490089 -525.225268)
			(xy 69.474021 -525.278675) (xy 69.450349 -525.329172) (xy 69.419576 -525.375685) (xy 69.382359 -525.417222)
			(xy 69.339491 -525.452897) (xy 69.291885 -525.481951) (xy 69.240556 -525.503763) (xy 69.186599 -525.517869)
			(xy 69.131162 -525.523969) (xy 69.075428 -525.521932) (xy 69.020585 -525.511802) (xy 68.967801 -525.493795)
			(xy 68.918201 -525.468294) (xy 68.872843 -525.435843) (xy 68.832694 -525.397134) (xy 68.798608 -525.352991)
			(xy 68.771312 -525.304356) (xy 68.751389 -525.252265) (xy 68.739263 -525.197828) (xy 68.735192 -525.142206)
			(xy 68.228718 -525.142206) (xy 68.228209 -525.170092) (xy 68.220089 -525.225268) (xy 68.204021 -525.278675)
			(xy 68.180349 -525.329172) (xy 68.149576 -525.375685) (xy 68.112359 -525.417222) (xy 68.069491 -525.452897)
			(xy 68.021885 -525.481951) (xy 67.970556 -525.503763) (xy 67.916599 -525.517869) (xy 67.861162 -525.523969)
			(xy 67.805428 -525.521932) (xy 67.750585 -525.511802) (xy 67.697801 -525.493795) (xy 67.648201 -525.468294)
			(xy 67.602843 -525.435843) (xy 67.562694 -525.397134) (xy 67.528608 -525.352991) (xy 67.501312 -525.304356)
			(xy 67.481389 -525.252265) (xy 67.469263 -525.197828) (xy 67.465192 -525.142206) (xy 66.507106 -525.142206)
			(xy 66.506597 -525.170092) (xy 66.498477 -525.225268) (xy 66.482409 -525.278675) (xy 66.458737 -525.329172)
			(xy 66.427964 -525.375685) (xy 66.390747 -525.417222) (xy 66.347879 -525.452897) (xy 66.300273 -525.481951)
			(xy 66.248944 -525.503763) (xy 66.194987 -525.517869) (xy 66.13955 -525.523969) (xy 66.083816 -525.521932)
			(xy 66.028973 -525.511802) (xy 65.976189 -525.493795) (xy 65.926589 -525.468294) (xy 65.881231 -525.435843)
			(xy 65.841082 -525.397134) (xy 65.806996 -525.352991) (xy 65.7797 -525.304356) (xy 65.759777 -525.252265)
			(xy 65.747651 -525.197828) (xy 65.74358 -525.142206) (xy 65.237106 -525.142206) (xy 65.236597 -525.170092)
			(xy 65.228477 -525.225268) (xy 65.212409 -525.278675) (xy 65.188737 -525.329172) (xy 65.157964 -525.375685)
			(xy 65.120747 -525.417222) (xy 65.077879 -525.452897) (xy 65.030273 -525.481951) (xy 64.978944 -525.503763)
			(xy 64.924987 -525.517869) (xy 64.86955 -525.523969) (xy 64.813816 -525.521932) (xy 64.758973 -525.511802)
			(xy 64.706189 -525.493795) (xy 64.656589 -525.468294) (xy 64.611231 -525.435843) (xy 64.571082 -525.397134)
			(xy 64.536996 -525.352991) (xy 64.5097 -525.304356) (xy 64.489777 -525.252265) (xy 64.477651 -525.197828)
			(xy 64.47358 -525.142206) (xy 63.267336 -525.142206) (xy 63.266827 -525.170092) (xy 63.258707 -525.225268)
			(xy 63.242639 -525.278675) (xy 63.218967 -525.329172) (xy 63.188194 -525.375685) (xy 63.150977 -525.417222)
			(xy 63.108109 -525.452897) (xy 63.060503 -525.481951) (xy 63.009174 -525.503763) (xy 62.955217 -525.517869)
			(xy 62.89978 -525.523969) (xy 62.844046 -525.521932) (xy 62.789203 -525.511802) (xy 62.736419 -525.493795)
			(xy 62.686819 -525.468294) (xy 62.641461 -525.435843) (xy 62.601312 -525.397134) (xy 62.567226 -525.352991)
			(xy 62.53993 -525.304356) (xy 62.520007 -525.252265) (xy 62.507881 -525.197828) (xy 62.50381 -525.142206)
			(xy 61.997336 -525.142206) (xy 61.996827 -525.170092) (xy 61.988707 -525.225268) (xy 61.972639 -525.278675)
			(xy 61.948967 -525.329172) (xy 61.918194 -525.375685) (xy 61.880977 -525.417222) (xy 61.838109 -525.452897)
			(xy 61.790503 -525.481951) (xy 61.739174 -525.503763) (xy 61.685217 -525.517869) (xy 61.62978 -525.523969)
			(xy 61.574046 -525.521932) (xy 61.519203 -525.511802) (xy 61.466419 -525.493795) (xy 61.416819 -525.468294)
			(xy 61.371461 -525.435843) (xy 61.331312 -525.397134) (xy 61.297226 -525.352991) (xy 61.26993 -525.304356)
			(xy 61.250007 -525.252265) (xy 61.237881 -525.197828) (xy 61.23381 -525.142206) (xy 60.462922 -525.142206)
			(xy 60.462413 -525.170092) (xy 60.454293 -525.225268) (xy 60.438225 -525.278675) (xy 60.414553 -525.329172)
			(xy 60.38378 -525.375685) (xy 60.346563 -525.417222) (xy 60.303695 -525.452897) (xy 60.256089 -525.481951)
			(xy 60.20476 -525.503763) (xy 60.150803 -525.517869) (xy 60.095366 -525.523969) (xy 60.039632 -525.521932)
			(xy 59.984789 -525.511802) (xy 59.932005 -525.493795) (xy 59.882405 -525.468294) (xy 59.837047 -525.435843)
			(xy 59.796898 -525.397134) (xy 59.762812 -525.352991) (xy 59.735516 -525.304356) (xy 59.715593 -525.252265)
			(xy 59.703467 -525.197828) (xy 59.699396 -525.142206) (xy 59.192922 -525.142206) (xy 59.192413 -525.170092)
			(xy 59.184293 -525.225268) (xy 59.168225 -525.278675) (xy 59.144553 -525.329172) (xy 59.11378 -525.375685)
			(xy 59.076563 -525.417222) (xy 59.033695 -525.452897) (xy 58.986089 -525.481951) (xy 58.93476 -525.503763)
			(xy 58.880803 -525.517869) (xy 58.825366 -525.523969) (xy 58.769632 -525.521932) (xy 58.714789 -525.511802)
			(xy 58.662005 -525.493795) (xy 58.612405 -525.468294) (xy 58.567047 -525.435843) (xy 58.526898 -525.397134)
			(xy 58.492812 -525.352991) (xy 58.465516 -525.304356) (xy 58.445593 -525.252265) (xy 58.433467 -525.197828)
			(xy 58.429396 -525.142206) (xy 57.93105 -525.142206) (xy 57.930541 -525.170092) (xy 57.922421 -525.225268)
			(xy 57.906353 -525.278675) (xy 57.882681 -525.329172) (xy 57.851908 -525.375685) (xy 57.814691 -525.417222)
			(xy 57.771823 -525.452897) (xy 57.724217 -525.481951) (xy 57.672888 -525.503763) (xy 57.618931 -525.517869)
			(xy 57.563494 -525.523969) (xy 57.50776 -525.521932) (xy 57.452917 -525.511802) (xy 57.400133 -525.493795)
			(xy 57.350533 -525.468294) (xy 57.305175 -525.435843) (xy 57.265026 -525.397134) (xy 57.23094 -525.352991)
			(xy 57.203644 -525.304356) (xy 57.183721 -525.252265) (xy 57.171595 -525.197828) (xy 57.167524 -525.142206)
			(xy 56.66105 -525.142206) (xy 56.660541 -525.170092) (xy 56.652421 -525.225268) (xy 56.636353 -525.278675)
			(xy 56.612681 -525.329172) (xy 56.581908 -525.375685) (xy 56.544691 -525.417222) (xy 56.501823 -525.452897)
			(xy 56.454217 -525.481951) (xy 56.402888 -525.503763) (xy 56.348931 -525.517869) (xy 56.293494 -525.523969)
			(xy 56.23776 -525.521932) (xy 56.182917 -525.511802) (xy 56.130133 -525.493795) (xy 56.080533 -525.468294)
			(xy 56.035175 -525.435843) (xy 55.995026 -525.397134) (xy 55.96094 -525.352991) (xy 55.933644 -525.304356)
			(xy 55.913721 -525.252265) (xy 55.901595 -525.197828) (xy 55.897524 -525.142206) (xy 36.460677 -525.142206)
			(xy 36.471468 -525.199933) (xy 36.479486 -525.286462) (xy 36.479988 -525.329912) (xy 36.479486 -525.373362)
			(xy 36.471468 -525.459891) (xy 36.4555 -525.545311) (xy 36.431719 -525.628893) (xy 36.400327 -525.709925)
			(xy 36.361593 -525.787714) (xy 36.315846 -525.861598) (xy 36.263477 -525.930945) (xy 36.204933 -525.995165)
			(xy 36.140713 -526.053709) (xy 36.071366 -526.106078) (xy 35.997482 -526.151825) (xy 35.919693 -526.190559)
			(xy 35.838661 -526.221951) (xy 35.755079 -526.245732) (xy 35.669659 -526.2617) (xy 35.58313 -526.269718)
			(xy 35.49623 -526.269718) (xy 35.409701 -526.2617) (xy 35.324281 -526.245732) (xy 35.240699 -526.221951)
			(xy 35.159667 -526.190559) (xy 35.081878 -526.151825) (xy 35.007994 -526.106078) (xy 34.938647 -526.053709)
			(xy 34.874427 -525.995165) (xy 34.815883 -525.930945) (xy 34.763514 -525.861598) (xy 34.717767 -525.787714)
			(xy 34.679033 -525.709925) (xy 34.647641 -525.628893) (xy 34.62386 -525.545311) (xy 34.607892 -525.459891)
			(xy 34.599874 -525.373362) (xy 31.399988 -525.373362) (xy 31.399988 -526.27022) (xy 29.519372 -526.27022)
			(xy 29.519372 -524.389604) (xy 1.532209 -524.389604) (xy 1.534131 -524.396777) (xy 1.550786 -524.425624)
			(xy 1.57434 -524.449176) (xy 1.603187 -524.46583) (xy 1.635361 -524.47445) (xy 1.652016 -524.474948)
			(xy 23.50008 -524.474948) (xy 23.576725 -524.475425) (xy 23.729819 -524.483189) (xy 23.882323 -524.498697)
			(xy 24.033845 -524.52191) (xy 24.183998 -524.552768) (xy 24.332394 -524.591192) (xy 24.478654 -524.637083)
			(xy 24.622401 -524.690324) (xy 24.763268 -524.750778) (xy 24.900891 -524.818289) (xy 25.034918 -524.892685)
			(xy 25.165004 -524.973774) (xy 25.290817 -525.061348) (xy 25.412031 -525.155182) (xy 25.528338 -525.255036)
			(xy 25.639437 -525.360652) (xy 25.745044 -525.471761) (xy 25.844887 -525.588076) (xy 25.938711 -525.709299)
			(xy 26.026274 -525.83512) (xy 26.107351 -525.965213) (xy 26.181735 -526.099247) (xy 26.249234 -526.236876)
			(xy 26.309675 -526.377748) (xy 26.362904 -526.5215) (xy 26.408782 -526.667764) (xy 26.447193 -526.816164)
			(xy 26.478038 -526.966319) (xy 26.501237 -527.117843) (xy 26.516732 -527.270348) (xy 26.524482 -527.423443)
			(xy 26.524966 -527.500088) (xy 26.524966 -528.34794) (xy 26.525514 -528.364586) (xy 26.534138 -528.396743)
			(xy 26.550788 -528.425574) (xy 26.57433 -528.449116) (xy 26.603162 -528.465764) (xy 26.635319 -528.474387)
			(xy 26.651966 -528.47494)
		)
		(stroke
			(width 0)
			(type solid)
		)
		(fill yes)
		(layer "B.Cu")
		(net "GND")
	)
	(gr_line
		(start 0 -524.500094)
		(end 0 -5.500116)
		(stroke
			(width 1.016)
			(type default)
		)
		(layer "In1.Cu")
	)
	(gr_arc
		(start 0 -524.500094)
		(mid 0.439393 -525.560749)
		(end 1.500124 -525.999964)
		(stroke
			(width 1.016)
			(type default)
		)
		(layer "In1.Cu")
	)
	(gr_poly
		(pts
			(xy 101.000052 -529.49094) (xy 101.055822 -529.490433) (xy 101.167051 -529.482101) (xy 101.277346 -529.46548)
			(xy 101.38609 -529.440662) (xy 101.492675 -529.407788) (xy 101.596506 -529.367039) (xy 101.697001 -529.318645)
			(xy 101.793598 -529.262876) (xy 101.885758 -529.200044) (xy 101.972964 -529.130501) (xy 102.054729 -529.054635)
			(xy 102.130596 -528.97287) (xy 102.20014 -528.885664) (xy 102.262972 -528.793505) (xy 102.318742 -528.696908)
			(xy 102.367136 -528.596413) (xy 102.407885 -528.492583) (xy 102.44076 -528.385998) (xy 102.465578 -528.277253)
			(xy 102.4822 -528.166959) (xy 102.490533 -528.05573) (xy 102.491032 -527.99996) (xy 102.491032 -1.999996)
			(xy 102.490523 -1.944227) (xy 102.482188 -1.833002) (xy 102.465563 -1.72271) (xy 102.440743 -1.613969)
			(xy 102.407866 -1.507387) (xy 102.367116 -1.40356) (xy 102.31872 -1.303069) (xy 102.26295 -1.206475)
			(xy 102.200118 -1.11432) (xy 102.130574 -1.027117) (xy 102.054708 -0.945356) (xy 101.972944 -0.869492)
			(xy 101.885739 -0.799951) (xy 101.793581 -0.737122) (xy 101.696985 -0.681355) (xy 101.596492 -0.632964)
			(xy 101.492664 -0.592217) (xy 101.386081 -0.559343) (xy 101.277339 -0.534527) (xy 101.167047 -0.517907)
			(xy 101.055821 -0.509575) (xy 101.000052 -0.509016) (xy 26.500074 -0.509016) (xy 26.454278 -0.509546)
			(xy 26.363077 -0.517999) (xy 26.273045 -0.534832) (xy 26.184949 -0.559899) (xy 26.099543 -0.592988)
			(xy 26.017554 -0.633817) (xy 25.939682 -0.682036) (xy 25.866592 -0.737234) (xy 25.798906 -0.798941)
			(xy 25.737202 -0.86663) (xy 25.682007 -0.939724) (xy 25.633792 -1.017598) (xy 25.592968 -1.099589)
			(xy 25.559883 -1.184997) (xy 25.53482 -1.273093) (xy 25.517992 -1.363126) (xy 25.509543 -1.454328)
			(xy 25.508966 -1.500124) (xy 25.508966 -2.500122) (xy 25.50847 -2.563238) (xy 25.500544 -2.689221)
			(xy 25.484723 -2.814458) (xy 25.461069 -2.938455) (xy 25.429676 -3.060721) (xy 25.390668 -3.180775)
			(xy 25.344199 -3.298143) (xy 25.290452 -3.412362) (xy 25.229639 -3.52298) (xy 25.162 -3.629561) (xy 25.087803 -3.731685)
			(xy 25.007339 -3.828949) (xy 24.920927 -3.920968) (xy 24.828907 -4.00738) (xy 24.731644 -4.087844)
			(xy 24.62952 -4.162041) (xy 24.522938 -4.22968) (xy 24.41232 -4.290493) (xy 24.298101 -4.34424) (xy 24.180733 -4.390709)
			(xy 24.060679 -4.429717) (xy 23.938413 -4.46111) (xy 23.814416 -4.484763) (xy 23.689179 -4.500584)
			(xy 23.563196 -4.50851) (xy 23.50008 -4.509008) (xy 1.500124 -4.509008) (xy 1.454327 -4.509537) (xy 1.363123 -4.517988)
			(xy 1.273088 -4.534819) (xy 1.18499 -4.559885) (xy 1.099581 -4.592972) (xy 1.017589 -4.6338) (xy 0.939714 -4.682018)
			(xy 0.86662 -4.737216) (xy 0.798931 -4.798923) (xy 0.737224 -4.866612) (xy 0.682026 -4.939706) (xy 0.633808 -5.017581)
			(xy 0.59298 -5.099573) (xy 0.559893 -5.184982) (xy 0.534827 -5.27308) (xy 0.517996 -5.363115) (xy 0.509545 -5.454319)
			(xy 0.509016 -5.500116) (xy 0.509016 -7.747) (xy 5.5306 -7.747) (xy 5.534631 -7.617434) (xy 5.54671 -7.48837)
			(xy 5.566789 -7.360306) (xy 5.594791 -7.233739) (xy 5.630608 -7.109156) (xy 5.6741 -6.987042) (xy 5.7251 -6.867868)
			(xy 5.783411 -6.752095) (xy 5.848806 -6.640171) (xy 5.921033 -6.532529) (xy 5.999813 -6.429586) (xy 6.08484 -6.33174)
			(xy 6.175785 -6.239368) (xy 6.272297 -6.15283) (xy 6.374003 -6.072459) (xy 6.480509 -5.998567) (xy 6.591402 -5.931439)
			(xy 6.706254 -5.871335) (xy 6.824621 -5.818488) (xy 6.946044 -5.773101) (xy 7.070054 -5.735352) (xy 7.196171 -5.705385)
			(xy 7.323907 -5.683316) (xy 7.452768 -5.669232) (xy 7.582255 -5.663186) (xy 7.711868 -5.665202) (xy 7.841104 -5.675272)
			(xy 7.969465 -5.693357) (xy 8.096453 -5.719387) (xy 8.221577 -5.753262) (xy 8.344353 -5.79485) (xy 8.464306 -5.843991)
			(xy 8.580971 -5.900494) (xy 8.693899 -5.964141) (xy 8.802651 -6.034685) (xy 8.906807 -6.111854) (xy 9.005964 -6.195349)
			(xy 9.099738 -6.284847) (xy 9.187767 -6.380002) (xy 9.26971 -6.480445) (xy 9.345249 -6.585788) (xy 9.414094 -6.695624)
			(xy 9.475977 -6.809528) (xy 9.522754 -6.91007) (xy 39.818564 -6.91007) (xy 39.819054 -6.852663) (xy 39.826889 -6.738117)
			(xy 39.842523 -6.624372) (xy 39.865882 -6.51196) (xy 39.896859 -6.401403) (xy 39.935308 -6.293218)
			(xy 39.98105 -6.18791) (xy 40.033872 -6.085968) (xy 40.093527 -5.987869) (xy 40.159738 -5.894069)
			(xy 40.232196 -5.805007) (xy 40.310562 -5.721096) (xy 40.394473 -5.64273) (xy 40.483535 -5.570272)
			(xy 40.577335 -5.504061) (xy 40.675434 -5.444406) (xy 40.777376 -5.391584) (xy 40.882684 -5.345842)
			(xy 40.990869 -5.307393) (xy 41.101426 -5.276416) (xy 41.213838 -5.253057) (xy 41.327583 -5.237423)
			(xy 41.442129 -5.229588) (xy 41.556943 -5.229588) (xy 41.671489 -5.237423) (xy 41.785234 -5.253057)
			(xy 41.897646 -5.276416) (xy 42.008203 -5.307393) (xy 42.116388 -5.345842) (xy 42.221696 -5.391584)
			(xy 42.323638 -5.444406) (xy 42.421737 -5.504061) (xy 42.515537 -5.570272) (xy 42.604599 -5.64273)
			(xy 42.68851 -5.721096) (xy 42.766876 -5.805007) (xy 42.839334 -5.894069) (xy 42.905545 -5.987869)
			(xy 42.9652 -6.085968) (xy 43.018022 -6.18791) (xy 43.063764 -6.293218) (xy 43.102213 -6.401403)
			(xy 43.13319 -6.51196) (xy 43.156549 -6.624372) (xy 43.172183 -6.738117) (xy 43.180018 -6.852663)
			(xy 43.180508 -6.91007) (xy 43.180381 -6.943251) (xy 43.177842 -7.009565) (xy 43.175428 -7.042658)
			(xy 43.170272 -7.100942) (xy 43.152948 -7.216671) (xy 43.127616 -7.330914) (xy 43.094401 -7.443119)
			(xy 43.053462 -7.552742) (xy 43.004999 -7.659253) (xy 42.949245 -7.762135) (xy 42.886471 -7.860891)
			(xy 42.816981 -7.955042) (xy 42.741111 -8.044132) (xy 42.659229 -8.127729) (xy 42.571732 -8.20543)
			(xy 42.500813 -8.26008) (xy 93.154506 -8.26008) (xy 93.158522 -8.14381) (xy 93.170549 -8.028095)
			(xy 93.190531 -7.913485) (xy 93.218373 -7.800526) (xy 93.253942 -7.689758) (xy 93.297068 -7.581707)
			(xy 93.347545 -7.476889) (xy 93.405134 -7.375804) (xy 93.46956 -7.278932) (xy 93.540515 -7.186736)
			(xy 93.617662 -7.099655) (xy 93.700633 -7.018104) (xy 93.789033 -6.942472) (xy 93.88244 -6.873118)
			(xy 93.980409 -6.810375) (xy 94.082473 -6.754539) (xy 94.188147 -6.705878) (xy 94.296926 -6.664624)
			(xy 94.408291 -6.630973) (xy 94.521714 -6.605085) (xy 94.636651 -6.587084) (xy 94.752557 -6.577055)
			(xy 94.868879 -6.575047) (xy 94.985062 -6.581069) (xy 95.100553 -6.595092) (xy 95.214801 -6.61705)
			(xy 95.327262 -6.646837) (xy 95.4374 -6.684312) (xy 95.54469 -6.729297) (xy 95.648621 -6.781576)
			(xy 95.748697 -6.840901) (xy 95.844443 -6.906989) (xy 95.9354 -6.979525) (xy 96.021136 -7.058164)
			(xy 96.101243 -7.14253) (xy 96.175339 -7.232222) (xy 96.243069 -7.326812) (xy 96.304113 -7.42585)
			(xy 96.358178 -7.528863) (xy 96.405008 -7.63536) (xy 96.444379 -7.744835) (xy 96.476103 -7.856765)
			(xy 96.500029 -7.970617) (xy 96.516043 -8.085849) (xy 96.52407 -8.201911) (xy 96.524572 -8.26008)
			(xy 96.52407 -8.318249) (xy 96.516043 -8.434311) (xy 96.500029 -8.549543) (xy 96.476103 -8.663395)
			(xy 96.444379 -8.775325) (xy 96.405008 -8.8848) (xy 96.358178 -8.991297) (xy 96.304113 -9.09431)
			(xy 96.243069 -9.193348) (xy 96.175339 -9.287938) (xy 96.101243 -9.37763) (xy 96.021136 -9.461996)
			(xy 95.9354 -9.540635) (xy 95.844443 -9.613171) (xy 95.748697 -9.679259) (xy 95.648621 -9.738584)
			(xy 95.54469 -9.790863) (xy 95.4374 -9.835848) (xy 95.327262 -9.873323) (xy 95.214801 -9.90311) (xy 95.100553 -9.925068)
			(xy 94.985062 -9.939091) (xy 94.868879 -9.945113) (xy 94.752557 -9.943105) (xy 94.636651 -9.933076)
			(xy 94.521714 -9.915075) (xy 94.408291 -9.889187) (xy 94.296926 -9.855536) (xy 94.188147 -9.814282)
			(xy 94.082473 -9.765621) (xy 93.980409 -9.709785) (xy 93.88244 -9.647042) (xy 93.789033 -9.577688)
			(xy 93.700633 -9.502056) (xy 93.617662 -9.420505) (xy 93.540515 -9.333424) (xy 93.46956 -9.241228)
			(xy 93.405134 -9.144356) (xy 93.347545 -9.043271) (xy 93.297068 -8.938453) (xy 93.253942 -8.830402)
			(xy 93.218373 -8.719634) (xy 93.190531 -8.606675) (xy 93.170549 -8.492065) (xy 93.158522 -8.37635)
			(xy 93.154506 -8.26008) (xy 42.500813 -8.26008) (xy 42.479042 -8.276857) (xy 42.381609 -8.341665)
			(xy 42.279905 -8.39954) (xy 42.174422 -8.450202) (xy 42.065671 -8.493404) (xy 41.954179 -8.528939)
			(xy 41.840485 -8.556634) (xy 41.725141 -8.576354) (xy 41.608704 -8.588005) (xy 41.491739 -8.59153)
			(xy 41.374812 -8.586912) (xy 41.258489 -8.574173) (xy 41.143334 -8.553375) (xy 41.029905 -8.524618)
			(xy 40.91875 -8.488042) (xy 40.810407 -8.443825) (xy 40.705403 -8.392179) (xy 40.604244 -8.333356)
			(xy 40.507421 -8.26764) (xy 40.415403 -8.195349) (xy 40.328636 -8.116834) (xy 40.247539 -8.032474)
			(xy 40.172506 -7.942679) (xy 40.103899 -7.847883) (xy 40.042051 -7.748544) (xy 39.987262 -7.645145)
			(xy 39.939796 -7.538186) (xy 39.899884 -7.428185) (xy 39.86772 -7.315674) (xy 39.843457 -7.201199)
			(xy 39.827215 -7.085313) (xy 39.819072 -6.968579) (xy 39.818564 -6.91007) (xy 9.522754 -6.91007)
			(xy 9.530658 -6.927058) (xy 9.577928 -7.047761) (xy 9.617601 -7.171169) (xy 9.649526 -7.296805) (xy 9.673578 -7.424182)
			(xy 9.689665 -7.552808) (xy 9.697724 -7.682186) (xy 9.698228 -7.747) (xy 9.697724 -7.811814) (xy 9.689665 -7.941192)
			(xy 9.673578 -8.069818) (xy 9.649526 -8.197195) (xy 9.617601 -8.322831) (xy 9.577928 -8.446239) (xy 9.530658 -8.566942)
			(xy 9.475977 -8.684472) (xy 9.414094 -8.798376) (xy 9.345249 -8.908212) (xy 9.26971 -9.013555) (xy 9.187767 -9.113998)
			(xy 9.099738 -9.209153) (xy 9.005964 -9.298651) (xy 8.906807 -9.382146) (xy 8.802651 -9.459315) (xy 8.693899 -9.529859)
			(xy 8.580971 -9.593506) (xy 8.464306 -9.650009) (xy 8.344353 -9.69915) (xy 8.221577 -9.740738) (xy 8.096453 -9.774613)
			(xy 7.969465 -9.800643) (xy 7.841104 -9.818728) (xy 7.711868 -9.828798) (xy 7.582255 -9.830814) (xy 7.452768 -9.824768)
			(xy 7.323907 -9.810684) (xy 7.196171 -9.788615) (xy 7.070054 -9.758648) (xy 6.946044 -9.720899) (xy 6.824621 -9.675512)
			(xy 6.706254 -9.622665) (xy 6.591402 -9.562561) (xy 6.480509 -9.495433) (xy 6.374003 -9.421541) (xy 6.272297 -9.34117)
			(xy 6.175785 -9.254632) (xy 6.08484 -9.16226) (xy 5.999813 -9.064414) (xy 5.921033 -8.961471) (xy 5.848806 -8.853829)
			(xy 5.783411 -8.741905) (xy 5.7251 -8.626132) (xy 5.6741 -8.506958) (xy 5.630608 -8.384844) (xy 5.594791 -8.260261)
			(xy 5.566789 -8.133694) (xy 5.54671 -8.00563) (xy 5.534631 -7.876566) (xy 5.5306 -7.747) (xy 0.509016 -7.747)
			(xy 0.509016 -19.177) (xy 5.5306 -19.177) (xy 5.534631 -19.047434) (xy 5.54671 -18.91837) (xy 5.566789 -18.790306)
			(xy 5.594791 -18.663739) (xy 5.630608 -18.539156) (xy 5.6741 -18.417042) (xy 5.7251 -18.297868) (xy 5.783411 -18.182095)
			(xy 5.848806 -18.070171) (xy 5.921033 -17.962529) (xy 5.999813 -17.859586) (xy 6.08484 -17.76174)
			(xy 6.175785 -17.669368) (xy 6.272297 -17.58283) (xy 6.374003 -17.502459) (xy 6.480509 -17.428567)
			(xy 6.591402 -17.361439) (xy 6.706254 -17.301335) (xy 6.824621 -17.248488) (xy 6.946044 -17.203101)
			(xy 7.070054 -17.165352) (xy 7.196171 -17.135385) (xy 7.323907 -17.113316) (xy 7.452768 -17.099232)
			(xy 7.582255 -17.093186) (xy 7.711868 -17.095202) (xy 7.841104 -17.105272) (xy 7.969465 -17.123357)
			(xy 8.096453 -17.149387) (xy 8.221577 -17.183262) (xy 8.344353 -17.22485) (xy 8.464306 -17.273991)
			(xy 8.580971 -17.330494) (xy 8.693899 -17.394141) (xy 8.802651 -17.464685) (xy 8.906807 -17.541854)
			(xy 9.005964 -17.625349) (xy 9.099738 -17.714847) (xy 9.187767 -17.810002) (xy 9.26971 -17.910445)
			(xy 9.345249 -18.015788) (xy 9.414094 -18.125624) (xy 9.475977 -18.239528) (xy 9.530658 -18.357058)
			(xy 9.577928 -18.477761) (xy 9.617601 -18.601169) (xy 9.649526 -18.726805) (xy 9.673578 -18.854182)
			(xy 9.689665 -18.982808) (xy 9.697724 -19.112186) (xy 9.698228 -19.177) (xy 9.697724 -19.241814)
			(xy 9.689665 -19.371192) (xy 9.673578 -19.499818) (xy 9.649526 -19.627195) (xy 9.617601 -19.752831)
			(xy 9.577928 -19.876239) (xy 9.530658 -19.996942) (xy 9.524527 -20.01012) (xy 86.877404 -20.01012)
			(xy 86.881424 -19.819469) (xy 86.893478 -19.629156) (xy 86.913544 -19.439521) (xy 86.941587 -19.2509)
			(xy 86.977556 -19.06363) (xy 87.021388 -18.878042) (xy 87.073005 -18.694467) (xy 87.132315 -18.513231)
			(xy 87.199213 -18.334656) (xy 87.273579 -18.159061) (xy 87.355281 -17.986756) (xy 87.444175 -17.818049)
			(xy 87.540101 -17.653239) (xy 87.64289 -17.49262) (xy 87.752359 -17.336477) (xy 87.868313 -17.185088)
			(xy 87.990547 -17.038721) (xy 88.118841 -16.897637) (xy 88.252969 -16.762088) (xy 88.392693 -16.632313)
			(xy 88.537763 -16.508543) (xy 88.687921 -16.391) (xy 88.842902 -16.279891) (xy 89.002429 -16.175414)
			(xy 89.166218 -16.077755) (xy 89.333978 -15.987088) (xy 89.505412 -15.903574) (xy 89.680214 -15.827361)
			(xy 89.858073 -15.758585) (xy 90.038674 -15.697367) (xy 90.221694 -15.643818) (xy 90.40681 -15.598032)
			(xy 90.593691 -15.56009) (xy 90.782006 -15.530061) (xy 90.971419 -15.507996) (xy 91.161593 -15.493937)
			(xy 91.352192 -15.487907) (xy 91.542875 -15.489917) (xy 91.733304 -15.499964) (xy 91.92314 -15.51803)
			(xy 92.112046 -15.544083) (xy 92.299685 -15.578076) (xy 92.485725 -15.619949) (xy 92.669834 -15.669628)
			(xy 92.851685 -15.727024) (xy 93.030955 -15.792035) (xy 93.207325 -15.864546) (xy 93.380481 -15.944427)
			(xy 93.550116 -16.031537) (xy 93.715928 -16.125721) (xy 93.877622 -16.226812) (xy 94.03491 -16.334628)
			(xy 94.187513 -16.44898) (xy 94.335161 -16.569663) (xy 94.477589 -16.696464) (xy 94.614545 -16.829155)
			(xy 94.745786 -16.967503) (xy 94.871078 -17.11126) (xy 94.990198 -17.260171) (xy 95.102934 -17.413972)
			(xy 95.209087 -17.572388) (xy 95.308467 -17.735139) (xy 95.400897 -17.901934) (xy 95.486214 -18.072478)
			(xy 95.564266 -18.246466) (xy 95.634913 -18.423591) (xy 95.698031 -18.603536) (xy 95.753507 -18.785982)
			(xy 95.801242 -18.970605) (xy 95.841152 -19.157075) (xy 95.873165 -19.345063) (xy 95.897225 -19.534233)
			(xy 95.913288 -19.724249) (xy 95.921327 -19.914773) (xy 95.92183 -20.01012) (xy 95.921327 -20.105467)
			(xy 95.913288 -20.295991) (xy 95.897225 -20.486007) (xy 95.873165 -20.675177) (xy 95.841152 -20.863165)
			(xy 95.801242 -21.049635) (xy 95.753507 -21.234258) (xy 95.698031 -21.416704) (xy 95.634913 -21.596649)
			(xy 95.564266 -21.773774) (xy 95.486214 -21.947762) (xy 95.400897 -22.118306) (xy 95.308467 -22.285101)
			(xy 95.209087 -22.447852) (xy 95.102934 -22.606268) (xy 94.990198 -22.760069) (xy 94.871078 -22.90898)
			(xy 94.745786 -23.052737) (xy 94.614545 -23.191085) (xy 94.477589 -23.323776) (xy 94.335161 -23.450577)
			(xy 94.187513 -23.57126) (xy 94.03491 -23.685612) (xy 93.877622 -23.793428) (xy 93.715928 -23.894519)
			(xy 93.550116 -23.988703) (xy 93.380481 -24.075813) (xy 93.207325 -24.155694) (xy 93.030955 -24.228205)
			(xy 92.851685 -24.293216) (xy 92.669834 -24.350612) (xy 92.485725 -24.400291) (xy 92.299685 -24.442164)
			(xy 92.112046 -24.476157) (xy 91.92314 -24.50221) (xy 91.733304 -24.520276) (xy 91.542875 -24.530323)
			(xy 91.352192 -24.532333) (xy 91.161593 -24.526303) (xy 90.971419 -24.512244) (xy 90.782006 -24.490179)
			(xy 90.593691 -24.46015) (xy 90.40681 -24.422208) (xy 90.221694 -24.376422) (xy 90.038674 -24.322873)
			(xy 89.858073 -24.261655) (xy 89.680214 -24.192879) (xy 89.505412 -24.116666) (xy 89.333978 -24.033152)
			(xy 89.166218 -23.942485) (xy 89.002429 -23.844826) (xy 88.842902 -23.740349) (xy 88.687921 -23.62924)
			(xy 88.537763 -23.511697) (xy 88.392693 -23.387927) (xy 88.252969 -23.258152) (xy 88.118841 -23.122603)
			(xy 87.990547 -22.981519) (xy 87.868313 -22.835152) (xy 87.752359 -22.683763) (xy 87.64289 -22.52762)
			(xy 87.540101 -22.367001) (xy 87.444175 -22.202191) (xy 87.355281 -22.033484) (xy 87.273579 -21.861179)
			(xy 87.199213 -21.685584) (xy 87.132315 -21.507009) (xy 87.073005 -21.325773) (xy 87.021388 -21.142198)
			(xy 86.977556 -20.95661) (xy 86.941587 -20.76934) (xy 86.913544 -20.580719) (xy 86.893478 -20.391084)
			(xy 86.881424 -20.200771) (xy 86.877404 -20.01012) (xy 9.524527 -20.01012) (xy 9.475977 -20.114472)
			(xy 9.414094 -20.228376) (xy 9.345249 -20.338212) (xy 9.26971 -20.443555) (xy 9.187767 -20.543998)
			(xy 9.099738 -20.639153) (xy 9.005964 -20.728651) (xy 8.906807 -20.812146) (xy 8.802651 -20.889315)
			(xy 8.693899 -20.959859) (xy 8.580971 -21.023506) (xy 8.464306 -21.080009) (xy 8.344353 -21.12915)
			(xy 8.221577 -21.170738) (xy 8.096453 -21.204613) (xy 7.969465 -21.230643) (xy 7.841104 -21.248728)
			(xy 7.711868 -21.258798) (xy 7.582255 -21.260814) (xy 7.452768 -21.254768) (xy 7.323907 -21.240684)
			(xy 7.196171 -21.218615) (xy 7.070054 -21.188648) (xy 6.946044 -21.150899) (xy 6.824621 -21.105512)
			(xy 6.706254 -21.052665) (xy 6.591402 -20.992561) (xy 6.480509 -20.925433) (xy 6.374003 -20.851541)
			(xy 6.272297 -20.77117) (xy 6.175785 -20.684632) (xy 6.08484 -20.59226) (xy 5.999813 -20.494414)
			(xy 5.921033 -20.391471) (xy 5.848806 -20.283829) (xy 5.783411 -20.171905) (xy 5.7251 -20.056132)
			(xy 5.6741 -19.936958) (xy 5.630608 -19.814844) (xy 5.594791 -19.690261) (xy 5.566789 -19.563694)
			(xy 5.54671 -19.43563) (xy 5.534631 -19.306566) (xy 5.5306 -19.177) (xy 0.509016 -19.177) (xy 0.509016 -25.909778)
			(xy 6.671831 -25.909778) (xy 6.675786 -25.817941) (xy 6.687621 -25.726784) (xy 6.707248 -25.636981)
			(xy 6.734522 -25.549199) (xy 6.769242 -25.464085) (xy 6.81115 -25.382272) (xy 6.859936 -25.304364)
			(xy 6.915239 -25.230939) (xy 6.976649 -25.162539) (xy 7.043711 -25.099672) (xy 7.11593 -25.042802)
			(xy 7.19277 -24.992351) (xy 7.273663 -24.948692) (xy 7.358009 -24.912149) (xy 7.445185 -24.882992)
			(xy 7.534544 -24.861438) (xy 7.625425 -24.847644) (xy 7.717156 -24.841714) (xy 7.809057 -24.843692)
			(xy 7.900448 -24.853563) (xy 7.990652 -24.871253) (xy 8.079001 -24.896633) (xy 8.164841 -24.929513)
			(xy 8.247537 -24.969651) (xy 8.326477 -25.01675) (xy 8.401075 -25.07046) (xy 8.470781 -25.130384)
			(xy 8.535076 -25.196078) (xy 8.593487 -25.267056) (xy 8.645579 -25.342793) (xy 8.690968 -25.422728)
			(xy 8.729318 -25.506268) (xy 8.760343 -25.592796) (xy 8.783816 -25.681671) (xy 8.799562 -25.772235)
			(xy 8.807464 -25.863817) (xy 8.807958 -25.909778) (xy 8.807464 -25.955739) (xy 8.799562 -26.047321)
			(xy 8.783816 -26.137885) (xy 8.760343 -26.22676) (xy 8.729318 -26.313288) (xy 8.690968 -26.396828)
			(xy 8.645579 -26.476763) (xy 8.593487 -26.5525) (xy 8.535076 -26.623478) (xy 8.470781 -26.689172)
			(xy 8.401075 -26.749096) (xy 8.326477 -26.802806) (xy 8.247537 -26.849905) (xy 8.164841 -26.890043)
			(xy 8.079001 -26.922923) (xy 7.990652 -26.948303) (xy 7.900448 -26.965993) (xy 7.809057 -26.975864)
			(xy 7.717156 -26.977842) (xy 7.625425 -26.971912) (xy 7.534544 -26.958118) (xy 7.445185 -26.936564)
			(xy 7.358009 -26.907407) (xy 7.273663 -26.870864) (xy 7.19277 -26.827205) (xy 7.11593 -26.776754)
			(xy 7.043711 -26.719884) (xy 6.976649 -26.657017) (xy 6.915239 -26.588617) (xy 6.859936 -26.515192)
			(xy 6.81115 -26.437284) (xy 6.769242 -26.355471) (xy 6.734522 -26.270357) (xy 6.707248 -26.182575)
			(xy 6.687621 -26.092772) (xy 6.675786 -26.001615) (xy 6.671831 -25.909778) (xy 0.509016 -25.909778)
			(xy 0.509016 -29.19984) (xy 14.086591 -29.19984) (xy 14.090616 -29.057648) (xy 14.102679 -28.915912)
			(xy 14.122742 -28.775086) (xy 14.15074 -28.63562) (xy 14.186584 -28.497961) (xy 14.230158 -28.362551)
			(xy 14.281323 -28.229823) (xy 14.339916 -28.100202) (xy 14.405747 -27.974104) (xy 14.478608 -27.851932)
			(xy 14.558263 -27.734078) (xy 14.644459 -27.620919) (xy 14.736918 -27.512817) (xy 14.835346 -27.41012)
			(xy 14.939425 -27.313156) (xy 15.048824 -27.222236) (xy 15.163192 -27.13765) (xy 15.282161 -27.05967)
			(xy 15.405352 -26.988546) (xy 15.532369 -26.924505) (xy 15.662806 -26.867753) (xy 15.796245 -26.818471)
			(xy 15.932258 -26.776817) (xy 16.07041 -26.742925) (xy 16.210259 -26.716904) (xy 16.351355 -26.698836)
			(xy 16.493247 -26.688779) (xy 16.635482 -26.686766) (xy 16.777602 -26.692803) (xy 16.919153 -26.706871)
			(xy 17.059682 -26.728925) (xy 17.198737 -26.758894) (xy 17.335875 -26.796682) (xy 17.470655 -26.842168)
			(xy 17.602646 -26.895206) (xy 17.731425 -26.955627) (xy 17.856579 -27.023236) (xy 17.977707 -27.097818)
			(xy 18.094423 -27.179134) (xy 18.206351 -27.266922) (xy 18.313133 -27.360902) (xy 18.414427 -27.460772)
			(xy 18.509908 -27.566214) (xy 18.599272 -27.676888) (xy 18.68223 -27.792441) (xy 18.758519 -27.912502)
			(xy 18.827893 -28.036687) (xy 18.89013 -28.164598) (xy 18.945031 -28.295825) (xy 18.992419 -28.429948)
			(xy 19.032144 -28.566537) (xy 19.064077 -28.705155) (xy 19.088118 -28.845357) (xy 19.104187 -28.986695)
			(xy 19.112235 -29.128716) (xy 19.112738 -29.19984) (xy 19.112235 -29.270964) (xy 19.104187 -29.412985)
			(xy 19.088118 -29.554323) (xy 19.064077 -29.694525) (xy 19.032144 -29.833143) (xy 18.992419 -29.969732)
			(xy 18.945031 -30.103855) (xy 18.89013 -30.235082) (xy 18.827893 -30.362993) (xy 18.758519 -30.487178)
			(xy 18.68223 -30.607239) (xy 18.599272 -30.722792) (xy 18.509908 -30.833466) (xy 18.414427 -30.938908)
			(xy 18.313133 -31.038778) (xy 18.206351 -31.132758) (xy 18.094423 -31.220546) (xy 17.977707 -31.301862)
			(xy 17.856579 -31.376444) (xy 17.731425 -31.444053) (xy 17.602646 -31.504474) (xy 17.470655 -31.557512)
			(xy 17.335875 -31.602998) (xy 17.198737 -31.640786) (xy 17.059682 -31.670755) (xy 16.919153 -31.692809)
			(xy 16.777602 -31.706877) (xy 16.635482 -31.712914) (xy 16.493247 -31.710901) (xy 16.351355 -31.700844)
			(xy 16.210259 -31.682776) (xy 16.07041 -31.656755) (xy 15.932258 -31.622863) (xy 15.796245 -31.581209)
			(xy 15.662806 -31.531927) (xy 15.532369 -31.475175) (xy 15.405352 -31.411134) (xy 15.282161 -31.34001)
			(xy 15.163192 -31.26203) (xy 15.048824 -31.177444) (xy 14.939425 -31.086524) (xy 14.835346 -30.98956)
			(xy 14.736918 -30.886863) (xy 14.644459 -30.778761) (xy 14.558263 -30.665602) (xy 14.478608 -30.547748)
			(xy 14.405747 -30.425576) (xy 14.339916 -30.299478) (xy 14.281323 -30.169857) (xy 14.230158 -30.037129)
			(xy 14.186584 -29.901719) (xy 14.15074 -29.76406) (xy 14.122742 -29.624594) (xy 14.102679 -29.483768)
			(xy 14.090616 -29.342032) (xy 14.086591 -29.19984) (xy 0.509016 -29.19984) (xy 0.509016 -32.29991)
			(xy 75.486519 -32.29991) (xy 75.490544 -32.157718) (xy 75.502607 -32.015982) (xy 75.52267 -31.875156)
			(xy 75.550668 -31.73569) (xy 75.586512 -31.598031) (xy 75.630086 -31.462621) (xy 75.681251 -31.329893)
			(xy 75.739844 -31.200272) (xy 75.805675 -31.074174) (xy 75.878536 -30.952002) (xy 75.958191 -30.834148)
			(xy 76.044387 -30.720989) (xy 76.136846 -30.612887) (xy 76.235274 -30.51019) (xy 76.339353 -30.413226)
			(xy 76.448752 -30.322306) (xy 76.56312 -30.23772) (xy 76.682089 -30.15974) (xy 76.80528 -30.088616)
			(xy 76.932297 -30.024575) (xy 77.062734 -29.967823) (xy 77.196173 -29.918541) (xy 77.332186 -29.876887)
			(xy 77.470338 -29.842995) (xy 77.610187 -29.816974) (xy 77.751283 -29.798906) (xy 77.893175 -29.788849)
			(xy 78.03541 -29.786836) (xy 78.17753 -29.792873) (xy 78.319081 -29.806941) (xy 78.45961 -29.828995)
			(xy 78.598665 -29.858964) (xy 78.735803 -29.896752) (xy 78.870583 -29.942238) (xy 79.002574 -29.995276)
			(xy 79.131353 -30.055697) (xy 79.256507 -30.123306) (xy 79.377635 -30.197888) (xy 79.494351 -30.279204)
			(xy 79.606279 -30.366992) (xy 79.713061 -30.460972) (xy 79.814355 -30.560842) (xy 79.909836 -30.666284)
			(xy 79.9992 -30.776958) (xy 80.082158 -30.892511) (xy 80.158447 -31.012572) (xy 80.227821 -31.136757)
			(xy 80.290058 -31.264668) (xy 80.344959 -31.395895) (xy 80.392347 -31.530018) (xy 80.432072 -31.666607)
			(xy 80.464005 -31.805225) (xy 80.488046 -31.945427) (xy 80.504115 -32.086765) (xy 80.512163 -32.228786)
			(xy 80.512666 -32.29991) (xy 80.512163 -32.371034) (xy 80.504115 -32.513055) (xy 80.488046 -32.654393)
			(xy 80.464005 -32.794595) (xy 80.432072 -32.933213) (xy 80.392347 -33.069802) (xy 80.344959 -33.203925)
			(xy 80.290058 -33.335152) (xy 80.227821 -33.463063) (xy 80.158447 -33.587248) (xy 80.082158 -33.707309)
			(xy 79.9992 -33.822862) (xy 79.909836 -33.933536) (xy 79.814355 -34.038978) (xy 79.713061 -34.138848)
			(xy 79.606279 -34.232828) (xy 79.494351 -34.320616) (xy 79.377635 -34.401932) (xy 79.256507 -34.476514)
			(xy 79.131353 -34.544123) (xy 79.002574 -34.604544) (xy 78.870583 -34.657582) (xy 78.735803 -34.703068)
			(xy 78.598665 -34.740856) (xy 78.45961 -34.770825) (xy 78.319081 -34.792879) (xy 78.17753 -34.806947)
			(xy 78.03541 -34.812984) (xy 77.893175 -34.810971) (xy 77.751283 -34.800914) (xy 77.610187 -34.782846)
			(xy 77.470338 -34.756825) (xy 77.332186 -34.722933) (xy 77.196173 -34.681279) (xy 77.062734 -34.631997)
			(xy 76.932297 -34.575245) (xy 76.80528 -34.511204) (xy 76.682089 -34.44008) (xy 76.56312 -34.3621)
			(xy 76.448752 -34.277514) (xy 76.339353 -34.186594) (xy 76.235274 -34.08963) (xy 76.136846 -33.986933)
			(xy 76.044387 -33.878831) (xy 75.958191 -33.765672) (xy 75.878536 -33.647818) (xy 75.805675 -33.525646)
			(xy 75.739844 -33.399548) (xy 75.681251 -33.269927) (xy 75.630086 -33.137199) (xy 75.586512 -33.001789)
			(xy 75.550668 -32.86413) (xy 75.52267 -32.724664) (xy 75.502607 -32.583838) (xy 75.490544 -32.442102)
			(xy 75.486519 -32.29991) (xy 0.509016 -32.29991) (xy 0.509016 -34.90976) (xy 6.671831 -34.90976)
			(xy 6.675786 -34.817923) (xy 6.687621 -34.726766) (xy 6.707248 -34.636963) (xy 6.734522 -34.549181)
			(xy 6.769242 -34.464067) (xy 6.81115 -34.382254) (xy 6.859936 -34.304346) (xy 6.915239 -34.230921)
			(xy 6.976649 -34.162521) (xy 7.043711 -34.099654) (xy 7.11593 -34.042784) (xy 7.19277 -33.992333)
			(xy 7.273663 -33.948674) (xy 7.358009 -33.912131) (xy 7.445185 -33.882974) (xy 7.534544 -33.86142)
			(xy 7.625425 -33.847626) (xy 7.717156 -33.841696) (xy 7.809057 -33.843674) (xy 7.900448 -33.853545)
			(xy 7.990652 -33.871235) (xy 8.079001 -33.896615) (xy 8.164841 -33.929495) (xy 8.247537 -33.969633)
			(xy 8.326477 -34.016732) (xy 8.401075 -34.070442) (xy 8.470781 -34.130366) (xy 8.535076 -34.19606)
			(xy 8.593487 -34.267038) (xy 8.645579 -34.342775) (xy 8.690968 -34.42271) (xy 8.729318 -34.50625)
			(xy 8.760343 -34.592778) (xy 8.783816 -34.681653) (xy 8.799562 -34.772217) (xy 8.807464 -34.863799)
			(xy 8.807958 -34.90976) (xy 8.807464 -34.955721) (xy 8.799562 -35.047303) (xy 8.783816 -35.137867)
			(xy 8.760343 -35.226742) (xy 8.729318 -35.31327) (xy 8.690968 -35.39681) (xy 8.645579 -35.476745)
			(xy 8.593487 -35.552482) (xy 8.535076 -35.62346) (xy 8.470781 -35.689154) (xy 8.401075 -35.749078)
			(xy 8.326477 -35.802788) (xy 8.247537 -35.849887) (xy 8.164841 -35.890025) (xy 8.079001 -35.922905)
			(xy 7.990652 -35.948285) (xy 7.900448 -35.965975) (xy 7.809057 -35.975846) (xy 7.717156 -35.977824)
			(xy 7.625425 -35.971894) (xy 7.534544 -35.9581) (xy 7.445185 -35.936546) (xy 7.358009 -35.907389)
			(xy 7.273663 -35.870846) (xy 7.19277 -35.827187) (xy 7.11593 -35.776736) (xy 7.043711 -35.719866)
			(xy 6.976649 -35.656999) (xy 6.915239 -35.588599) (xy 6.859936 -35.515174) (xy 6.81115 -35.437266)
			(xy 6.769242 -35.355453) (xy 6.734522 -35.270339) (xy 6.707248 -35.182557) (xy 6.687621 -35.092754)
			(xy 6.675786 -35.001597) (xy 6.671831 -34.90976) (xy 0.509016 -34.90976) (xy 0.509016 -42.291) (xy 5.5306 -42.291)
			(xy 5.534631 -42.161434) (xy 5.54671 -42.03237) (xy 5.566789 -41.904306) (xy 5.594791 -41.777739)
			(xy 5.630608 -41.653156) (xy 5.6741 -41.531042) (xy 5.7251 -41.411868) (xy 5.783411 -41.296095) (xy 5.848806 -41.184171)
			(xy 5.921033 -41.076529) (xy 5.999813 -40.973586) (xy 6.08484 -40.87574) (xy 6.175785 -40.783368)
			(xy 6.272297 -40.69683) (xy 6.374003 -40.616459) (xy 6.480509 -40.542567) (xy 6.591402 -40.475439)
			(xy 6.706254 -40.415335) (xy 6.824621 -40.362488) (xy 6.946044 -40.317101) (xy 7.070054 -40.279352)
			(xy 7.196171 -40.249385) (xy 7.323907 -40.227316) (xy 7.452768 -40.213232) (xy 7.582255 -40.207186)
			(xy 7.711868 -40.209202) (xy 7.841104 -40.219272) (xy 7.969465 -40.237357) (xy 8.096453 -40.263387)
			(xy 8.221577 -40.297262) (xy 8.344353 -40.33885) (xy 8.464306 -40.387991) (xy 8.580971 -40.444494)
			(xy 8.693899 -40.508141) (xy 8.802651 -40.578685) (xy 8.906807 -40.655854) (xy 9.005964 -40.739349)
			(xy 9.099738 -40.828847) (xy 9.187767 -40.924002) (xy 9.26971 -41.024445) (xy 9.345249 -41.129788)
			(xy 9.414094 -41.239624) (xy 9.475977 -41.353528) (xy 9.530658 -41.471058) (xy 9.577928 -41.591761)
			(xy 9.617601 -41.715169) (xy 9.649526 -41.840805) (xy 9.673578 -41.968182) (xy 9.689665 -42.096808)
			(xy 9.697724 -42.226186) (xy 9.698228 -42.291) (xy 9.697724 -42.355814) (xy 9.689665 -42.485192)
			(xy 9.673578 -42.613818) (xy 9.649526 -42.741195) (xy 9.617601 -42.866831) (xy 9.577928 -42.990239)
			(xy 9.530658 -43.110942) (xy 9.475977 -43.228472) (xy 9.414094 -43.342376) (xy 9.345249 -43.452212)
			(xy 9.26971 -43.557555) (xy 9.187767 -43.657998) (xy 9.099738 -43.753153) (xy 9.005964 -43.842651)
			(xy 8.906807 -43.926146) (xy 8.802651 -44.003315) (xy 8.693899 -44.073859) (xy 8.580971 -44.137506)
			(xy 8.464306 -44.194009) (xy 8.344353 -44.24315) (xy 8.221577 -44.284738) (xy 8.096453 -44.318613)
			(xy 7.969465 -44.344643) (xy 7.841104 -44.362728) (xy 7.711868 -44.372798) (xy 7.582255 -44.374814)
			(xy 7.452768 -44.368768) (xy 7.323907 -44.354684) (xy 7.196171 -44.332615) (xy 7.070054 -44.302648)
			(xy 6.946044 -44.264899) (xy 6.824621 -44.219512) (xy 6.706254 -44.166665) (xy 6.591402 -44.106561)
			(xy 6.480509 -44.039433) (xy 6.374003 -43.965541) (xy 6.272297 -43.88517) (xy 6.175785 -43.798632)
			(xy 6.08484 -43.70626) (xy 5.999813 -43.608414) (xy 5.921033 -43.505471) (xy 5.848806 -43.397829)
			(xy 5.783411 -43.285905) (xy 5.7251 -43.170132) (xy 5.6741 -43.050958) (xy 5.630608 -42.928844) (xy 5.594791 -42.804261)
			(xy 5.566789 -42.677694) (xy 5.54671 -42.54963) (xy 5.534631 -42.420566) (xy 5.5306 -42.291) (xy 0.509016 -42.291)
			(xy 0.509016 -51.36007) (xy 39.818564 -51.36007) (xy 39.819054 -51.302663) (xy 39.826889 -51.188117)
			(xy 39.842523 -51.074372) (xy 39.865882 -50.96196) (xy 39.896859 -50.851403) (xy 39.935308 -50.743218)
			(xy 39.98105 -50.63791) (xy 40.033872 -50.535968) (xy 40.093527 -50.437869) (xy 40.159738 -50.344069)
			(xy 40.232196 -50.255007) (xy 40.310562 -50.171096) (xy 40.394473 -50.09273) (xy 40.483535 -50.020272)
			(xy 40.577335 -49.954061) (xy 40.675434 -49.894406) (xy 40.777376 -49.841584) (xy 40.882684 -49.795842)
			(xy 40.990869 -49.757393) (xy 41.101426 -49.726416) (xy 41.213838 -49.703057) (xy 41.327583 -49.687423)
			(xy 41.442129 -49.679588) (xy 41.556943 -49.679588) (xy 41.671489 -49.687423) (xy 41.785234 -49.703057)
			(xy 41.897646 -49.726416) (xy 42.008203 -49.757393) (xy 42.116388 -49.795842) (xy 42.221696 -49.841584)
			(xy 42.323638 -49.894406) (xy 42.421737 -49.954061) (xy 42.515537 -50.020272) (xy 42.604599 -50.09273)
			(xy 42.68851 -50.171096) (xy 42.766876 -50.255007) (xy 42.839334 -50.344069) (xy 42.905545 -50.437869)
			(xy 42.9652 -50.535968) (xy 43.018022 -50.63791) (xy 43.063764 -50.743218) (xy 43.102213 -50.851403)
			(xy 43.13319 -50.96196) (xy 43.156549 -51.074372) (xy 43.172183 -51.188117) (xy 43.180018 -51.302663)
			(xy 43.180508 -51.36007) (xy 43.180381 -51.393251) (xy 43.177842 -51.459565) (xy 43.175428 -51.492658)
			(xy 43.170272 -51.550942) (xy 43.152948 -51.666671) (xy 43.127616 -51.780914) (xy 43.094401 -51.893119)
			(xy 43.053462 -52.002742) (xy 43.004999 -52.109253) (xy 42.949245 -52.212135) (xy 42.886471 -52.310891)
			(xy 42.816981 -52.405042) (xy 42.741111 -52.494132) (xy 42.659229 -52.577729) (xy 42.571732 -52.65543)
			(xy 42.500813 -52.71008) (xy 93.154506 -52.71008) (xy 93.158522 -52.59381) (xy 93.170549 -52.478095)
			(xy 93.190531 -52.363485) (xy 93.218373 -52.250526) (xy 93.253942 -52.139758) (xy 93.297068 -52.031707)
			(xy 93.347545 -51.926889) (xy 93.405134 -51.825804) (xy 93.46956 -51.728932) (xy 93.540515 -51.636736)
			(xy 93.617662 -51.549655) (xy 93.700633 -51.468104) (xy 93.789033 -51.392472) (xy 93.88244 -51.323118)
			(xy 93.980409 -51.260375) (xy 94.082473 -51.204539) (xy 94.188147 -51.155878) (xy 94.296926 -51.114624)
			(xy 94.408291 -51.080973) (xy 94.521714 -51.055085) (xy 94.636651 -51.037084) (xy 94.752557 -51.027055)
			(xy 94.868879 -51.025047) (xy 94.985062 -51.031069) (xy 95.100553 -51.045092) (xy 95.214801 -51.06705)
			(xy 95.327262 -51.096837) (xy 95.4374 -51.134312) (xy 95.54469 -51.179297) (xy 95.648621 -51.231576)
			(xy 95.748697 -51.290901) (xy 95.844443 -51.356989) (xy 95.9354 -51.429525) (xy 96.021136 -51.508164)
			(xy 96.101243 -51.59253) (xy 96.175339 -51.682222) (xy 96.243069 -51.776812) (xy 96.304113 -51.87585)
			(xy 96.358178 -51.978863) (xy 96.405008 -52.08536) (xy 96.444379 -52.194835) (xy 96.476103 -52.306765)
			(xy 96.500029 -52.420617) (xy 96.516043 -52.535849) (xy 96.52407 -52.651911) (xy 96.524572 -52.71008)
			(xy 96.52407 -52.768249) (xy 96.516043 -52.884311) (xy 96.500029 -52.999543) (xy 96.476103 -53.113395)
			(xy 96.444379 -53.225325) (xy 96.405008 -53.3348) (xy 96.358178 -53.441297) (xy 96.304113 -53.54431)
			(xy 96.243069 -53.643348) (xy 96.175339 -53.737938) (xy 96.101243 -53.82763) (xy 96.021136 -53.911996)
			(xy 95.9354 -53.990635) (xy 95.844443 -54.063171) (xy 95.748697 -54.129259) (xy 95.648621 -54.188584)
			(xy 95.54469 -54.240863) (xy 95.4374 -54.285848) (xy 95.327262 -54.323323) (xy 95.214801 -54.35311)
			(xy 95.100553 -54.375068) (xy 94.985062 -54.389091) (xy 94.868879 -54.395113) (xy 94.752557 -54.393105)
			(xy 94.636651 -54.383076) (xy 94.521714 -54.365075) (xy 94.408291 -54.339187) (xy 94.296926 -54.305536)
			(xy 94.188147 -54.264282) (xy 94.082473 -54.215621) (xy 93.980409 -54.159785) (xy 93.88244 -54.097042)
			(xy 93.789033 -54.027688) (xy 93.700633 -53.952056) (xy 93.617662 -53.870505) (xy 93.540515 -53.783424)
			(xy 93.46956 -53.691228) (xy 93.405134 -53.594356) (xy 93.347545 -53.493271) (xy 93.297068 -53.388453)
			(xy 93.253942 -53.280402) (xy 93.218373 -53.169634) (xy 93.190531 -53.056675) (xy 93.170549 -52.942065)
			(xy 93.158522 -52.82635) (xy 93.154506 -52.71008) (xy 42.500813 -52.71008) (xy 42.479042 -52.726857)
			(xy 42.381609 -52.791665) (xy 42.279905 -52.84954) (xy 42.174422 -52.900202) (xy 42.065671 -52.943404)
			(xy 41.954179 -52.978939) (xy 41.840485 -53.006634) (xy 41.725141 -53.026354) (xy 41.608704 -53.038005)
			(xy 41.491739 -53.04153) (xy 41.374812 -53.036912) (xy 41.258489 -53.024173) (xy 41.143334 -53.003375)
			(xy 41.029905 -52.974618) (xy 40.91875 -52.938042) (xy 40.810407 -52.893825) (xy 40.705403 -52.842179)
			(xy 40.604244 -52.783356) (xy 40.507421 -52.71764) (xy 40.415403 -52.645349) (xy 40.328636 -52.566834)
			(xy 40.247539 -52.482474) (xy 40.172506 -52.392679) (xy 40.103899 -52.297883) (xy 40.042051 -52.198544)
			(xy 39.987262 -52.095145) (xy 39.939796 -51.988186) (xy 39.899884 -51.878185) (xy 39.86772 -51.765674)
			(xy 39.843457 -51.651199) (xy 39.827215 -51.535313) (xy 39.819072 -51.418579) (xy 39.818564 -51.36007)
			(xy 0.509016 -51.36007) (xy 0.509016 -53.721) (xy 5.5306 -53.721) (xy 5.534631 -53.591434) (xy 5.54671 -53.46237)
			(xy 5.566789 -53.334306) (xy 5.594791 -53.207739) (xy 5.630608 -53.083156) (xy 5.6741 -52.961042)
			(xy 5.7251 -52.841868) (xy 5.783411 -52.726095) (xy 5.848806 -52.614171) (xy 5.921033 -52.506529)
			(xy 5.999813 -52.403586) (xy 6.08484 -52.30574) (xy 6.175785 -52.213368) (xy 6.272297 -52.12683)
			(xy 6.374003 -52.046459) (xy 6.480509 -51.972567) (xy 6.591402 -51.905439) (xy 6.706254 -51.845335)
			(xy 6.824621 -51.792488) (xy 6.946044 -51.747101) (xy 7.070054 -51.709352) (xy 7.196171 -51.679385)
			(xy 7.323907 -51.657316) (xy 7.452768 -51.643232) (xy 7.582255 -51.637186) (xy 7.711868 -51.639202)
			(xy 7.841104 -51.649272) (xy 7.969465 -51.667357) (xy 8.096453 -51.693387) (xy 8.221577 -51.727262)
			(xy 8.344353 -51.76885) (xy 8.464306 -51.817991) (xy 8.580971 -51.874494) (xy 8.693899 -51.938141)
			(xy 8.802651 -52.008685) (xy 8.906807 -52.085854) (xy 9.005964 -52.169349) (xy 9.099738 -52.258847)
			(xy 9.187767 -52.354002) (xy 9.26971 -52.454445) (xy 9.345249 -52.559788) (xy 9.414094 -52.669624)
			(xy 9.475977 -52.783528) (xy 9.530658 -52.901058) (xy 9.577928 -53.021761) (xy 9.617601 -53.145169)
			(xy 9.649526 -53.270805) (xy 9.673578 -53.398182) (xy 9.689665 -53.526808) (xy 9.697724 -53.656186)
			(xy 9.698228 -53.721) (xy 9.697724 -53.785814) (xy 9.689665 -53.915192) (xy 9.673578 -54.043818)
			(xy 9.649526 -54.171195) (xy 9.617601 -54.296831) (xy 9.577928 -54.420239) (xy 9.530658 -54.540942)
			(xy 9.475977 -54.658472) (xy 9.414094 -54.772376) (xy 9.345249 -54.882212) (xy 9.26971 -54.987555)
			(xy 9.187767 -55.087998) (xy 9.099738 -55.183153) (xy 9.005964 -55.272651) (xy 8.906807 -55.356146)
			(xy 8.802651 -55.433315) (xy 8.693899 -55.503859) (xy 8.580971 -55.567506) (xy 8.464306 -55.624009)
			(xy 8.344353 -55.67315) (xy 8.221577 -55.714738) (xy 8.096453 -55.748613) (xy 7.969465 -55.774643)
			(xy 7.841104 -55.792728) (xy 7.711868 -55.802798) (xy 7.582255 -55.804814) (xy 7.452768 -55.798768)
			(xy 7.323907 -55.784684) (xy 7.196171 -55.762615) (xy 7.070054 -55.732648) (xy 6.946044 -55.694899)
			(xy 6.824621 -55.649512) (xy 6.706254 -55.596665) (xy 6.591402 -55.536561) (xy 6.480509 -55.469433)
			(xy 6.374003 -55.395541) (xy 6.272297 -55.31517) (xy 6.175785 -55.228632) (xy 6.08484 -55.13626)
			(xy 5.999813 -55.038414) (xy 5.921033 -54.935471) (xy 5.848806 -54.827829) (xy 5.783411 -54.715905)
			(xy 5.7251 -54.600132) (xy 5.6741 -54.480958) (xy 5.630608 -54.358844) (xy 5.594791 -54.234261) (xy 5.566789 -54.107694)
			(xy 5.54671 -53.97963) (xy 5.534631 -53.850566) (xy 5.5306 -53.721) (xy 0.509016 -53.721) (xy 0.509016 -60.833)
			(xy 5.5306 -60.833) (xy 5.534631 -60.703434) (xy 5.54671 -60.57437) (xy 5.566789 -60.446306) (xy 5.594791 -60.319739)
			(xy 5.630608 -60.195156) (xy 5.6741 -60.073042) (xy 5.7251 -59.953868) (xy 5.783411 -59.838095) (xy 5.848806 -59.726171)
			(xy 5.921033 -59.618529) (xy 5.999813 -59.515586) (xy 6.08484 -59.41774) (xy 6.175785 -59.325368)
			(xy 6.272297 -59.23883) (xy 6.374003 -59.158459) (xy 6.480509 -59.084567) (xy 6.591402 -59.017439)
			(xy 6.706254 -58.957335) (xy 6.824621 -58.904488) (xy 6.946044 -58.859101) (xy 7.070054 -58.821352)
			(xy 7.196171 -58.791385) (xy 7.323907 -58.769316) (xy 7.452768 -58.755232) (xy 7.582255 -58.749186)
			(xy 7.711868 -58.751202) (xy 7.841104 -58.761272) (xy 7.969465 -58.779357) (xy 8.096453 -58.805387)
			(xy 8.221577 -58.839262) (xy 8.344353 -58.88085) (xy 8.464306 -58.929991) (xy 8.580971 -58.986494)
			(xy 8.693899 -59.050141) (xy 8.802651 -59.120685) (xy 8.906807 -59.197854) (xy 9.005964 -59.281349)
			(xy 9.099738 -59.370847) (xy 9.187767 -59.466002) (xy 9.26971 -59.566445) (xy 9.345249 -59.671788)
			(xy 9.414094 -59.781624) (xy 9.475977 -59.895528) (xy 9.530658 -60.013058) (xy 9.577928 -60.133761)
			(xy 9.617601 -60.257169) (xy 9.649526 -60.382805) (xy 9.673578 -60.510182) (xy 9.689665 -60.638808)
			(xy 9.697724 -60.768186) (xy 9.698228 -60.833) (xy 9.697724 -60.897814) (xy 9.689665 -61.027192)
			(xy 9.673578 -61.155818) (xy 9.649526 -61.283195) (xy 9.617601 -61.408831) (xy 9.577928 -61.532239)
			(xy 9.530658 -61.652942) (xy 9.475977 -61.770472) (xy 9.414094 -61.884376) (xy 9.345249 -61.994212)
			(xy 9.26971 -62.099555) (xy 9.187767 -62.199998) (xy 9.099738 -62.295153) (xy 9.005964 -62.384651)
			(xy 8.906807 -62.468146) (xy 8.802651 -62.545315) (xy 8.693899 -62.615859) (xy 8.580971 -62.679506)
			(xy 8.464306 -62.736009) (xy 8.344353 -62.78515) (xy 8.221577 -62.826738) (xy 8.096453 -62.860613)
			(xy 7.969465 -62.886643) (xy 7.841104 -62.904728) (xy 7.711868 -62.914798) (xy 7.582255 -62.916814)
			(xy 7.452768 -62.910768) (xy 7.323907 -62.896684) (xy 7.196171 -62.874615) (xy 7.070054 -62.844648)
			(xy 6.946044 -62.806899) (xy 6.824621 -62.761512) (xy 6.706254 -62.708665) (xy 6.591402 -62.648561)
			(xy 6.480509 -62.581433) (xy 6.374003 -62.507541) (xy 6.272297 -62.42717) (xy 6.175785 -62.340632)
			(xy 6.08484 -62.24826) (xy 5.999813 -62.150414) (xy 5.921033 -62.047471) (xy 5.848806 -61.939829)
			(xy 5.783411 -61.827905) (xy 5.7251 -61.712132) (xy 5.6741 -61.592958) (xy 5.630608 -61.470844) (xy 5.594791 -61.346261)
			(xy 5.566789 -61.219694) (xy 5.54671 -61.09163) (xy 5.534631 -60.962566) (xy 5.5306 -60.833) (xy 0.509016 -60.833)
			(xy 0.509016 -64.46012) (xy 86.877404 -64.46012) (xy 86.881424 -64.269469) (xy 86.893478 -64.079156)
			(xy 86.913544 -63.889521) (xy 86.941587 -63.7009) (xy 86.977556 -63.51363) (xy 87.021388 -63.328042)
			(xy 87.073005 -63.144467) (xy 87.132315 -62.963231) (xy 87.199213 -62.784656) (xy 87.273579 -62.609061)
			(xy 87.355281 -62.436756) (xy 87.444175 -62.268049) (xy 87.540101 -62.103239) (xy 87.64289 -61.94262)
			(xy 87.752359 -61.786477) (xy 87.868313 -61.635088) (xy 87.990547 -61.488721) (xy 88.118841 -61.347637)
			(xy 88.252969 -61.212088) (xy 88.392693 -61.082313) (xy 88.537763 -60.958543) (xy 88.687921 -60.841)
			(xy 88.842902 -60.729891) (xy 89.002429 -60.625414) (xy 89.166218 -60.527755) (xy 89.333978 -60.437088)
			(xy 89.505412 -60.353574) (xy 89.680214 -60.277361) (xy 89.858073 -60.208585) (xy 90.038674 -60.147367)
			(xy 90.221694 -60.093818) (xy 90.40681 -60.048032) (xy 90.593691 -60.01009) (xy 90.782006 -59.980061)
			(xy 90.971419 -59.957996) (xy 91.161593 -59.943937) (xy 91.352192 -59.937907) (xy 91.542875 -59.939917)
			(xy 91.733304 -59.949964) (xy 91.92314 -59.96803) (xy 92.112046 -59.994083) (xy 92.299685 -60.028076)
			(xy 92.485725 -60.069949) (xy 92.669834 -60.119628) (xy 92.851685 -60.177024) (xy 93.030955 -60.242035)
			(xy 93.207325 -60.314546) (xy 93.380481 -60.394427) (xy 93.550116 -60.481537) (xy 93.715928 -60.575721)
			(xy 93.877622 -60.676812) (xy 94.03491 -60.784628) (xy 94.187513 -60.89898) (xy 94.335161 -61.019663)
			(xy 94.477589 -61.146464) (xy 94.614545 -61.279155) (xy 94.745786 -61.417503) (xy 94.871078 -61.56126)
			(xy 94.990198 -61.710171) (xy 95.102934 -61.863972) (xy 95.209087 -62.022388) (xy 95.308467 -62.185139)
			(xy 95.400897 -62.351934) (xy 95.486214 -62.522478) (xy 95.564266 -62.696466) (xy 95.634913 -62.873591)
			(xy 95.698031 -63.053536) (xy 95.753507 -63.235982) (xy 95.801242 -63.420605) (xy 95.841152 -63.607075)
			(xy 95.873165 -63.795063) (xy 95.897225 -63.984233) (xy 95.913288 -64.174249) (xy 95.921327 -64.364773)
			(xy 95.92183 -64.46012) (xy 95.921327 -64.555467) (xy 95.913288 -64.745991) (xy 95.897225 -64.936007)
			(xy 95.873165 -65.125177) (xy 95.841152 -65.313165) (xy 95.801242 -65.499635) (xy 95.753507 -65.684258)
			(xy 95.698031 -65.866704) (xy 95.634913 -66.046649) (xy 95.564266 -66.223774) (xy 95.486214 -66.397762)
			(xy 95.400897 -66.568306) (xy 95.308467 -66.735101) (xy 95.209087 -66.897852) (xy 95.102934 -67.056268)
			(xy 94.990198 -67.210069) (xy 94.871078 -67.35898) (xy 94.745786 -67.502737) (xy 94.614545 -67.641085)
			(xy 94.477589 -67.773776) (xy 94.335161 -67.900577) (xy 94.187513 -68.02126) (xy 94.03491 -68.135612)
			(xy 93.877622 -68.243428) (xy 93.715928 -68.344519) (xy 93.550116 -68.438703) (xy 93.380481 -68.525813)
			(xy 93.207325 -68.605694) (xy 93.030955 -68.678205) (xy 92.851685 -68.743216) (xy 92.669834 -68.800612)
			(xy 92.485725 -68.850291) (xy 92.299685 -68.892164) (xy 92.112046 -68.926157) (xy 91.92314 -68.95221)
			(xy 91.733304 -68.970276) (xy 91.542875 -68.980323) (xy 91.352192 -68.982333) (xy 91.161593 -68.976303)
			(xy 90.971419 -68.962244) (xy 90.782006 -68.940179) (xy 90.593691 -68.91015) (xy 90.40681 -68.872208)
			(xy 90.221694 -68.826422) (xy 90.038674 -68.772873) (xy 89.858073 -68.711655) (xy 89.680214 -68.642879)
			(xy 89.505412 -68.566666) (xy 89.333978 -68.483152) (xy 89.166218 -68.392485) (xy 89.002429 -68.294826)
			(xy 88.842902 -68.190349) (xy 88.687921 -68.07924) (xy 88.537763 -67.961697) (xy 88.392693 -67.837927)
			(xy 88.252969 -67.708152) (xy 88.118841 -67.572603) (xy 87.990547 -67.431519) (xy 87.868313 -67.285152)
			(xy 87.752359 -67.133763) (xy 87.64289 -66.97762) (xy 87.540101 -66.817001) (xy 87.444175 -66.652191)
			(xy 87.355281 -66.483484) (xy 87.273579 -66.311179) (xy 87.199213 -66.135584) (xy 87.132315 -65.957009)
			(xy 87.073005 -65.775773) (xy 87.021388 -65.592198) (xy 86.977556 -65.40661) (xy 86.941587 -65.21934)
			(xy 86.913544 -65.030719) (xy 86.893478 -64.841084) (xy 86.881424 -64.650771) (xy 86.877404 -64.46012)
			(xy 0.509016 -64.46012) (xy 0.509016 -72.263) (xy 5.5306 -72.263) (xy 5.534631 -72.133434) (xy 5.54671 -72.00437)
			(xy 5.566789 -71.876306) (xy 5.594791 -71.749739) (xy 5.630608 -71.625156) (xy 5.6741 -71.503042)
			(xy 5.7251 -71.383868) (xy 5.783411 -71.268095) (xy 5.848806 -71.156171) (xy 5.921033 -71.048529)
			(xy 5.999813 -70.945586) (xy 6.08484 -70.84774) (xy 6.175785 -70.755368) (xy 6.272297 -70.66883)
			(xy 6.374003 -70.588459) (xy 6.480509 -70.514567) (xy 6.591402 -70.447439) (xy 6.706254 -70.387335)
			(xy 6.824621 -70.334488) (xy 6.946044 -70.289101) (xy 7.070054 -70.251352) (xy 7.196171 -70.221385)
			(xy 7.323907 -70.199316) (xy 7.452768 -70.185232) (xy 7.582255 -70.179186) (xy 7.711868 -70.181202)
			(xy 7.841104 -70.191272) (xy 7.969465 -70.209357) (xy 8.096453 -70.235387) (xy 8.221577 -70.269262)
			(xy 8.344353 -70.31085) (xy 8.464306 -70.359991) (xy 8.580971 -70.416494) (xy 8.693899 -70.480141)
			(xy 8.802651 -70.550685) (xy 8.906807 -70.627854) (xy 9.005964 -70.711349) (xy 9.099738 -70.800847)
			(xy 9.187767 -70.896002) (xy 9.26971 -70.996445) (xy 9.345249 -71.101788) (xy 9.414094 -71.211624)
			(xy 9.475977 -71.325528) (xy 9.530658 -71.443058) (xy 9.577928 -71.563761) (xy 9.617601 -71.687169)
			(xy 9.649526 -71.812805) (xy 9.673578 -71.940182) (xy 9.689665 -72.068808) (xy 9.697724 -72.198186)
			(xy 9.698228 -72.263) (xy 9.697724 -72.327814) (xy 9.689665 -72.457192) (xy 9.673578 -72.585818)
			(xy 9.649526 -72.713195) (xy 9.617601 -72.838831) (xy 9.577928 -72.962239) (xy 9.530658 -73.082942)
			(xy 9.475977 -73.200472) (xy 9.414094 -73.314376) (xy 9.345249 -73.424212) (xy 9.26971 -73.529555)
			(xy 9.187767 -73.629998) (xy 9.099738 -73.725153) (xy 9.005964 -73.814651) (xy 8.906807 -73.898146)
			(xy 8.802651 -73.975315) (xy 8.693899 -74.045859) (xy 8.580971 -74.109506) (xy 8.464306 -74.166009)
			(xy 8.344353 -74.21515) (xy 8.221577 -74.256738) (xy 8.096453 -74.290613) (xy 7.969465 -74.316643)
			(xy 7.841104 -74.334728) (xy 7.711868 -74.344798) (xy 7.582255 -74.346814) (xy 7.452768 -74.340768)
			(xy 7.323907 -74.326684) (xy 7.196171 -74.304615) (xy 7.070054 -74.274648) (xy 6.946044 -74.236899)
			(xy 6.824621 -74.191512) (xy 6.706254 -74.138665) (xy 6.591402 -74.078561) (xy 6.480509 -74.011433)
			(xy 6.374003 -73.937541) (xy 6.272297 -73.85717) (xy 6.175785 -73.770632) (xy 6.08484 -73.67826)
			(xy 5.999813 -73.580414) (xy 5.921033 -73.477471) (xy 5.848806 -73.369829) (xy 5.783411 -73.257905)
			(xy 5.7251 -73.142132) (xy 5.6741 -73.022958) (xy 5.630608 -72.900844) (xy 5.594791 -72.776261) (xy 5.566789 -72.649694)
			(xy 5.54671 -72.52163) (xy 5.534631 -72.392566) (xy 5.5306 -72.263) (xy 0.509016 -72.263) (xy 0.509016 -77.476858)
			(xy 6.601727 -77.476858) (xy 6.605682 -77.385021) (xy 6.617517 -77.293864) (xy 6.637144 -77.204061)
			(xy 6.664418 -77.116279) (xy 6.699138 -77.031165) (xy 6.741046 -76.949352) (xy 6.789832 -76.871444)
			(xy 6.845135 -76.798019) (xy 6.906545 -76.729619) (xy 6.973607 -76.666752) (xy 7.045826 -76.609882)
			(xy 7.122666 -76.559431) (xy 7.203559 -76.515772) (xy 7.287905 -76.479229) (xy 7.375081 -76.450072)
			(xy 7.46444 -76.428518) (xy 7.555321 -76.414724) (xy 7.647052 -76.408794) (xy 7.738953 -76.410772)
			(xy 7.830344 -76.420643) (xy 7.920548 -76.438333) (xy 8.008897 -76.463713) (xy 8.094737 -76.496593)
			(xy 8.177433 -76.536731) (xy 8.256373 -76.58383) (xy 8.330971 -76.63754) (xy 8.400677 -76.697464)
			(xy 8.464972 -76.763158) (xy 8.523383 -76.834136) (xy 8.575475 -76.909873) (xy 8.620864 -76.989808)
			(xy 8.659214 -77.073348) (xy 8.690239 -77.159876) (xy 8.713712 -77.248751) (xy 8.729458 -77.339315)
			(xy 8.73736 -77.430897) (xy 8.737854 -77.476858) (xy 8.73736 -77.522819) (xy 8.729458 -77.614401)
			(xy 8.713712 -77.704965) (xy 8.690239 -77.79384) (xy 8.659214 -77.880368) (xy 8.620864 -77.963908)
			(xy 8.575475 -78.043843) (xy 8.523383 -78.11958) (xy 8.464972 -78.190558) (xy 8.400677 -78.256252)
			(xy 8.330971 -78.316176) (xy 8.256373 -78.369886) (xy 8.241646 -78.378673) (xy 74.888081 -78.378673)
			(xy 74.888081 -78.220963) (xy 74.896069 -78.063456) (xy 74.912025 -77.906556) (xy 74.935906 -77.750665)
			(xy 74.967653 -77.596184) (xy 75.007183 -77.443509) (xy 75.054395 -77.293033) (xy 75.109169 -77.14514)
			(xy 75.171362 -77.000212) (xy 75.240817 -76.85862) (xy 75.317353 -76.720727) (xy 75.400776 -76.586888)
			(xy 75.49087 -76.457446) (xy 75.587405 -76.332733) (xy 75.690133 -76.21307) (xy 75.798789 -76.098763)
			(xy 75.913096 -75.990107) (xy 76.032759 -75.887379) (xy 76.157472 -75.790844) (xy 76.286914 -75.70075)
			(xy 76.420753 -75.617327) (xy 76.558646 -75.540791) (xy 76.700238 -75.471336) (xy 76.845166 -75.409143)
			(xy 76.993059 -75.354369) (xy 77.143535 -75.307157) (xy 77.29621 -75.267627) (xy 77.450691 -75.23588)
			(xy 77.606582 -75.211999) (xy 77.763482 -75.196043) (xy 77.920989 -75.188055) (xy 78.078699 -75.188055)
			(xy 78.236206 -75.196043) (xy 78.393106 -75.211999) (xy 78.548997 -75.23588) (xy 78.703478 -75.267627)
			(xy 78.856153 -75.307157) (xy 79.006629 -75.354369) (xy 79.154522 -75.409143) (xy 79.29945 -75.471336)
			(xy 79.441042 -75.540791) (xy 79.578935 -75.617327) (xy 79.712774 -75.70075) (xy 79.842216 -75.790844)
			(xy 79.966929 -75.887379) (xy 80.086592 -75.990107) (xy 80.200899 -76.098763) (xy 80.309555 -76.21307)
			(xy 80.412283 -76.332733) (xy 80.508818 -76.457446) (xy 80.598912 -76.586888) (xy 80.682335 -76.720727)
			(xy 80.758871 -76.85862) (xy 80.828326 -77.000212) (xy 80.890519 -77.14514) (xy 80.945293 -77.293033)
			(xy 80.992505 -77.443509) (xy 81.032035 -77.596184) (xy 81.063782 -77.750665) (xy 81.087663 -77.906556)
			(xy 81.103619 -78.063456) (xy 81.111607 -78.220963) (xy 81.112106 -78.299818) (xy 81.111607 -78.378673)
			(xy 81.103619 -78.53618) (xy 81.087663 -78.69308) (xy 81.063782 -78.848971) (xy 81.032035 -79.003452)
			(xy 80.992505 -79.156127) (xy 80.945293 -79.306603) (xy 80.890519 -79.454496) (xy 80.828326 -79.599424)
			(xy 80.758871 -79.741016) (xy 80.682335 -79.878909) (xy 80.598912 -80.012748) (xy 80.508818 -80.14219)
			(xy 80.412283 -80.266903) (xy 80.309555 -80.386566) (xy 80.200899 -80.500873) (xy 80.086592 -80.609529)
			(xy 79.966929 -80.712257) (xy 79.842216 -80.808792) (xy 79.712774 -80.898886) (xy 79.578935 -80.982309)
			(xy 79.441042 -81.058845) (xy 79.29945 -81.1283) (xy 79.154522 -81.190493) (xy 79.006629 -81.245267)
			(xy 78.856153 -81.292479) (xy 78.703478 -81.332009) (xy 78.548997 -81.363756) (xy 78.393106 -81.387637)
			(xy 78.236206 -81.403593) (xy 78.078699 -81.411581) (xy 77.920989 -81.411581) (xy 77.763482 -81.403593)
			(xy 77.606582 -81.387637) (xy 77.450691 -81.363756) (xy 77.29621 -81.332009) (xy 77.143535 -81.292479)
			(xy 76.993059 -81.245267) (xy 76.845166 -81.190493) (xy 76.700238 -81.1283) (xy 76.558646 -81.058845)
			(xy 76.420753 -80.982309) (xy 76.286914 -80.898886) (xy 76.157472 -80.808792) (xy 76.032759 -80.712257)
			(xy 75.913096 -80.609529) (xy 75.798789 -80.500873) (xy 75.690133 -80.386566) (xy 75.587405 -80.266903)
			(xy 75.49087 -80.14219) (xy 75.400776 -80.012748) (xy 75.317353 -79.878909) (xy 75.240817 -79.741016)
			(xy 75.171362 -79.599424) (xy 75.109169 -79.454496) (xy 75.054395 -79.306603) (xy 75.007183 -79.156127)
			(xy 74.967653 -79.003452) (xy 74.935906 -78.848971) (xy 74.912025 -78.69308) (xy 74.896069 -78.53618)
			(xy 74.888081 -78.378673) (xy 8.241646 -78.378673) (xy 8.177433 -78.416985) (xy 8.094737 -78.457123)
			(xy 8.008897 -78.490003) (xy 7.920548 -78.515383) (xy 7.830344 -78.533073) (xy 7.738953 -78.542944)
			(xy 7.647052 -78.544922) (xy 7.555321 -78.538992) (xy 7.46444 -78.525198) (xy 7.375081 -78.503644)
			(xy 7.287905 -78.474487) (xy 7.203559 -78.437944) (xy 7.122666 -78.394285) (xy 7.045826 -78.343834)
			(xy 6.973607 -78.286964) (xy 6.906545 -78.224097) (xy 6.845135 -78.155697) (xy 6.789832 -78.082272)
			(xy 6.741046 -78.004364) (xy 6.699138 -77.922551) (xy 6.664418 -77.837437) (xy 6.637144 -77.749655)
			(xy 6.617517 -77.659852) (xy 6.605682 -77.568695) (xy 6.601727 -77.476858) (xy 0.509016 -77.476858)
			(xy 0.509016 -89.476834) (xy 6.601727 -89.476834) (xy 6.605682 -89.384997) (xy 6.617517 -89.29384)
			(xy 6.637144 -89.204037) (xy 6.664418 -89.116255) (xy 6.699138 -89.031141) (xy 6.741046 -88.949328)
			(xy 6.789832 -88.87142) (xy 6.845135 -88.797995) (xy 6.906545 -88.729595) (xy 6.973607 -88.666728)
			(xy 7.045826 -88.609858) (xy 7.122666 -88.559407) (xy 7.203559 -88.515748) (xy 7.287905 -88.479205)
			(xy 7.375081 -88.450048) (xy 7.46444 -88.428494) (xy 7.555321 -88.4147) (xy 7.647052 -88.40877) (xy 7.738953 -88.410748)
			(xy 7.830344 -88.420619) (xy 7.920548 -88.438309) (xy 8.008897 -88.463689) (xy 8.094737 -88.496569)
			(xy 8.177433 -88.536707) (xy 8.256373 -88.583806) (xy 8.330971 -88.637516) (xy 8.400677 -88.69744)
			(xy 8.464972 -88.763134) (xy 8.523383 -88.834112) (xy 8.575475 -88.909849) (xy 8.620864 -88.989784)
			(xy 8.659214 -89.073324) (xy 8.690239 -89.159852) (xy 8.713712 -89.248727) (xy 8.729458 -89.339291)
			(xy 8.73736 -89.430873) (xy 8.737854 -89.476834) (xy 8.73736 -89.522795) (xy 8.729458 -89.614377)
			(xy 8.713712 -89.704941) (xy 8.690239 -89.793816) (xy 8.659214 -89.880344) (xy 8.620864 -89.963884)
			(xy 8.575475 -90.043819) (xy 8.523383 -90.119556) (xy 8.464972 -90.190534) (xy 8.400677 -90.256228)
			(xy 8.330971 -90.316152) (xy 8.256373 -90.369862) (xy 8.177433 -90.416961) (xy 8.094737 -90.457099)
			(xy 8.008897 -90.489979) (xy 7.920548 -90.515359) (xy 7.830344 -90.533049) (xy 7.738953 -90.54292)
			(xy 7.647052 -90.544898) (xy 7.555321 -90.538968) (xy 7.46444 -90.525174) (xy 7.375081 -90.50362)
			(xy 7.287905 -90.474463) (xy 7.203559 -90.43792) (xy 7.122666 -90.394261) (xy 7.045826 -90.34381)
			(xy 6.973607 -90.28694) (xy 6.906545 -90.224073) (xy 6.845135 -90.155673) (xy 6.789832 -90.082248)
			(xy 6.741046 -90.00434) (xy 6.699138 -89.922527) (xy 6.664418 -89.837413) (xy 6.637144 -89.749631)
			(xy 6.617517 -89.659828) (xy 6.605682 -89.568671) (xy 6.601727 -89.476834) (xy 0.509016 -89.476834)
			(xy 0.509016 -95.377) (xy 5.5306 -95.377) (xy 5.534631 -95.247434) (xy 5.54671 -95.11837) (xy 5.566789 -94.990306)
			(xy 5.594791 -94.863739) (xy 5.630608 -94.739156) (xy 5.6741 -94.617042) (xy 5.7251 -94.497868) (xy 5.783411 -94.382095)
			(xy 5.848806 -94.270171) (xy 5.921033 -94.162529) (xy 5.999813 -94.059586) (xy 6.08484 -93.96174)
			(xy 6.175785 -93.869368) (xy 6.272297 -93.78283) (xy 6.374003 -93.702459) (xy 6.480509 -93.628567)
			(xy 6.591402 -93.561439) (xy 6.706254 -93.501335) (xy 6.824621 -93.448488) (xy 6.946044 -93.403101)
			(xy 7.070054 -93.365352) (xy 7.196171 -93.335385) (xy 7.323907 -93.313316) (xy 7.452768 -93.299232)
			(xy 7.582255 -93.293186) (xy 7.711868 -93.295202) (xy 7.841104 -93.305272) (xy 7.969465 -93.323357)
			(xy 8.096453 -93.349387) (xy 8.221577 -93.383262) (xy 8.344353 -93.42485) (xy 8.464306 -93.473991)
			(xy 8.580971 -93.530494) (xy 8.693899 -93.594141) (xy 8.802651 -93.664685) (xy 8.906807 -93.741854)
			(xy 9.005964 -93.825349) (xy 9.099738 -93.914847) (xy 9.187767 -94.010002) (xy 9.26971 -94.110445)
			(xy 9.345249 -94.215788) (xy 9.414094 -94.325624) (xy 9.475977 -94.439528) (xy 9.530658 -94.557058)
			(xy 9.577928 -94.677761) (xy 9.617601 -94.801169) (xy 9.649526 -94.926805) (xy 9.673578 -95.054182)
			(xy 9.689665 -95.182808) (xy 9.697724 -95.312186) (xy 9.698228 -95.377) (xy 9.697724 -95.441814)
			(xy 9.689665 -95.571192) (xy 9.673578 -95.699818) (xy 9.65276 -95.81007) (xy 39.818564 -95.81007)
			(xy 39.819054 -95.752663) (xy 39.826889 -95.638117) (xy 39.842523 -95.524372) (xy 39.865882 -95.41196)
			(xy 39.896859 -95.301403) (xy 39.935308 -95.193218) (xy 39.98105 -95.08791) (xy 40.033872 -94.985968)
			(xy 40.093527 -94.887869) (xy 40.159738 -94.794069) (xy 40.232196 -94.705007) (xy 40.310562 -94.621096)
			(xy 40.394473 -94.54273) (xy 40.483535 -94.470272) (xy 40.577335 -94.404061) (xy 40.675434 -94.344406)
			(xy 40.777376 -94.291584) (xy 40.882684 -94.245842) (xy 40.990869 -94.207393) (xy 41.101426 -94.176416)
			(xy 41.213838 -94.153057) (xy 41.327583 -94.137423) (xy 41.442129 -94.129588) (xy 41.556943 -94.129588)
			(xy 41.671489 -94.137423) (xy 41.785234 -94.153057) (xy 41.897646 -94.176416) (xy 42.008203 -94.207393)
			(xy 42.116388 -94.245842) (xy 42.221696 -94.291584) (xy 42.323638 -94.344406) (xy 42.421737 -94.404061)
			(xy 42.515537 -94.470272) (xy 42.604599 -94.54273) (xy 42.68851 -94.621096) (xy 42.766876 -94.705007)
			(xy 42.839334 -94.794069) (xy 42.905545 -94.887869) (xy 42.9652 -94.985968) (xy 43.018022 -95.08791)
			(xy 43.063764 -95.193218) (xy 43.102213 -95.301403) (xy 43.13319 -95.41196) (xy 43.156549 -95.524372)
			(xy 43.172183 -95.638117) (xy 43.180018 -95.752663) (xy 43.180508 -95.81007) (xy 43.180381 -95.843251)
			(xy 43.177842 -95.909565) (xy 43.175428 -95.942658) (xy 43.170272 -96.000942) (xy 43.152948 -96.116671)
			(xy 43.127616 -96.230914) (xy 43.094401 -96.343119) (xy 43.053462 -96.452742) (xy 43.004999 -96.559253)
			(xy 42.949245 -96.662135) (xy 42.886471 -96.760891) (xy 42.816981 -96.855042) (xy 42.741111 -96.944132)
			(xy 42.659229 -97.027729) (xy 42.571732 -97.10543) (xy 42.500813 -97.16008) (xy 93.154506 -97.16008)
			(xy 93.158522 -97.04381) (xy 93.170549 -96.928095) (xy 93.190531 -96.813485) (xy 93.218373 -96.700526)
			(xy 93.253942 -96.589758) (xy 93.297068 -96.481707) (xy 93.347545 -96.376889) (xy 93.405134 -96.275804)
			(xy 93.46956 -96.178932) (xy 93.540515 -96.086736) (xy 93.617662 -95.999655) (xy 93.700633 -95.918104)
			(xy 93.789033 -95.842472) (xy 93.88244 -95.773118) (xy 93.980409 -95.710375) (xy 94.082473 -95.654539)
			(xy 94.188147 -95.605878) (xy 94.296926 -95.564624) (xy 94.408291 -95.530973) (xy 94.521714 -95.505085)
			(xy 94.636651 -95.487084) (xy 94.752557 -95.477055) (xy 94.868879 -95.475047) (xy 94.985062 -95.481069)
			(xy 95.100553 -95.495092) (xy 95.214801 -95.51705) (xy 95.327262 -95.546837) (xy 95.4374 -95.584312)
			(xy 95.54469 -95.629297) (xy 95.648621 -95.681576) (xy 95.748697 -95.740901) (xy 95.844443 -95.806989)
			(xy 95.9354 -95.879525) (xy 96.021136 -95.958164) (xy 96.101243 -96.04253) (xy 96.175339 -96.132222)
			(xy 96.243069 -96.226812) (xy 96.304113 -96.32585) (xy 96.358178 -96.428863) (xy 96.405008 -96.53536)
			(xy 96.444379 -96.644835) (xy 96.476103 -96.756765) (xy 96.500029 -96.870617) (xy 96.516043 -96.985849)
			(xy 96.52407 -97.101911) (xy 96.524572 -97.16008) (xy 96.52407 -97.218249) (xy 96.516043 -97.334311)
			(xy 96.500029 -97.449543) (xy 96.476103 -97.563395) (xy 96.444379 -97.675325) (xy 96.405008 -97.7848)
			(xy 96.358178 -97.891297) (xy 96.304113 -97.99431) (xy 96.243069 -98.093348) (xy 96.175339 -98.187938)
			(xy 96.101243 -98.27763) (xy 96.021136 -98.361996) (xy 95.9354 -98.440635) (xy 95.844443 -98.513171)
			(xy 95.748697 -98.579259) (xy 95.648621 -98.638584) (xy 95.54469 -98.690863) (xy 95.4374 -98.735848)
			(xy 95.327262 -98.773323) (xy 95.214801 -98.80311) (xy 95.100553 -98.825068) (xy 94.985062 -98.839091)
			(xy 94.868879 -98.845113) (xy 94.752557 -98.843105) (xy 94.636651 -98.833076) (xy 94.521714 -98.815075)
			(xy 94.408291 -98.789187) (xy 94.296926 -98.755536) (xy 94.188147 -98.714282) (xy 94.082473 -98.665621)
			(xy 93.980409 -98.609785) (xy 93.88244 -98.547042) (xy 93.789033 -98.477688) (xy 93.700633 -98.402056)
			(xy 93.617662 -98.320505) (xy 93.540515 -98.233424) (xy 93.46956 -98.141228) (xy 93.405134 -98.044356)
			(xy 93.347545 -97.943271) (xy 93.297068 -97.838453) (xy 93.253942 -97.730402) (xy 93.218373 -97.619634)
			(xy 93.190531 -97.506675) (xy 93.170549 -97.392065) (xy 93.158522 -97.27635) (xy 93.154506 -97.16008)
			(xy 42.500813 -97.16008) (xy 42.479042 -97.176857) (xy 42.381609 -97.241665) (xy 42.279905 -97.29954)
			(xy 42.174422 -97.350202) (xy 42.065671 -97.393404) (xy 41.954179 -97.428939) (xy 41.840485 -97.456634)
			(xy 41.725141 -97.476354) (xy 41.608704 -97.488005) (xy 41.491739 -97.49153) (xy 41.374812 -97.486912)
			(xy 41.258489 -97.474173) (xy 41.143334 -97.453375) (xy 41.029905 -97.424618) (xy 40.91875 -97.388042)
			(xy 40.810407 -97.343825) (xy 40.705403 -97.292179) (xy 40.604244 -97.233356) (xy 40.507421 -97.16764)
			(xy 40.415403 -97.095349) (xy 40.328636 -97.016834) (xy 40.247539 -96.932474) (xy 40.172506 -96.842679)
			(xy 40.103899 -96.747883) (xy 40.042051 -96.648544) (xy 39.987262 -96.545145) (xy 39.939796 -96.438186)
			(xy 39.899884 -96.328185) (xy 39.86772 -96.215674) (xy 39.843457 -96.101199) (xy 39.827215 -95.985313)
			(xy 39.819072 -95.868579) (xy 39.818564 -95.81007) (xy 9.65276 -95.81007) (xy 9.649526 -95.827195)
			(xy 9.617601 -95.952831) (xy 9.577928 -96.076239) (xy 9.530658 -96.196942) (xy 9.475977 -96.314472)
			(xy 9.414094 -96.428376) (xy 9.345249 -96.538212) (xy 9.26971 -96.643555) (xy 9.187767 -96.743998)
			(xy 9.099738 -96.839153) (xy 9.005964 -96.928651) (xy 8.906807 -97.012146) (xy 8.802651 -97.089315)
			(xy 8.693899 -97.159859) (xy 8.580971 -97.223506) (xy 8.464306 -97.280009) (xy 8.344353 -97.32915)
			(xy 8.221577 -97.370738) (xy 8.096453 -97.404613) (xy 7.969465 -97.430643) (xy 7.841104 -97.448728)
			(xy 7.711868 -97.458798) (xy 7.582255 -97.460814) (xy 7.452768 -97.454768) (xy 7.323907 -97.440684)
			(xy 7.196171 -97.418615) (xy 7.070054 -97.388648) (xy 6.946044 -97.350899) (xy 6.824621 -97.305512)
			(xy 6.706254 -97.252665) (xy 6.591402 -97.192561) (xy 6.480509 -97.125433) (xy 6.374003 -97.051541)
			(xy 6.272297 -96.97117) (xy 6.175785 -96.884632) (xy 6.08484 -96.79226) (xy 5.999813 -96.694414)
			(xy 5.921033 -96.591471) (xy 5.848806 -96.483829) (xy 5.783411 -96.371905) (xy 5.7251 -96.256132)
			(xy 5.6741 -96.136958) (xy 5.630608 -96.014844) (xy 5.594791 -95.890261) (xy 5.566789 -95.763694)
			(xy 5.54671 -95.63563) (xy 5.534631 -95.506566) (xy 5.5306 -95.377) (xy 0.509016 -95.377) (xy 0.509016 -106.807)
			(xy 5.5306 -106.807) (xy 5.534631 -106.677434) (xy 5.54671 -106.54837) (xy 5.566789 -106.420306)
			(xy 5.594791 -106.293739) (xy 5.630608 -106.169156) (xy 5.6741 -106.047042) (xy 5.7251 -105.927868)
			(xy 5.783411 -105.812095) (xy 5.848806 -105.700171) (xy 5.921033 -105.592529) (xy 5.999813 -105.489586)
			(xy 6.08484 -105.39174) (xy 6.175785 -105.299368) (xy 6.272297 -105.21283) (xy 6.374003 -105.132459)
			(xy 6.480509 -105.058567) (xy 6.591402 -104.991439) (xy 6.706254 -104.931335) (xy 6.824621 -104.878488)
			(xy 6.946044 -104.833101) (xy 7.070054 -104.795352) (xy 7.196171 -104.765385) (xy 7.323907 -104.743316)
			(xy 7.452768 -104.729232) (xy 7.582255 -104.723186) (xy 7.711868 -104.725202) (xy 7.841104 -104.735272)
			(xy 7.969465 -104.753357) (xy 8.096453 -104.779387) (xy 8.221577 -104.813262) (xy 8.344353 -104.85485)
			(xy 8.464306 -104.903991) (xy 8.580971 -104.960494) (xy 8.693899 -105.024141) (xy 8.802651 -105.094685)
			(xy 8.906807 -105.171854) (xy 9.005964 -105.255349) (xy 9.099738 -105.344847) (xy 9.187767 -105.440002)
			(xy 9.26971 -105.540445) (xy 9.345249 -105.645788) (xy 9.414094 -105.755624) (xy 9.475977 -105.869528)
			(xy 9.530658 -105.987058) (xy 9.577928 -106.107761) (xy 9.617601 -106.231169) (xy 9.649526 -106.356805)
			(xy 9.673578 -106.484182) (xy 9.689665 -106.612808) (xy 9.697724 -106.742186) (xy 9.698228 -106.807)
			(xy 9.697724 -106.871814) (xy 9.689665 -107.001192) (xy 9.673578 -107.129818) (xy 9.649526 -107.257195)
			(xy 9.617601 -107.382831) (xy 9.577928 -107.506239) (xy 9.530658 -107.626942) (xy 9.475977 -107.744472)
			(xy 9.414094 -107.858376) (xy 9.345249 -107.968212) (xy 9.26971 -108.073555) (xy 9.187767 -108.173998)
			(xy 9.099738 -108.269153) (xy 9.005964 -108.358651) (xy 8.906807 -108.442146) (xy 8.802651 -108.519315)
			(xy 8.693899 -108.589859) (xy 8.580971 -108.653506) (xy 8.464306 -108.710009) (xy 8.344353 -108.75915)
			(xy 8.221577 -108.800738) (xy 8.096453 -108.834613) (xy 7.969465 -108.860643) (xy 7.841104 -108.878728)
			(xy 7.711868 -108.888798) (xy 7.582255 -108.890814) (xy 7.452768 -108.884768) (xy 7.323907 -108.870684)
			(xy 7.196171 -108.848615) (xy 7.070054 -108.818648) (xy 6.946044 -108.780899) (xy 6.824621 -108.735512)
			(xy 6.706254 -108.682665) (xy 6.591402 -108.622561) (xy 6.480509 -108.555433) (xy 6.374003 -108.481541)
			(xy 6.272297 -108.40117) (xy 6.175785 -108.314632) (xy 6.08484 -108.22226) (xy 5.999813 -108.124414)
			(xy 5.921033 -108.021471) (xy 5.848806 -107.913829) (xy 5.783411 -107.801905) (xy 5.7251 -107.686132)
			(xy 5.6741 -107.566958) (xy 5.630608 -107.444844) (xy 5.594791 -107.320261) (xy 5.566789 -107.193694)
			(xy 5.54671 -107.06563) (xy 5.534631 -106.936566) (xy 5.5306 -106.807) (xy 0.509016 -106.807) (xy 0.509016 -108.909866)
			(xy 86.877404 -108.909866) (xy 86.881424 -108.719215) (xy 86.893478 -108.528902) (xy 86.913544 -108.339267)
			(xy 86.941587 -108.150646) (xy 86.977556 -107.963376) (xy 87.021388 -107.777788) (xy 87.073005 -107.594213)
			(xy 87.132315 -107.412977) (xy 87.199213 -107.234402) (xy 87.273579 -107.058807) (xy 87.355281 -106.886502)
			(xy 87.444175 -106.717795) (xy 87.540101 -106.552985) (xy 87.64289 -106.392366) (xy 87.752359 -106.236223)
			(xy 87.868313 -106.084834) (xy 87.990547 -105.938467) (xy 88.118841 -105.797383) (xy 88.252969 -105.661834)
			(xy 88.392693 -105.532059) (xy 88.537763 -105.408289) (xy 88.687921 -105.290746) (xy 88.842902 -105.179637)
			(xy 89.002429 -105.07516) (xy 89.166218 -104.977501) (xy 89.333978 -104.886834) (xy 89.505412 -104.80332)
			(xy 89.680214 -104.727107) (xy 89.858073 -104.658331) (xy 90.038674 -104.597113) (xy 90.221694 -104.543564)
			(xy 90.40681 -104.497778) (xy 90.593691 -104.459836) (xy 90.782006 -104.429807) (xy 90.971419 -104.407742)
			(xy 91.161593 -104.393683) (xy 91.352192 -104.387653) (xy 91.542875 -104.389663) (xy 91.733304 -104.39971)
			(xy 91.92314 -104.417776) (xy 92.112046 -104.443829) (xy 92.299685 -104.477822) (xy 92.485725 -104.519695)
			(xy 92.669834 -104.569374) (xy 92.851685 -104.62677) (xy 93.030955 -104.691781) (xy 93.207325 -104.764292)
			(xy 93.380481 -104.844173) (xy 93.550116 -104.931283) (xy 93.715928 -105.025467) (xy 93.877622 -105.126558)
			(xy 94.03491 -105.234374) (xy 94.187513 -105.348726) (xy 94.335161 -105.469409) (xy 94.477589 -105.59621)
			(xy 94.614545 -105.728901) (xy 94.745786 -105.867249) (xy 94.871078 -106.011006) (xy 94.990198 -106.159917)
			(xy 95.102934 -106.313718) (xy 95.209087 -106.472134) (xy 95.308467 -106.634885) (xy 95.400897 -106.80168)
			(xy 95.486214 -106.972224) (xy 95.564266 -107.146212) (xy 95.634913 -107.323337) (xy 95.698031 -107.503282)
			(xy 95.753507 -107.685728) (xy 95.801242 -107.870351) (xy 95.841152 -108.056821) (xy 95.873165 -108.244809)
			(xy 95.897225 -108.433979) (xy 95.913288 -108.623995) (xy 95.921327 -108.814519) (xy 95.92183 -108.909866)
			(xy 95.921327 -109.005213) (xy 95.913288 -109.195737) (xy 95.897225 -109.385753) (xy 95.873165 -109.574923)
			(xy 95.841152 -109.762911) (xy 95.801242 -109.949381) (xy 95.753507 -110.134004) (xy 95.698031 -110.31645)
			(xy 95.634913 -110.496395) (xy 95.564266 -110.67352) (xy 95.486214 -110.847508) (xy 95.400897 -111.018052)
			(xy 95.308467 -111.184847) (xy 95.209087 -111.347598) (xy 95.102934 -111.506014) (xy 94.990198 -111.659815)
			(xy 94.871078 -111.808726) (xy 94.745786 -111.952483) (xy 94.614545 -112.090831) (xy 94.477589 -112.223522)
			(xy 94.335161 -112.350323) (xy 94.187513 -112.471006) (xy 94.03491 -112.585358) (xy 93.877622 -112.693174)
			(xy 93.715928 -112.794265) (xy 93.550116 -112.888449) (xy 93.380481 -112.975559) (xy 93.207325 -113.05544)
			(xy 93.030955 -113.127951) (xy 92.851685 -113.192962) (xy 92.669834 -113.250358) (xy 92.485725 -113.300037)
			(xy 92.299685 -113.34191) (xy 92.112046 -113.375903) (xy 91.92314 -113.401956) (xy 91.733304 -113.420022)
			(xy 91.542875 -113.430069) (xy 91.352192 -113.432079) (xy 91.161593 -113.426049) (xy 90.971419 -113.41199)
			(xy 90.782006 -113.389925) (xy 90.593691 -113.359896) (xy 90.40681 -113.321954) (xy 90.221694 -113.276168)
			(xy 90.038674 -113.222619) (xy 89.858073 -113.161401) (xy 89.680214 -113.092625) (xy 89.505412 -113.016412)
			(xy 89.333978 -112.932898) (xy 89.166218 -112.842231) (xy 89.002429 -112.744572) (xy 88.842902 -112.640095)
			(xy 88.687921 -112.528986) (xy 88.537763 -112.411443) (xy 88.392693 -112.287673) (xy 88.252969 -112.157898)
			(xy 88.118841 -112.022349) (xy 87.990547 -111.881265) (xy 87.868313 -111.734898) (xy 87.752359 -111.583509)
			(xy 87.64289 -111.427366) (xy 87.540101 -111.266747) (xy 87.444175 -111.101937) (xy 87.355281 -110.93323)
			(xy 87.273579 -110.760925) (xy 87.199213 -110.58533) (xy 87.132315 -110.406755) (xy 87.073005 -110.225519)
			(xy 87.021388 -110.041944) (xy 86.977556 -109.856356) (xy 86.941587 -109.669086) (xy 86.913544 -109.480465)
			(xy 86.893478 -109.29083) (xy 86.881424 -109.100517) (xy 86.877404 -108.909866) (xy 0.509016 -108.909866)
			(xy 0.509016 -118.09984) (xy 14.086591 -118.09984) (xy 14.090616 -117.957648) (xy 14.102679 -117.815912)
			(xy 14.122742 -117.675086) (xy 14.15074 -117.53562) (xy 14.186584 -117.397961) (xy 14.230158 -117.262551)
			(xy 14.281323 -117.129823) (xy 14.339916 -117.000202) (xy 14.405747 -116.874104) (xy 14.478608 -116.751932)
			(xy 14.558263 -116.634078) (xy 14.644459 -116.520919) (xy 14.736918 -116.412817) (xy 14.835346 -116.31012)
			(xy 14.939425 -116.213156) (xy 15.048824 -116.122236) (xy 15.163192 -116.03765) (xy 15.282161 -115.95967)
			(xy 15.405352 -115.888546) (xy 15.532369 -115.824505) (xy 15.662806 -115.767753) (xy 15.796245 -115.718471)
			(xy 15.932258 -115.676817) (xy 16.07041 -115.642925) (xy 16.210259 -115.616904) (xy 16.351355 -115.598836)
			(xy 16.493247 -115.588779) (xy 16.635482 -115.586766) (xy 16.777602 -115.592803) (xy 16.919153 -115.606871)
			(xy 17.059682 -115.628925) (xy 17.198737 -115.658894) (xy 17.335875 -115.696682) (xy 17.470655 -115.742168)
			(xy 17.602646 -115.795206) (xy 17.731425 -115.855627) (xy 17.856579 -115.923236) (xy 17.977707 -115.997818)
			(xy 18.094423 -116.079134) (xy 18.206351 -116.166922) (xy 18.313133 -116.260902) (xy 18.414427 -116.360772)
			(xy 18.509908 -116.466214) (xy 18.599272 -116.576888) (xy 18.68223 -116.692441) (xy 18.758519 -116.812502)
			(xy 18.827893 -116.936687) (xy 18.89013 -117.064598) (xy 18.945031 -117.195825) (xy 18.992419 -117.329948)
			(xy 19.032144 -117.466537) (xy 19.064077 -117.605155) (xy 19.088118 -117.745357) (xy 19.104187 -117.886695)
			(xy 19.112235 -118.028716) (xy 19.112738 -118.09984) (xy 19.112235 -118.170964) (xy 19.104187 -118.312985)
			(xy 19.088118 -118.454323) (xy 19.064077 -118.594525) (xy 19.032144 -118.733143) (xy 18.992419 -118.869732)
			(xy 18.945031 -119.003855) (xy 18.89013 -119.135082) (xy 18.827893 -119.262993) (xy 18.758519 -119.387178)
			(xy 18.68223 -119.507239) (xy 18.599272 -119.622792) (xy 18.509908 -119.733466) (xy 18.414427 -119.838908)
			(xy 18.313133 -119.938778) (xy 18.206351 -120.032758) (xy 18.094423 -120.120546) (xy 17.977707 -120.201862)
			(xy 17.856579 -120.276444) (xy 17.731425 -120.344053) (xy 17.602646 -120.404474) (xy 17.470655 -120.457512)
			(xy 17.335875 -120.502998) (xy 17.198737 -120.540786) (xy 17.059682 -120.570755) (xy 16.919153 -120.592809)
			(xy 16.777602 -120.606877) (xy 16.635482 -120.612914) (xy 16.493247 -120.610901) (xy 16.351355 -120.600844)
			(xy 16.210259 -120.582776) (xy 16.07041 -120.556755) (xy 15.932258 -120.522863) (xy 15.796245 -120.481209)
			(xy 15.662806 -120.431927) (xy 15.532369 -120.375175) (xy 15.405352 -120.311134) (xy 15.282161 -120.24001)
			(xy 15.163192 -120.16203) (xy 15.048824 -120.077444) (xy 14.939425 -119.986524) (xy 14.835346 -119.88956)
			(xy 14.736918 -119.786863) (xy 14.644459 -119.678761) (xy 14.558263 -119.565602) (xy 14.478608 -119.447748)
			(xy 14.405747 -119.325576) (xy 14.339916 -119.199478) (xy 14.281323 -119.069857) (xy 14.230158 -118.937129)
			(xy 14.186584 -118.801719) (xy 14.15074 -118.66406) (xy 14.122742 -118.524594) (xy 14.102679 -118.383768)
			(xy 14.090616 -118.242032) (xy 14.086591 -118.09984) (xy 0.509016 -118.09984) (xy 0.509016 -121.19991)
			(xy 75.486519 -121.19991) (xy 75.490544 -121.057718) (xy 75.502607 -120.915982) (xy 75.52267 -120.775156)
			(xy 75.550668 -120.63569) (xy 75.586512 -120.498031) (xy 75.630086 -120.362621) (xy 75.681251 -120.229893)
			(xy 75.739844 -120.100272) (xy 75.805675 -119.974174) (xy 75.878536 -119.852002) (xy 75.958191 -119.734148)
			(xy 76.044387 -119.620989) (xy 76.136846 -119.512887) (xy 76.235274 -119.41019) (xy 76.339353 -119.313226)
			(xy 76.448752 -119.222306) (xy 76.56312 -119.13772) (xy 76.682089 -119.05974) (xy 76.80528 -118.988616)
			(xy 76.932297 -118.924575) (xy 77.062734 -118.867823) (xy 77.196173 -118.818541) (xy 77.332186 -118.776887)
			(xy 77.470338 -118.742995) (xy 77.610187 -118.716974) (xy 77.751283 -118.698906) (xy 77.893175 -118.688849)
			(xy 78.03541 -118.686836) (xy 78.17753 -118.692873) (xy 78.319081 -118.706941) (xy 78.45961 -118.728995)
			(xy 78.598665 -118.758964) (xy 78.735803 -118.796752) (xy 78.870583 -118.842238) (xy 79.002574 -118.895276)
			(xy 79.131353 -118.955697) (xy 79.256507 -119.023306) (xy 79.377635 -119.097888) (xy 79.494351 -119.179204)
			(xy 79.606279 -119.266992) (xy 79.713061 -119.360972) (xy 79.814355 -119.460842) (xy 79.909836 -119.566284)
			(xy 79.9992 -119.676958) (xy 80.082158 -119.792511) (xy 80.158447 -119.912572) (xy 80.227821 -120.036757)
			(xy 80.290058 -120.164668) (xy 80.344959 -120.295895) (xy 80.392347 -120.430018) (xy 80.432072 -120.566607)
			(xy 80.464005 -120.705225) (xy 80.488046 -120.845427) (xy 80.504115 -120.986765) (xy 80.512163 -121.128786)
			(xy 80.512666 -121.19991) (xy 80.512163 -121.271034) (xy 80.504115 -121.413055) (xy 80.488046 -121.554393)
			(xy 80.464005 -121.694595) (xy 80.432072 -121.833213) (xy 80.392347 -121.969802) (xy 80.344959 -122.103925)
			(xy 80.290058 -122.235152) (xy 80.227821 -122.363063) (xy 80.158447 -122.487248) (xy 80.082158 -122.607309)
			(xy 79.9992 -122.722862) (xy 79.909836 -122.833536) (xy 79.814355 -122.938978) (xy 79.713061 -123.038848)
			(xy 79.606279 -123.132828) (xy 79.494351 -123.220616) (xy 79.377635 -123.301932) (xy 79.256507 -123.376514)
			(xy 79.131353 -123.444123) (xy 79.002574 -123.504544) (xy 78.870583 -123.557582) (xy 78.735803 -123.603068)
			(xy 78.598665 -123.640856) (xy 78.45961 -123.670825) (xy 78.319081 -123.692879) (xy 78.17753 -123.706947)
			(xy 78.03541 -123.712984) (xy 77.893175 -123.710971) (xy 77.751283 -123.700914) (xy 77.610187 -123.682846)
			(xy 77.470338 -123.656825) (xy 77.332186 -123.622933) (xy 77.196173 -123.581279) (xy 77.062734 -123.531997)
			(xy 76.932297 -123.475245) (xy 76.80528 -123.411204) (xy 76.682089 -123.34008) (xy 76.56312 -123.2621)
			(xy 76.448752 -123.177514) (xy 76.339353 -123.086594) (xy 76.235274 -122.98963) (xy 76.136846 -122.886933)
			(xy 76.044387 -122.778831) (xy 75.958191 -122.665672) (xy 75.878536 -122.547818) (xy 75.805675 -122.425646)
			(xy 75.739844 -122.299548) (xy 75.681251 -122.169927) (xy 75.630086 -122.037199) (xy 75.586512 -121.901789)
			(xy 75.550668 -121.76413) (xy 75.52267 -121.624664) (xy 75.502607 -121.483838) (xy 75.490544 -121.342102)
			(xy 75.486519 -121.19991) (xy 0.509016 -121.19991) (xy 0.509016 -130.746068) (xy 5.677649 -130.746068)
			(xy 5.677649 -130.619932) (xy 5.685569 -130.494044) (xy 5.701379 -130.368902) (xy 5.725014 -130.244999)
			(xy 5.756383 -130.122826) (xy 5.795361 -130.002863) (xy 5.841795 -129.885584) (xy 5.895502 -129.771452)
			(xy 5.956269 -129.660917) (xy 6.023856 -129.554417) (xy 6.097997 -129.45237) (xy 6.1784 -129.35518)
			(xy 6.264746 -129.26323) (xy 6.356696 -129.176884) (xy 6.453886 -129.096481) (xy 6.555933 -129.02234)
			(xy 6.662433 -128.954753) (xy 6.772968 -128.893986) (xy 6.8871 -128.840279) (xy 7.004379 -128.793845)
			(xy 7.124342 -128.754867) (xy 7.246515 -128.723498) (xy 7.370418 -128.699863) (xy 7.49556 -128.684053)
			(xy 7.621448 -128.676133) (xy 7.747584 -128.676133) (xy 7.873472 -128.684053) (xy 7.998614 -128.699863)
			(xy 8.122517 -128.723498) (xy 8.24469 -128.754867) (xy 8.364653 -128.793845) (xy 8.481932 -128.840279)
			(xy 8.596064 -128.893986) (xy 8.706599 -128.954753) (xy 8.813099 -129.02234) (xy 8.915146 -129.096481)
			(xy 9.012336 -129.176884) (xy 9.104286 -129.26323) (xy 9.190632 -129.35518) (xy 9.271035 -129.45237)
			(xy 9.345176 -129.554417) (xy 9.412763 -129.660917) (xy 9.47353 -129.771452) (xy 9.527237 -129.885584)
			(xy 9.573671 -130.002863) (xy 9.612649 -130.122826) (xy 9.644018 -130.244999) (xy 9.667653 -130.368902)
			(xy 9.683463 -130.494044) (xy 9.691383 -130.619932) (xy 9.691878 -130.683) (xy 9.691383 -130.746068)
			(xy 9.683463 -130.871956) (xy 9.667653 -130.997098) (xy 9.644018 -131.121001) (xy 9.612649 -131.243174)
			(xy 9.573671 -131.363137) (xy 9.527237 -131.480416) (xy 9.47353 -131.594548) (xy 9.412763 -131.705083)
			(xy 9.345176 -131.811583) (xy 9.271035 -131.91363) (xy 9.190632 -132.01082) (xy 9.104286 -132.10277)
			(xy 9.012336 -132.189116) (xy 8.915146 -132.269519) (xy 8.813099 -132.34366) (xy 8.706599 -132.411247)
			(xy 8.596064 -132.472014) (xy 8.481932 -132.525721) (xy 8.364653 -132.572155) (xy 8.24469 -132.611133)
			(xy 8.122517 -132.642502) (xy 7.998614 -132.666137) (xy 7.873472 -132.681947) (xy 7.747584 -132.689867)
			(xy 7.621448 -132.689867) (xy 7.49556 -132.681947) (xy 7.370418 -132.666137) (xy 7.246515 -132.642502)
			(xy 7.124342 -132.611133) (xy 7.004379 -132.572155) (xy 6.8871 -132.525721) (xy 6.772968 -132.472014)
			(xy 6.662433 -132.411247) (xy 6.555933 -132.34366) (xy 6.453886 -132.269519) (xy 6.356696 -132.189116)
			(xy 6.264746 -132.10277) (xy 6.1784 -132.01082) (xy 6.097997 -131.91363) (xy 6.023856 -131.811583)
			(xy 5.956269 -131.705083) (xy 5.895502 -131.594548) (xy 5.841795 -131.480416) (xy 5.795361 -131.363137)
			(xy 5.756383 -131.243174) (xy 5.725014 -131.121001) (xy 5.701379 -130.997098) (xy 5.685569 -130.871956)
			(xy 5.677649 -130.746068) (xy 0.509016 -130.746068) (xy 0.509016 -142.176068) (xy 5.677649 -142.176068)
			(xy 5.677649 -142.049932) (xy 5.685569 -141.924044) (xy 5.701379 -141.798902) (xy 5.725014 -141.674999)
			(xy 5.756383 -141.552826) (xy 5.795361 -141.432863) (xy 5.841795 -141.315584) (xy 5.895502 -141.201452)
			(xy 5.956269 -141.090917) (xy 6.023856 -140.984417) (xy 6.097997 -140.88237) (xy 6.1784 -140.78518)
			(xy 6.264746 -140.69323) (xy 6.356696 -140.606884) (xy 6.453886 -140.526481) (xy 6.555933 -140.45234)
			(xy 6.662433 -140.384753) (xy 6.772968 -140.323986) (xy 6.8871 -140.270279) (xy 7.004379 -140.223845)
			(xy 7.124342 -140.184867) (xy 7.246515 -140.153498) (xy 7.370418 -140.129863) (xy 7.49556 -140.114053)
			(xy 7.621448 -140.106133) (xy 7.747584 -140.106133) (xy 7.873472 -140.114053) (xy 7.998614 -140.129863)
			(xy 8.122517 -140.153498) (xy 8.24469 -140.184867) (xy 8.364653 -140.223845) (xy 8.441392 -140.254228)
			(xy 39.818818 -140.254228) (xy 39.819523 -140.195605) (xy 39.828091 -140.078667) (xy 39.844787 -139.962611)
			(xy 39.86953 -139.848001) (xy 39.902199 -139.735393) (xy 39.942635 -139.625335) (xy 39.990642 -139.518363)
			(xy 40.045986 -139.414996) (xy 40.108399 -139.315737) (xy 40.177577 -139.221068) (xy 40.253183 -139.13145)
			(xy 40.334851 -139.047318) (xy 40.422182 -138.969081) (xy 40.514753 -138.89712) (xy 40.612113 -138.831784)
			(xy 40.713789 -138.773392) (xy 40.819288 -138.722226) (xy 40.928095 -138.678537) (xy 41.039682 -138.642535)
			(xy 41.153506 -138.614397) (xy 41.269014 -138.594259) (xy 41.385645 -138.582218) (xy 41.502832 -138.578334)
			(xy 41.620004 -138.582625) (xy 41.736593 -138.595071) (xy 41.85203 -138.615611) (xy 41.965756 -138.644144)
			(xy 42.077217 -138.680533) (xy 42.185872 -138.724601) (xy 42.291192 -138.776133) (xy 42.392665 -138.834878)
			(xy 42.489797 -138.900552) (xy 42.582117 -138.972834) (xy 42.669176 -139.051374) (xy 42.750551 -139.135789)
			(xy 42.825845 -139.225669) (xy 42.894694 -139.320578) (xy 42.956761 -139.420054) (xy 43.011746 -139.523612)
			(xy 43.059381 -139.630751) (xy 43.099434 -139.740948) (xy 43.131712 -139.853669) (xy 43.156056 -139.968365)
			(xy 43.172348 -140.084478) (xy 43.18051 -140.201445) (xy 43.181016 -140.26007) (xy 43.180861 -140.290833)
			(xy 43.178574 -140.352316) (xy 43.176444 -140.383006) (xy 43.175682 -140.392404) (xy 43.170622 -140.450806)
			(xy 43.153396 -140.566771) (xy 43.12813 -140.681253) (xy 43.094949 -140.793697) (xy 43.054014 -140.903555)
			(xy 43.005523 -141.010294) (xy 42.949712 -141.113395) (xy 42.886853 -141.212356) (xy 42.817252 -141.306696)
			(xy 42.741246 -141.395958) (xy 42.659204 -141.479706) (xy 42.571527 -141.557535) (xy 42.503292 -141.61008)
			(xy 93.15476 -141.61008) (xy 93.158776 -141.49381) (xy 93.170803 -141.378095) (xy 93.190785 -141.263485)
			(xy 93.218627 -141.150526) (xy 93.254196 -141.039758) (xy 93.297322 -140.931707) (xy 93.347799 -140.826889)
			(xy 93.405388 -140.725804) (xy 93.469814 -140.628932) (xy 93.540769 -140.536736) (xy 93.617916 -140.449655)
			(xy 93.700887 -140.368104) (xy 93.789287 -140.292472) (xy 93.882694 -140.223118) (xy 93.980663 -140.160375)
			(xy 94.082727 -140.104539) (xy 94.188401 -140.055878) (xy 94.29718 -140.014624) (xy 94.408545 -139.980973)
			(xy 94.521968 -139.955085) (xy 94.636905 -139.937084) (xy 94.752811 -139.927055) (xy 94.869133 -139.925047)
			(xy 94.985316 -139.931069) (xy 95.100807 -139.945092) (xy 95.215055 -139.96705) (xy 95.327516 -139.996837)
			(xy 95.437654 -140.034312) (xy 95.544944 -140.079297) (xy 95.648875 -140.131576) (xy 95.748951 -140.190901)
			(xy 95.844697 -140.256989) (xy 95.935654 -140.329525) (xy 96.02139 -140.408164) (xy 96.101497 -140.49253)
			(xy 96.175593 -140.582222) (xy 96.243323 -140.676812) (xy 96.304367 -140.77585) (xy 96.358432 -140.878863)
			(xy 96.405262 -140.98536) (xy 96.444633 -141.094835) (xy 96.476357 -141.206765) (xy 96.500283 -141.320617)
			(xy 96.516297 -141.435849) (xy 96.524324 -141.551911) (xy 96.524826 -141.61008) (xy 96.524324 -141.668249)
			(xy 96.516297 -141.784311) (xy 96.500283 -141.899543) (xy 96.476357 -142.013395) (xy 96.444633 -142.125325)
			(xy 96.405262 -142.2348) (xy 96.358432 -142.341297) (xy 96.304367 -142.44431) (xy 96.243323 -142.543348)
			(xy 96.175593 -142.637938) (xy 96.101497 -142.72763) (xy 96.02139 -142.811996) (xy 95.935654 -142.890635)
			(xy 95.844697 -142.963171) (xy 95.748951 -143.029259) (xy 95.648875 -143.088584) (xy 95.544944 -143.140863)
			(xy 95.437654 -143.185848) (xy 95.327516 -143.223323) (xy 95.215055 -143.25311) (xy 95.100807 -143.275068)
			(xy 94.985316 -143.289091) (xy 94.869133 -143.295113) (xy 94.752811 -143.293105) (xy 94.636905 -143.283076)
			(xy 94.521968 -143.265075) (xy 94.408545 -143.239187) (xy 94.29718 -143.205536) (xy 94.188401 -143.164282)
			(xy 94.082727 -143.115621) (xy 93.980663 -143.059785) (xy 93.882694 -142.997042) (xy 93.789287 -142.927688)
			(xy 93.700887 -142.852056) (xy 93.617916 -142.770505) (xy 93.540769 -142.683424) (xy 93.469814 -142.591228)
			(xy 93.405388 -142.494356) (xy 93.347799 -142.393271) (xy 93.297322 -142.288453) (xy 93.254196 -142.180402)
			(xy 93.218627 -142.069634) (xy 93.190785 -141.956675) (xy 93.170803 -141.842065) (xy 93.158776 -141.72635)
			(xy 93.15476 -141.61008) (xy 42.503292 -141.61008) (xy 42.47864 -141.629064) (xy 42.380994 -141.693948)
			(xy 42.279065 -141.75187) (xy 42.173347 -141.802549) (xy 42.064355 -141.845738) (xy 41.952619 -141.881228)
			(xy 41.838681 -141.908845) (xy 41.723096 -141.928457) (xy 41.606425 -141.939967) (xy 41.489236 -141.943319)
			(xy 41.372098 -141.938497) (xy 41.25558 -141.925525) (xy 41.14025 -141.904466) (xy 41.026668 -141.875421)
			(xy 40.915385 -141.838533) (xy 40.806943 -141.79398) (xy 40.70187 -141.74198) (xy 40.600675 -141.682784)
			(xy 40.50385 -141.616681) (xy 40.411868 -141.543992) (xy 40.325173 -141.46507) (xy 40.244189 -141.380299)
			(xy 40.169308 -141.290091) (xy 40.100895 -141.194885) (xy 40.039282 -141.095143) (xy 39.984769 -140.991351)
			(xy 39.937621 -140.884012) (xy 39.898066 -140.773649) (xy 39.866298 -140.660798) (xy 39.842471 -140.546008)
			(xy 39.826699 -140.429836) (xy 39.819061 -140.312848) (xy 39.818818 -140.254228) (xy 8.441392 -140.254228)
			(xy 8.481932 -140.270279) (xy 8.596064 -140.323986) (xy 8.706599 -140.384753) (xy 8.813099 -140.45234)
			(xy 8.915146 -140.526481) (xy 9.012336 -140.606884) (xy 9.104286 -140.69323) (xy 9.190632 -140.78518)
			(xy 9.271035 -140.88237) (xy 9.345176 -140.984417) (xy 9.412763 -141.090917) (xy 9.47353 -141.201452)
			(xy 9.527237 -141.315584) (xy 9.573671 -141.432863) (xy 9.612649 -141.552826) (xy 9.644018 -141.674999)
			(xy 9.667653 -141.798902) (xy 9.683463 -141.924044) (xy 9.691383 -142.049932) (xy 9.691878 -142.113)
			(xy 9.691383 -142.176068) (xy 9.683463 -142.301956) (xy 9.667653 -142.427098) (xy 9.644018 -142.551001)
			(xy 9.612649 -142.673174) (xy 9.573671 -142.793137) (xy 9.527237 -142.910416) (xy 9.47353 -143.024548)
			(xy 9.412763 -143.135083) (xy 9.345176 -143.241583) (xy 9.271035 -143.34363) (xy 9.190632 -143.44082)
			(xy 9.104286 -143.53277) (xy 9.012336 -143.619116) (xy 8.915146 -143.699519) (xy 8.813099 -143.77366)
			(xy 8.706599 -143.841247) (xy 8.596064 -143.902014) (xy 8.481932 -143.955721) (xy 8.364653 -144.002155)
			(xy 8.24469 -144.041133) (xy 8.122517 -144.072502) (xy 7.998614 -144.096137) (xy 7.873472 -144.111947)
			(xy 7.747584 -144.119867) (xy 7.621448 -144.119867) (xy 7.49556 -144.111947) (xy 7.370418 -144.096137)
			(xy 7.246515 -144.072502) (xy 7.124342 -144.041133) (xy 7.004379 -144.002155) (xy 6.8871 -143.955721)
			(xy 6.772968 -143.902014) (xy 6.662433 -143.841247) (xy 6.555933 -143.77366) (xy 6.453886 -143.699519)
			(xy 6.356696 -143.619116) (xy 6.264746 -143.53277) (xy 6.1784 -143.44082) (xy 6.097997 -143.34363)
			(xy 6.023856 -143.241583) (xy 5.956269 -143.135083) (xy 5.895502 -143.024548) (xy 5.841795 -142.910416)
			(xy 5.795361 -142.793137) (xy 5.756383 -142.673174) (xy 5.725014 -142.551001) (xy 5.701379 -142.427098)
			(xy 5.685569 -142.301956) (xy 5.677649 -142.176068) (xy 0.509016 -142.176068) (xy 0.509016 -153.359866)
			(xy 86.877404 -153.359866) (xy 86.881424 -153.169215) (xy 86.893478 -152.978902) (xy 86.913544 -152.789267)
			(xy 86.941587 -152.600646) (xy 86.977556 -152.413376) (xy 87.021388 -152.227788) (xy 87.073005 -152.044213)
			(xy 87.132315 -151.862977) (xy 87.199213 -151.684402) (xy 87.273579 -151.508807) (xy 87.355281 -151.336502)
			(xy 87.444175 -151.167795) (xy 87.540101 -151.002985) (xy 87.64289 -150.842366) (xy 87.752359 -150.686223)
			(xy 87.868313 -150.534834) (xy 87.990547 -150.388467) (xy 88.118841 -150.247383) (xy 88.252969 -150.111834)
			(xy 88.392693 -149.982059) (xy 88.537763 -149.858289) (xy 88.687921 -149.740746) (xy 88.842902 -149.629637)
			(xy 89.002429 -149.52516) (xy 89.166218 -149.427501) (xy 89.333978 -149.336834) (xy 89.505412 -149.25332)
			(xy 89.680214 -149.177107) (xy 89.858073 -149.108331) (xy 90.038674 -149.047113) (xy 90.221694 -148.993564)
			(xy 90.40681 -148.947778) (xy 90.593691 -148.909836) (xy 90.782006 -148.879807) (xy 90.971419 -148.857742)
			(xy 91.161593 -148.843683) (xy 91.352192 -148.837653) (xy 91.542875 -148.839663) (xy 91.733304 -148.84971)
			(xy 91.92314 -148.867776) (xy 92.112046 -148.893829) (xy 92.299685 -148.927822) (xy 92.485725 -148.969695)
			(xy 92.669834 -149.019374) (xy 92.851685 -149.07677) (xy 93.030955 -149.141781) (xy 93.207325 -149.214292)
			(xy 93.380481 -149.294173) (xy 93.550116 -149.381283) (xy 93.715928 -149.475467) (xy 93.877622 -149.576558)
			(xy 94.03491 -149.684374) (xy 94.187513 -149.798726) (xy 94.335161 -149.919409) (xy 94.477589 -150.04621)
			(xy 94.614545 -150.178901) (xy 94.745786 -150.317249) (xy 94.871078 -150.461006) (xy 94.990198 -150.609917)
			(xy 95.102934 -150.763718) (xy 95.209087 -150.922134) (xy 95.308467 -151.084885) (xy 95.400897 -151.25168)
			(xy 95.486214 -151.422224) (xy 95.564266 -151.596212) (xy 95.634913 -151.773337) (xy 95.698031 -151.953282)
			(xy 95.753507 -152.135728) (xy 95.801242 -152.320351) (xy 95.841152 -152.506821) (xy 95.873165 -152.694809)
			(xy 95.897225 -152.883979) (xy 95.913288 -153.073995) (xy 95.921327 -153.264519) (xy 95.92183 -153.359866)
			(xy 95.921327 -153.455213) (xy 95.913288 -153.645737) (xy 95.897225 -153.835753) (xy 95.873165 -154.024923)
			(xy 95.841152 -154.212911) (xy 95.801242 -154.399381) (xy 95.753507 -154.584004) (xy 95.698031 -154.76645)
			(xy 95.634913 -154.946395) (xy 95.564266 -155.12352) (xy 95.486214 -155.297508) (xy 95.400897 -155.468052)
			(xy 95.308467 -155.634847) (xy 95.209087 -155.797598) (xy 95.102934 -155.956014) (xy 94.990198 -156.109815)
			(xy 94.871078 -156.258726) (xy 94.745786 -156.402483) (xy 94.614545 -156.540831) (xy 94.477589 -156.673522)
			(xy 94.335161 -156.800323) (xy 94.187513 -156.921006) (xy 94.03491 -157.035358) (xy 93.877622 -157.143174)
			(xy 93.715928 -157.244265) (xy 93.550116 -157.338449) (xy 93.380481 -157.425559) (xy 93.207325 -157.50544)
			(xy 93.030955 -157.577951) (xy 92.851685 -157.642962) (xy 92.669834 -157.700358) (xy 92.485725 -157.750037)
			(xy 92.299685 -157.79191) (xy 92.112046 -157.825903) (xy 91.92314 -157.851956) (xy 91.733304 -157.870022)
			(xy 91.542875 -157.880069) (xy 91.352192 -157.882079) (xy 91.161593 -157.876049) (xy 90.971419 -157.86199)
			(xy 90.782006 -157.839925) (xy 90.593691 -157.809896) (xy 90.40681 -157.771954) (xy 90.221694 -157.726168)
			(xy 90.038674 -157.672619) (xy 89.858073 -157.611401) (xy 89.680214 -157.542625) (xy 89.505412 -157.466412)
			(xy 89.333978 -157.382898) (xy 89.166218 -157.292231) (xy 89.002429 -157.194572) (xy 88.842902 -157.090095)
			(xy 88.687921 -156.978986) (xy 88.537763 -156.861443) (xy 88.392693 -156.737673) (xy 88.252969 -156.607898)
			(xy 88.118841 -156.472349) (xy 87.990547 -156.331265) (xy 87.868313 -156.184898) (xy 87.752359 -156.033509)
			(xy 87.64289 -155.877366) (xy 87.540101 -155.716747) (xy 87.444175 -155.551937) (xy 87.355281 -155.38323)
			(xy 87.273579 -155.210925) (xy 87.199213 -155.03533) (xy 87.132315 -154.856755) (xy 87.073005 -154.675519)
			(xy 87.021388 -154.491944) (xy 86.977556 -154.306356) (xy 86.941587 -154.119086) (xy 86.913544 -153.930465)
			(xy 86.893478 -153.74083) (xy 86.881424 -153.550517) (xy 86.877404 -153.359866) (xy 0.509016 -153.359866)
			(xy 0.509016 -184.704228) (xy 39.818818 -184.704228) (xy 39.819523 -184.645605) (xy 39.828091 -184.528667)
			(xy 39.844787 -184.412611) (xy 39.86953 -184.298001) (xy 39.902199 -184.185393) (xy 39.942635 -184.075335)
			(xy 39.990642 -183.968363) (xy 40.045986 -183.864996) (xy 40.108399 -183.765737) (xy 40.177577 -183.671068)
			(xy 40.253183 -183.58145) (xy 40.334851 -183.497318) (xy 40.422182 -183.419081) (xy 40.514753 -183.34712)
			(xy 40.612113 -183.281784) (xy 40.713789 -183.223392) (xy 40.819288 -183.172226) (xy 40.928095 -183.128537)
			(xy 41.039682 -183.092535) (xy 41.153506 -183.064397) (xy 41.269014 -183.044259) (xy 41.385645 -183.032218)
			(xy 41.502832 -183.028334) (xy 41.620004 -183.032625) (xy 41.736593 -183.045071) (xy 41.85203 -183.065611)
			(xy 41.965756 -183.094144) (xy 42.077217 -183.130533) (xy 42.185872 -183.174601) (xy 42.291192 -183.226133)
			(xy 42.392665 -183.284878) (xy 42.489797 -183.350552) (xy 42.582117 -183.422834) (xy 42.669176 -183.501374)
			(xy 42.750551 -183.585789) (xy 42.825845 -183.675669) (xy 42.894694 -183.770578) (xy 42.956761 -183.870054)
			(xy 43.011746 -183.973612) (xy 43.059381 -184.080751) (xy 43.099434 -184.190948) (xy 43.131712 -184.303669)
			(xy 43.156056 -184.418365) (xy 43.172348 -184.534478) (xy 43.18051 -184.651445) (xy 43.181016 -184.71007)
			(xy 43.180861 -184.740833) (xy 43.178574 -184.802316) (xy 43.176444 -184.833006) (xy 43.175682 -184.842404)
			(xy 43.170622 -184.900806) (xy 43.153396 -185.016771) (xy 43.12813 -185.131253) (xy 43.094949 -185.243697)
			(xy 43.054014 -185.353555) (xy 43.005523 -185.460294) (xy 42.949712 -185.563395) (xy 42.886853 -185.662356)
			(xy 42.817252 -185.756696) (xy 42.741246 -185.845958) (xy 42.659204 -185.929706) (xy 42.571527 -186.007535)
			(xy 42.503292 -186.06008) (xy 93.15476 -186.06008) (xy 93.158776 -185.94381) (xy 93.170803 -185.828095)
			(xy 93.190785 -185.713485) (xy 93.218627 -185.600526) (xy 93.254196 -185.489758) (xy 93.297322 -185.381707)
			(xy 93.347799 -185.276889) (xy 93.405388 -185.175804) (xy 93.469814 -185.078932) (xy 93.540769 -184.986736)
			(xy 93.617916 -184.899655) (xy 93.700887 -184.818104) (xy 93.789287 -184.742472) (xy 93.882694 -184.673118)
			(xy 93.980663 -184.610375) (xy 94.082727 -184.554539) (xy 94.188401 -184.505878) (xy 94.29718 -184.464624)
			(xy 94.408545 -184.430973) (xy 94.521968 -184.405085) (xy 94.636905 -184.387084) (xy 94.752811 -184.377055)
			(xy 94.869133 -184.375047) (xy 94.985316 -184.381069) (xy 95.100807 -184.395092) (xy 95.215055 -184.41705)
			(xy 95.327516 -184.446837) (xy 95.437654 -184.484312) (xy 95.544944 -184.529297) (xy 95.648875 -184.581576)
			(xy 95.748951 -184.640901) (xy 95.844697 -184.706989) (xy 95.935654 -184.779525) (xy 96.02139 -184.858164)
			(xy 96.101497 -184.94253) (xy 96.175593 -185.032222) (xy 96.243323 -185.126812) (xy 96.304367 -185.22585)
			(xy 96.358432 -185.328863) (xy 96.405262 -185.43536) (xy 96.444633 -185.544835) (xy 96.476357 -185.656765)
			(xy 96.500283 -185.770617) (xy 96.516297 -185.885849) (xy 96.524324 -186.001911) (xy 96.524826 -186.06008)
			(xy 96.524324 -186.118249) (xy 96.516297 -186.234311) (xy 96.500283 -186.349543) (xy 96.476357 -186.463395)
			(xy 96.444633 -186.575325) (xy 96.405262 -186.6848) (xy 96.358432 -186.791297) (xy 96.304367 -186.89431)
			(xy 96.243323 -186.993348) (xy 96.175593 -187.087938) (xy 96.101497 -187.17763) (xy 96.02139 -187.261996)
			(xy 95.935654 -187.340635) (xy 95.844697 -187.413171) (xy 95.748951 -187.479259) (xy 95.648875 -187.538584)
			(xy 95.544944 -187.590863) (xy 95.437654 -187.635848) (xy 95.327516 -187.673323) (xy 95.215055 -187.70311)
			(xy 95.100807 -187.725068) (xy 94.985316 -187.739091) (xy 94.869133 -187.745113) (xy 94.752811 -187.743105)
			(xy 94.636905 -187.733076) (xy 94.521968 -187.715075) (xy 94.408545 -187.689187) (xy 94.29718 -187.655536)
			(xy 94.188401 -187.614282) (xy 94.082727 -187.565621) (xy 93.980663 -187.509785) (xy 93.882694 -187.447042)
			(xy 93.789287 -187.377688) (xy 93.700887 -187.302056) (xy 93.617916 -187.220505) (xy 93.540769 -187.133424)
			(xy 93.469814 -187.041228) (xy 93.405388 -186.944356) (xy 93.347799 -186.843271) (xy 93.297322 -186.738453)
			(xy 93.254196 -186.630402) (xy 93.218627 -186.519634) (xy 93.190785 -186.406675) (xy 93.170803 -186.292065)
			(xy 93.158776 -186.17635) (xy 93.15476 -186.06008) (xy 42.503292 -186.06008) (xy 42.47864 -186.079064)
			(xy 42.380994 -186.143948) (xy 42.279065 -186.20187) (xy 42.173347 -186.252549) (xy 42.064355 -186.295738)
			(xy 41.952619 -186.331228) (xy 41.838681 -186.358845) (xy 41.723096 -186.378457) (xy 41.606425 -186.389967)
			(xy 41.489236 -186.393319) (xy 41.372098 -186.388497) (xy 41.25558 -186.375525) (xy 41.14025 -186.354466)
			(xy 41.026668 -186.325421) (xy 40.915385 -186.288533) (xy 40.806943 -186.24398) (xy 40.70187 -186.19198)
			(xy 40.600675 -186.132784) (xy 40.50385 -186.066681) (xy 40.411868 -185.993992) (xy 40.325173 -185.91507)
			(xy 40.244189 -185.830299) (xy 40.169308 -185.740091) (xy 40.100895 -185.644885) (xy 40.039282 -185.545143)
			(xy 39.984769 -185.441351) (xy 39.937621 -185.334012) (xy 39.898066 -185.223649) (xy 39.866298 -185.110798)
			(xy 39.842471 -184.996008) (xy 39.826699 -184.879836) (xy 39.819061 -184.762848) (xy 39.818818 -184.704228)
			(xy 0.509016 -184.704228) (xy 0.509016 -197.81012) (xy 86.877404 -197.81012) (xy 86.881424 -197.619469)
			(xy 86.893478 -197.429156) (xy 86.913544 -197.239521) (xy 86.941587 -197.0509) (xy 86.977556 -196.86363)
			(xy 87.021388 -196.678042) (xy 87.073005 -196.494467) (xy 87.132315 -196.313231) (xy 87.199213 -196.134656)
			(xy 87.273579 -195.959061) (xy 87.355281 -195.786756) (xy 87.444175 -195.618049) (xy 87.540101 -195.453239)
			(xy 87.64289 -195.29262) (xy 87.752359 -195.136477) (xy 87.868313 -194.985088) (xy 87.990547 -194.838721)
			(xy 88.118841 -194.697637) (xy 88.252969 -194.562088) (xy 88.392693 -194.432313) (xy 88.537763 -194.308543)
			(xy 88.687921 -194.191) (xy 88.842902 -194.079891) (xy 89.002429 -193.975414) (xy 89.166218 -193.877755)
			(xy 89.333978 -193.787088) (xy 89.505412 -193.703574) (xy 89.680214 -193.627361) (xy 89.858073 -193.558585)
			(xy 90.038674 -193.497367) (xy 90.221694 -193.443818) (xy 90.40681 -193.398032) (xy 90.593691 -193.36009)
			(xy 90.782006 -193.330061) (xy 90.971419 -193.307996) (xy 91.161593 -193.293937) (xy 91.352192 -193.287907)
			(xy 91.542875 -193.289917) (xy 91.733304 -193.299964) (xy 91.92314 -193.31803) (xy 92.112046 -193.344083)
			(xy 92.299685 -193.378076) (xy 92.485725 -193.419949) (xy 92.669834 -193.469628) (xy 92.851685 -193.527024)
			(xy 93.030955 -193.592035) (xy 93.207325 -193.664546) (xy 93.380481 -193.744427) (xy 93.550116 -193.831537)
			(xy 93.715928 -193.925721) (xy 93.877622 -194.026812) (xy 94.03491 -194.134628) (xy 94.187513 -194.24898)
			(xy 94.335161 -194.369663) (xy 94.477589 -194.496464) (xy 94.614545 -194.629155) (xy 94.745786 -194.767503)
			(xy 94.871078 -194.91126) (xy 94.990198 -195.060171) (xy 95.102934 -195.213972) (xy 95.209087 -195.372388)
			(xy 95.308467 -195.535139) (xy 95.400897 -195.701934) (xy 95.486214 -195.872478) (xy 95.564266 -196.046466)
			(xy 95.634913 -196.223591) (xy 95.698031 -196.403536) (xy 95.753507 -196.585982) (xy 95.801242 -196.770605)
			(xy 95.841152 -196.957075) (xy 95.873165 -197.145063) (xy 95.897225 -197.334233) (xy 95.913288 -197.524249)
			(xy 95.921327 -197.714773) (xy 95.92183 -197.81012) (xy 95.921327 -197.905467) (xy 95.913288 -198.095991)
			(xy 95.897225 -198.286007) (xy 95.873165 -198.475177) (xy 95.841152 -198.663165) (xy 95.801242 -198.849635)
			(xy 95.753507 -199.034258) (xy 95.698031 -199.216704) (xy 95.634913 -199.396649) (xy 95.564266 -199.573774)
			(xy 95.486214 -199.747762) (xy 95.400897 -199.918306) (xy 95.308467 -200.085101) (xy 95.209087 -200.247852)
			(xy 95.102934 -200.406268) (xy 94.990198 -200.560069) (xy 94.871078 -200.70898) (xy 94.745786 -200.852737)
			(xy 94.614545 -200.991085) (xy 94.477589 -201.123776) (xy 94.335161 -201.250577) (xy 94.187513 -201.37126)
			(xy 94.03491 -201.485612) (xy 93.877622 -201.593428) (xy 93.715928 -201.694519) (xy 93.550116 -201.788703)
			(xy 93.380481 -201.875813) (xy 93.207325 -201.955694) (xy 93.030955 -202.028205) (xy 92.851685 -202.093216)
			(xy 92.669834 -202.150612) (xy 92.485725 -202.200291) (xy 92.299685 -202.242164) (xy 92.112046 -202.276157)
			(xy 91.92314 -202.30221) (xy 91.733304 -202.320276) (xy 91.542875 -202.330323) (xy 91.352192 -202.332333)
			(xy 91.161593 -202.326303) (xy 90.971419 -202.312244) (xy 90.782006 -202.290179) (xy 90.593691 -202.26015)
			(xy 90.40681 -202.222208) (xy 90.221694 -202.176422) (xy 90.038674 -202.122873) (xy 89.858073 -202.061655)
			(xy 89.680214 -201.992879) (xy 89.505412 -201.916666) (xy 89.333978 -201.833152) (xy 89.166218 -201.742485)
			(xy 89.002429 -201.644826) (xy 88.842902 -201.540349) (xy 88.687921 -201.42924) (xy 88.537763 -201.311697)
			(xy 88.392693 -201.187927) (xy 88.252969 -201.058152) (xy 88.118841 -200.922603) (xy 87.990547 -200.781519)
			(xy 87.868313 -200.635152) (xy 87.752359 -200.483763) (xy 87.64289 -200.32762) (xy 87.540101 -200.167001)
			(xy 87.444175 -200.002191) (xy 87.355281 -199.833484) (xy 87.273579 -199.661179) (xy 87.199213 -199.485584)
			(xy 87.132315 -199.307009) (xy 87.073005 -199.125773) (xy 87.021388 -198.942198) (xy 86.977556 -198.75661)
			(xy 86.941587 -198.56934) (xy 86.913544 -198.380719) (xy 86.893478 -198.191084) (xy 86.881424 -198.000771)
			(xy 86.877404 -197.81012) (xy 0.509016 -197.81012) (xy 0.509016 -206.99984) (xy 14.086591 -206.99984)
			(xy 14.090616 -206.857648) (xy 14.102679 -206.715912) (xy 14.122742 -206.575086) (xy 14.15074 -206.43562)
			(xy 14.186584 -206.297961) (xy 14.230158 -206.162551) (xy 14.281323 -206.029823) (xy 14.339916 -205.900202)
			(xy 14.405747 -205.774104) (xy 14.478608 -205.651932) (xy 14.558263 -205.534078) (xy 14.644459 -205.420919)
			(xy 14.736918 -205.312817) (xy 14.835346 -205.21012) (xy 14.939425 -205.113156) (xy 15.048824 -205.022236)
			(xy 15.163192 -204.93765) (xy 15.282161 -204.85967) (xy 15.405352 -204.788546) (xy 15.532369 -204.724505)
			(xy 15.662806 -204.667753) (xy 15.796245 -204.618471) (xy 15.932258 -204.576817) (xy 16.07041 -204.542925)
			(xy 16.210259 -204.516904) (xy 16.351355 -204.498836) (xy 16.493247 -204.488779) (xy 16.635482 -204.486766)
			(xy 16.777602 -204.492803) (xy 16.919153 -204.506871) (xy 17.059682 -204.528925) (xy 17.198737 -204.558894)
			(xy 17.335875 -204.596682) (xy 17.470655 -204.642168) (xy 17.602646 -204.695206) (xy 17.731425 -204.755627)
			(xy 17.856579 -204.823236) (xy 17.977707 -204.897818) (xy 18.094423 -204.979134) (xy 18.206351 -205.066922)
			(xy 18.313133 -205.160902) (xy 18.414427 -205.260772) (xy 18.509908 -205.366214) (xy 18.599272 -205.476888)
			(xy 18.68223 -205.592441) (xy 18.758519 -205.712502) (xy 18.827893 -205.836687) (xy 18.89013 -205.964598)
			(xy 18.945031 -206.095825) (xy 18.992419 -206.229948) (xy 19.032144 -206.366537) (xy 19.064077 -206.505155)
			(xy 19.088118 -206.645357) (xy 19.104187 -206.786695) (xy 19.112235 -206.928716) (xy 19.112738 -206.99984)
			(xy 19.112235 -207.070964) (xy 19.104187 -207.212985) (xy 19.088118 -207.354323) (xy 19.064077 -207.494525)
			(xy 19.032144 -207.633143) (xy 18.992419 -207.769732) (xy 18.945031 -207.903855) (xy 18.89013 -208.035082)
			(xy 18.827893 -208.162993) (xy 18.758519 -208.287178) (xy 18.68223 -208.407239) (xy 18.599272 -208.522792)
			(xy 18.509908 -208.633466) (xy 18.414427 -208.738908) (xy 18.313133 -208.838778) (xy 18.206351 -208.932758)
			(xy 18.094423 -209.020546) (xy 17.977707 -209.101862) (xy 17.856579 -209.176444) (xy 17.731425 -209.244053)
			(xy 17.602646 -209.304474) (xy 17.470655 -209.357512) (xy 17.335875 -209.402998) (xy 17.198737 -209.440786)
			(xy 17.059682 -209.470755) (xy 16.919153 -209.492809) (xy 16.777602 -209.506877) (xy 16.635482 -209.512914)
			(xy 16.493247 -209.510901) (xy 16.351355 -209.500844) (xy 16.210259 -209.482776) (xy 16.07041 -209.456755)
			(xy 15.932258 -209.422863) (xy 15.796245 -209.381209) (xy 15.662806 -209.331927) (xy 15.532369 -209.275175)
			(xy 15.405352 -209.211134) (xy 15.282161 -209.14001) (xy 15.163192 -209.06203) (xy 15.048824 -208.977444)
			(xy 14.939425 -208.886524) (xy 14.835346 -208.78956) (xy 14.736918 -208.686863) (xy 14.644459 -208.578761)
			(xy 14.558263 -208.465602) (xy 14.478608 -208.347748) (xy 14.405747 -208.225576) (xy 14.339916 -208.099478)
			(xy 14.281323 -207.969857) (xy 14.230158 -207.837129) (xy 14.186584 -207.701719) (xy 14.15074 -207.56406)
			(xy 14.122742 -207.424594) (xy 14.102679 -207.283768) (xy 14.090616 -207.142032) (xy 14.086591 -206.99984)
			(xy 0.509016 -206.99984) (xy 0.509016 -210.09991) (xy 75.486519 -210.09991) (xy 75.490544 -209.957718)
			(xy 75.502607 -209.815982) (xy 75.52267 -209.675156) (xy 75.550668 -209.53569) (xy 75.586512 -209.398031)
			(xy 75.630086 -209.262621) (xy 75.681251 -209.129893) (xy 75.739844 -209.000272) (xy 75.805675 -208.874174)
			(xy 75.878536 -208.752002) (xy 75.958191 -208.634148) (xy 76.044387 -208.520989) (xy 76.136846 -208.412887)
			(xy 76.235274 -208.31019) (xy 76.339353 -208.213226) (xy 76.448752 -208.122306) (xy 76.56312 -208.03772)
			(xy 76.682089 -207.95974) (xy 76.80528 -207.888616) (xy 76.932297 -207.824575) (xy 77.062734 -207.767823)
			(xy 77.196173 -207.718541) (xy 77.332186 -207.676887) (xy 77.470338 -207.642995) (xy 77.610187 -207.616974)
			(xy 77.751283 -207.598906) (xy 77.893175 -207.588849) (xy 78.03541 -207.586836) (xy 78.17753 -207.592873)
			(xy 78.319081 -207.606941) (xy 78.45961 -207.628995) (xy 78.598665 -207.658964) (xy 78.735803 -207.696752)
			(xy 78.870583 -207.742238) (xy 79.002574 -207.795276) (xy 79.131353 -207.855697) (xy 79.256507 -207.923306)
			(xy 79.377635 -207.997888) (xy 79.494351 -208.079204) (xy 79.606279 -208.166992) (xy 79.713061 -208.260972)
			(xy 79.814355 -208.360842) (xy 79.909836 -208.466284) (xy 79.9992 -208.576958) (xy 80.082158 -208.692511)
			(xy 80.158447 -208.812572) (xy 80.227821 -208.936757) (xy 80.290058 -209.064668) (xy 80.344959 -209.195895)
			(xy 80.392347 -209.330018) (xy 80.432072 -209.466607) (xy 80.464005 -209.605225) (xy 80.488046 -209.745427)
			(xy 80.504115 -209.886765) (xy 80.512163 -210.028786) (xy 80.512666 -210.09991) (xy 80.512163 -210.171034)
			(xy 80.504115 -210.313055) (xy 80.488046 -210.454393) (xy 80.464005 -210.594595) (xy 80.432072 -210.733213)
			(xy 80.392347 -210.869802) (xy 80.344959 -211.003925) (xy 80.290058 -211.135152) (xy 80.227821 -211.263063)
			(xy 80.158447 -211.387248) (xy 80.082158 -211.507309) (xy 79.9992 -211.622862) (xy 79.909836 -211.733536)
			(xy 79.814355 -211.838978) (xy 79.713061 -211.938848) (xy 79.606279 -212.032828) (xy 79.494351 -212.120616)
			(xy 79.377635 -212.201932) (xy 79.256507 -212.276514) (xy 79.131353 -212.344123) (xy 79.002574 -212.404544)
			(xy 78.870583 -212.457582) (xy 78.735803 -212.503068) (xy 78.598665 -212.540856) (xy 78.45961 -212.570825)
			(xy 78.319081 -212.592879) (xy 78.17753 -212.606947) (xy 78.03541 -212.612984) (xy 77.893175 -212.610971)
			(xy 77.751283 -212.600914) (xy 77.610187 -212.582846) (xy 77.470338 -212.556825) (xy 77.332186 -212.522933)
			(xy 77.196173 -212.481279) (xy 77.062734 -212.431997) (xy 76.932297 -212.375245) (xy 76.80528 -212.311204)
			(xy 76.682089 -212.24008) (xy 76.56312 -212.1621) (xy 76.448752 -212.077514) (xy 76.339353 -211.986594)
			(xy 76.235274 -211.88963) (xy 76.136846 -211.786933) (xy 76.044387 -211.678831) (xy 75.958191 -211.565672)
			(xy 75.878536 -211.447818) (xy 75.805675 -211.325646) (xy 75.739844 -211.199548) (xy 75.681251 -211.069927)
			(xy 75.630086 -210.937199) (xy 75.586512 -210.801789) (xy 75.550668 -210.66413) (xy 75.52267 -210.524664)
			(xy 75.502607 -210.383838) (xy 75.490544 -210.242102) (xy 75.486519 -210.09991) (xy 0.509016 -210.09991)
			(xy 0.509016 -229.16007) (xy 39.818564 -229.16007) (xy 39.819058 -229.102661) (xy 39.826902 -228.988113)
			(xy 39.842544 -228.874366) (xy 39.865911 -228.761952) (xy 39.896896 -228.651394) (xy 39.935352 -228.543209)
			(xy 39.981101 -228.4379) (xy 40.03393 -228.335958) (xy 40.093592 -228.237859) (xy 40.159809 -228.14406)
			(xy 40.232272 -228.054998) (xy 40.310645 -227.971089) (xy 40.39456 -227.892723) (xy 40.483627 -227.820266)
			(xy 40.577431 -227.754056) (xy 40.675535 -227.694402) (xy 40.777481 -227.641581) (xy 40.882793 -227.595839)
			(xy 40.990981 -227.557391) (xy 41.101541 -227.526415) (xy 41.213957 -227.503056) (xy 41.327705 -227.487423)
			(xy 41.442254 -227.479588) (xy 41.557072 -227.479588) (xy 41.671621 -227.487423) (xy 41.785369 -227.503056)
			(xy 41.897785 -227.526415) (xy 42.008345 -227.557391) (xy 42.116533 -227.595839) (xy 42.221845 -227.641581)
			(xy 42.323791 -227.694402) (xy 42.421895 -227.754056) (xy 42.515699 -227.820266) (xy 42.604766 -227.892723)
			(xy 42.688681 -227.971089) (xy 42.767054 -228.054998) (xy 42.839517 -228.14406) (xy 42.905734 -228.237859)
			(xy 42.965396 -228.335958) (xy 43.018225 -228.4379) (xy 43.063974 -228.543209) (xy 43.10243 -228.651394)
			(xy 43.133415 -228.761952) (xy 43.156782 -228.874366) (xy 43.172424 -228.988113) (xy 43.180268 -229.102661)
			(xy 43.180762 -229.16007) (xy 43.180576 -229.193253) (xy 43.177909 -229.259567) (xy 43.175428 -229.292658)
			(xy 43.170272 -229.350942) (xy 43.152948 -229.466671) (xy 43.127616 -229.580914) (xy 43.094401 -229.693119)
			(xy 43.053462 -229.802742) (xy 43.004999 -229.909253) (xy 42.949245 -230.012135) (xy 42.886471 -230.110891)
			(xy 42.816981 -230.205042) (xy 42.741111 -230.294132) (xy 42.659229 -230.377729) (xy 42.571732 -230.45543)
			(xy 42.500813 -230.51008) (xy 93.154506 -230.51008) (xy 93.158522 -230.39381) (xy 93.170549 -230.278095)
			(xy 93.190531 -230.163485) (xy 93.218373 -230.050526) (xy 93.253942 -229.939758) (xy 93.297068 -229.831707)
			(xy 93.347545 -229.726889) (xy 93.405134 -229.625804) (xy 93.46956 -229.528932) (xy 93.540515 -229.436736)
			(xy 93.617662 -229.349655) (xy 93.700633 -229.268104) (xy 93.789033 -229.192472) (xy 93.88244 -229.123118)
			(xy 93.980409 -229.060375) (xy 94.082473 -229.004539) (xy 94.188147 -228.955878) (xy 94.296926 -228.914624)
			(xy 94.408291 -228.880973) (xy 94.521714 -228.855085) (xy 94.636651 -228.837084) (xy 94.752557 -228.827055)
			(xy 94.868879 -228.825047) (xy 94.985062 -228.831069) (xy 95.100553 -228.845092) (xy 95.214801 -228.86705)
			(xy 95.327262 -228.896837) (xy 95.4374 -228.934312) (xy 95.54469 -228.979297) (xy 95.648621 -229.031576)
			(xy 95.748697 -229.090901) (xy 95.844443 -229.156989) (xy 95.9354 -229.229525) (xy 96.021136 -229.308164)
			(xy 96.101243 -229.39253) (xy 96.175339 -229.482222) (xy 96.243069 -229.576812) (xy 96.304113 -229.67585)
			(xy 96.358178 -229.778863) (xy 96.405008 -229.88536) (xy 96.444379 -229.994835) (xy 96.476103 -230.106765)
			(xy 96.500029 -230.220617) (xy 96.516043 -230.335849) (xy 96.52407 -230.451911) (xy 96.524572 -230.51008)
			(xy 96.52407 -230.568249) (xy 96.516043 -230.684311) (xy 96.500029 -230.799543) (xy 96.476103 -230.913395)
			(xy 96.444379 -231.025325) (xy 96.405008 -231.1348) (xy 96.358178 -231.241297) (xy 96.304113 -231.34431)
			(xy 96.243069 -231.443348) (xy 96.175339 -231.537938) (xy 96.101243 -231.62763) (xy 96.021136 -231.711996)
			(xy 95.9354 -231.790635) (xy 95.844443 -231.863171) (xy 95.748697 -231.929259) (xy 95.648621 -231.988584)
			(xy 95.54469 -232.040863) (xy 95.4374 -232.085848) (xy 95.327262 -232.123323) (xy 95.214801 -232.15311)
			(xy 95.100553 -232.175068) (xy 94.985062 -232.189091) (xy 94.868879 -232.195113) (xy 94.752557 -232.193105)
			(xy 94.636651 -232.183076) (xy 94.521714 -232.165075) (xy 94.408291 -232.139187) (xy 94.296926 -232.105536)
			(xy 94.188147 -232.064282) (xy 94.082473 -232.015621) (xy 93.980409 -231.959785) (xy 93.88244 -231.897042)
			(xy 93.789033 -231.827688) (xy 93.700633 -231.752056) (xy 93.617662 -231.670505) (xy 93.540515 -231.583424)
			(xy 93.46956 -231.491228) (xy 93.405134 -231.394356) (xy 93.347545 -231.293271) (xy 93.297068 -231.188453)
			(xy 93.253942 -231.080402) (xy 93.218373 -230.969634) (xy 93.190531 -230.856675) (xy 93.170549 -230.742065)
			(xy 93.158522 -230.62635) (xy 93.154506 -230.51008) (xy 42.500813 -230.51008) (xy 42.479042 -230.526857)
			(xy 42.381609 -230.591665) (xy 42.279905 -230.64954) (xy 42.174422 -230.700202) (xy 42.065671 -230.743404)
			(xy 41.954179 -230.778939) (xy 41.840485 -230.806634) (xy 41.725141 -230.826354) (xy 41.608704 -230.838005)
			(xy 41.491739 -230.84153) (xy 41.374812 -230.836912) (xy 41.258489 -230.824173) (xy 41.143334 -230.803375)
			(xy 41.029905 -230.774618) (xy 40.91875 -230.738042) (xy 40.810407 -230.693825) (xy 40.705403 -230.642179)
			(xy 40.604244 -230.583356) (xy 40.507421 -230.51764) (xy 40.415403 -230.445349) (xy 40.328636 -230.366834)
			(xy 40.247539 -230.282474) (xy 40.172506 -230.192679) (xy 40.103899 -230.097883) (xy 40.042051 -229.998544)
			(xy 39.987262 -229.895145) (xy 39.939796 -229.788186) (xy 39.899884 -229.678185) (xy 39.86772 -229.565674)
			(xy 39.843457 -229.451199) (xy 39.827215 -229.335313) (xy 39.819072 -229.218579) (xy 39.818564 -229.16007)
			(xy 0.509016 -229.16007) (xy 0.509016 -242.26012) (xy 86.877404 -242.26012) (xy 86.881424 -242.069469)
			(xy 86.893478 -241.879156) (xy 86.913544 -241.689521) (xy 86.941587 -241.5009) (xy 86.977556 -241.31363)
			(xy 87.021388 -241.128042) (xy 87.073005 -240.944467) (xy 87.132315 -240.763231) (xy 87.199213 -240.584656)
			(xy 87.273579 -240.409061) (xy 87.355281 -240.236756) (xy 87.444175 -240.068049) (xy 87.540101 -239.903239)
			(xy 87.64289 -239.74262) (xy 87.752359 -239.586477) (xy 87.868313 -239.435088) (xy 87.990547 -239.288721)
			(xy 88.118841 -239.147637) (xy 88.252969 -239.012088) (xy 88.392693 -238.882313) (xy 88.537763 -238.758543)
			(xy 88.687921 -238.641) (xy 88.842902 -238.529891) (xy 89.002429 -238.425414) (xy 89.166218 -238.327755)
			(xy 89.333978 -238.237088) (xy 89.505412 -238.153574) (xy 89.680214 -238.077361) (xy 89.858073 -238.008585)
			(xy 90.038674 -237.947367) (xy 90.221694 -237.893818) (xy 90.40681 -237.848032) (xy 90.593691 -237.81009)
			(xy 90.782006 -237.780061) (xy 90.971419 -237.757996) (xy 91.161593 -237.743937) (xy 91.352192 -237.737907)
			(xy 91.542875 -237.739917) (xy 91.733304 -237.749964) (xy 91.92314 -237.76803) (xy 92.112046 -237.794083)
			(xy 92.299685 -237.828076) (xy 92.485725 -237.869949) (xy 92.669834 -237.919628) (xy 92.851685 -237.977024)
			(xy 93.030955 -238.042035) (xy 93.207325 -238.114546) (xy 93.380481 -238.194427) (xy 93.550116 -238.281537)
			(xy 93.715928 -238.375721) (xy 93.877622 -238.476812) (xy 94.03491 -238.584628) (xy 94.187513 -238.69898)
			(xy 94.335161 -238.819663) (xy 94.477589 -238.946464) (xy 94.614545 -239.079155) (xy 94.745786 -239.217503)
			(xy 94.871078 -239.36126) (xy 94.990198 -239.510171) (xy 95.102934 -239.663972) (xy 95.209087 -239.822388)
			(xy 95.308467 -239.985139) (xy 95.400897 -240.151934) (xy 95.486214 -240.322478) (xy 95.564266 -240.496466)
			(xy 95.634913 -240.673591) (xy 95.698031 -240.853536) (xy 95.753507 -241.035982) (xy 95.801242 -241.220605)
			(xy 95.841152 -241.407075) (xy 95.873165 -241.595063) (xy 95.897225 -241.784233) (xy 95.913288 -241.974249)
			(xy 95.921327 -242.164773) (xy 95.92183 -242.26012) (xy 95.921327 -242.355467) (xy 95.913288 -242.545991)
			(xy 95.897225 -242.736007) (xy 95.873165 -242.925177) (xy 95.841152 -243.113165) (xy 95.801242 -243.299635)
			(xy 95.753507 -243.484258) (xy 95.698031 -243.666704) (xy 95.634913 -243.846649) (xy 95.564266 -244.023774)
			(xy 95.486214 -244.197762) (xy 95.400897 -244.368306) (xy 95.308467 -244.535101) (xy 95.209087 -244.697852)
			(xy 95.102934 -244.856268) (xy 94.990198 -245.010069) (xy 94.871078 -245.15898) (xy 94.745786 -245.302737)
			(xy 94.614545 -245.441085) (xy 94.477589 -245.573776) (xy 94.335161 -245.700577) (xy 94.187513 -245.82126)
			(xy 94.03491 -245.935612) (xy 93.877622 -246.043428) (xy 93.715928 -246.144519) (xy 93.550116 -246.238703)
			(xy 93.380481 -246.325813) (xy 93.207325 -246.405694) (xy 93.030955 -246.478205) (xy 92.851685 -246.543216)
			(xy 92.669834 -246.600612) (xy 92.485725 -246.650291) (xy 92.299685 -246.692164) (xy 92.112046 -246.726157)
			(xy 91.92314 -246.75221) (xy 91.733304 -246.770276) (xy 91.542875 -246.780323) (xy 91.352192 -246.782333)
			(xy 91.161593 -246.776303) (xy 90.971419 -246.762244) (xy 90.782006 -246.740179) (xy 90.593691 -246.71015)
			(xy 90.40681 -246.672208) (xy 90.221694 -246.626422) (xy 90.038674 -246.572873) (xy 89.858073 -246.511655)
			(xy 89.680214 -246.442879) (xy 89.505412 -246.366666) (xy 89.333978 -246.283152) (xy 89.166218 -246.192485)
			(xy 89.002429 -246.094826) (xy 88.842902 -245.990349) (xy 88.687921 -245.87924) (xy 88.537763 -245.761697)
			(xy 88.392693 -245.637927) (xy 88.252969 -245.508152) (xy 88.118841 -245.372603) (xy 87.990547 -245.231519)
			(xy 87.868313 -245.085152) (xy 87.752359 -244.933763) (xy 87.64289 -244.77762) (xy 87.540101 -244.617001)
			(xy 87.444175 -244.452191) (xy 87.355281 -244.283484) (xy 87.273579 -244.111179) (xy 87.199213 -243.935584)
			(xy 87.132315 -243.757009) (xy 87.073005 -243.575773) (xy 87.021388 -243.392198) (xy 86.977556 -243.20661)
			(xy 86.941587 -243.01934) (xy 86.913544 -242.830719) (xy 86.893478 -242.641084) (xy 86.881424 -242.450771)
			(xy 86.877404 -242.26012) (xy 0.509016 -242.26012) (xy 0.509016 -250.020582) (xy 3.582162 -250.020582)
			(xy 3.582653 -249.963338) (xy 3.590754 -249.849137) (xy 3.606915 -249.735795) (xy 3.631055 -249.623881)
			(xy 3.663052 -249.513955) (xy 3.702747 -249.406568) (xy 3.74994 -249.302259) (xy 3.804394 -249.20155)
			(xy 3.865837 -249.104947) (xy 3.933962 -249.012932) (xy 4.008425 -248.925969) (xy 4.088855 -248.844491)
			(xy 4.174848 -248.768908) (xy 4.265973 -248.699599) (xy 4.361773 -248.636911) (xy 4.461769 -248.581157)
			(xy 4.565458 -248.532619) (xy 4.672322 -248.491538) (xy 4.781825 -248.458121) (xy 4.893417 -248.432535)
			(xy 5.006541 -248.414908) (xy 5.120627 -248.405329) (xy 5.235106 -248.403846) (xy 5.349402 -248.410467)
			(xy 5.462944 -248.425157) (xy 5.575162 -248.447844) (xy 5.685494 -248.478413) (xy 5.793386 -248.516712)
			(xy 5.898298 -248.562549) (xy 5.999704 -248.615693) (xy 6.097096 -248.675879) (xy 6.189986 -248.742805)
			(xy 6.277908 -248.816135) (xy 6.360421 -248.895501) (xy 6.437112 -248.980507) (xy 6.507597 -249.070726)
			(xy 6.571522 -249.165706) (xy 6.628567 -249.26497) (xy 6.678446 -249.368022) (xy 6.720909 -249.474344)
			(xy 6.755743 -249.583404) (xy 6.782773 -249.694656) (xy 6.801865 -249.807541) (xy 6.812922 -249.921494)
			(xy 6.815888 -250.035944) (xy 6.81075 -250.150316) (xy 6.797533 -250.264039) (xy 6.776303 -250.376542)
			(xy 6.747166 -250.48726) (xy 6.710269 -250.59564) (xy 6.665797 -250.701137) (xy 6.613971 -250.803224)
			(xy 6.555053 -250.901388) (xy 6.489337 -250.995137) (xy 6.453632 -251.039884) (xy 6.059424 -251.039884)
			(xy 6.020367 -251.072253) (xy 5.938107 -251.131626) (xy 5.895086 -251.158502) (xy 5.881509 -251.167452)
			(xy 5.858992 -251.190897) (xy 5.843109 -251.219259) (xy 5.834884 -251.250707) (xy 5.83438 -251.26696)
			(xy 5.83438 -251.50699) (xy 5.834126 -251.50699) (xy 5.779452 -251.529781) (xy 5.667407 -251.568246)
			(xy 5.552848 -251.598407) (xy 5.436387 -251.620101) (xy 5.318652 -251.633212) (xy 5.200272 -251.637669)
			(xy 5.081884 -251.633449) (xy 4.964122 -251.620575) (xy 4.847619 -251.599114) (xy 4.732999 -251.569183)
			(xy 4.620877 -251.530943) (xy 4.566158 -251.50826) (xy 4.565904 -251.50826) (xy 4.565904 -251.26823)
			(xy 4.56544 -251.25195) (xy 4.557181 -251.220454) (xy 4.541219 -251.192074) (xy 4.518594 -251.168658)
			(xy 4.504944 -251.159772) (xy 4.45885 -251.131059) (xy 4.370982 -251.067228) (xy 4.32943 -251.032264)
			(xy 3.937762 -251.032264) (xy 3.903919 -250.989342) (xy 3.841441 -250.89964) (xy 3.785164 -250.805923)
			(xy 3.735346 -250.708619) (xy 3.692214 -250.608172) (xy 3.655964 -250.505042) (xy 3.626762 -250.399698)
			(xy 3.604742 -250.292623) (xy 3.590005 -250.184306) (xy 3.582617 -250.07524) (xy 3.582162 -250.020582)
			(xy 0.509016 -250.020582) (xy 0.509016 -267.850739) (xy 3.584556 -267.850739) (xy 3.589879 -267.737285)
			(xy 3.603163 -267.624485) (xy 3.624341 -267.512897) (xy 3.653308 -267.403074) (xy 3.689922 -267.295558)
			(xy 3.734001 -267.190881) (xy 3.785327 -267.08956) (xy 3.843647 -266.992097) (xy 3.908672 -266.898974)
			(xy 3.980081 -266.81065) (xy 4.05752 -266.727563) (xy 4.140607 -266.650124) (xy 4.228931 -266.578715)
			(xy 4.322054 -266.51369) (xy 4.419517 -266.455369) (xy 4.520837 -266.404043) (xy 4.625514 -266.359963)
			(xy 4.73303 -266.323349) (xy 4.842854 -266.294382) (xy 4.954441 -266.273204) (xy 5.067241 -266.25992)
			(xy 5.180695 -266.254596) (xy 5.294243 -266.257258) (xy 5.407324 -266.267894) (xy 5.519377 -266.28645)
			(xy 5.629849 -266.312835) (xy 5.738194 -266.346919) (xy 5.843876 -266.388532) (xy 5.946371 -266.437469)
			(xy 6.045175 -266.493488) (xy 6.139797 -266.556312) (xy 6.229771 -266.625631) (xy 6.31465 -266.701101)
			(xy 6.394016 -266.78235) (xy 6.467475 -266.868975) (xy 6.534666 -266.960549) (xy 6.595255 -267.056618)
			(xy 6.648942 -267.156707) (xy 6.695463 -267.260322) (xy 6.734588 -267.36695) (xy 6.766122 -267.476064)
			(xy 6.78991 -267.587124) (xy 6.805834 -267.699582) (xy 6.813816 -267.81288) (xy 6.814312 -267.86967)
			(xy 6.813806 -267.92732) (xy 6.805599 -268.042327) (xy 6.789208 -268.156456) (xy 6.764716 -268.269125)
			(xy 6.73225 -268.37976) (xy 6.691973 -268.487796) (xy 6.644093 -268.592684) (xy 6.588851 -268.693889)
			(xy 6.52653 -268.790895) (xy 6.457448 -268.883208) (xy 6.381956 -268.970358) (xy 6.30044 -269.0519)
			(xy 6.213314 -269.127419) (xy 6.121023 -269.196531) (xy 6.024036 -269.258882) (xy 5.922848 -269.314155)
			(xy 5.817976 -269.362069) (xy 5.709952 -269.402379) (xy 5.599327 -269.434881) (xy 5.486666 -269.459407)
			(xy 5.372543 -269.475834) (xy 5.257538 -269.484078) (xy 5.199888 -269.484602) (xy 5.199634 -269.484602)
			(xy 5.199634 -269.484348) (xy 5.142844 -269.483856) (xy 5.029546 -269.475875) (xy 4.917088 -269.459951)
			(xy 4.806028 -269.436163) (xy 4.696914 -269.404629) (xy 4.590286 -269.365505) (xy 4.486671 -269.318984)
			(xy 4.386581 -269.265297) (xy 4.290512 -269.204708) (xy 4.198938 -269.137518) (xy 4.112313 -269.064058)
			(xy 4.031064 -268.984693) (xy 3.955594 -268.899814) (xy 3.886275 -268.80984) (xy 3.82345 -268.715218)
			(xy 3.767431 -268.616415) (xy 3.718493 -268.513919) (xy 3.67688 -268.408238) (xy 3.642796 -268.299893)
			(xy 3.616411 -268.189421) (xy 3.597855 -268.077368) (xy 3.587219 -267.964287) (xy 3.584556 -267.850739)
			(xy 0.509016 -267.850739) (xy 0.509016 -273.61007) (xy 39.818564 -273.61007) (xy 39.819058 -273.552661)
			(xy 39.826902 -273.438113) (xy 39.842544 -273.324366) (xy 39.865911 -273.211952) (xy 39.896896 -273.101394)
			(xy 39.935352 -272.993209) (xy 39.981101 -272.8879) (xy 40.03393 -272.785958) (xy 40.093592 -272.687859)
			(xy 40.159809 -272.59406) (xy 40.232272 -272.504998) (xy 40.310645 -272.421089) (xy 40.39456 -272.342723)
			(xy 40.483627 -272.270266) (xy 40.577431 -272.204056) (xy 40.675535 -272.144402) (xy 40.777481 -272.091581)
			(xy 40.882793 -272.045839) (xy 40.990981 -272.007391) (xy 41.101541 -271.976415) (xy 41.213957 -271.953056)
			(xy 41.327705 -271.937423) (xy 41.442254 -271.929588) (xy 41.557072 -271.929588) (xy 41.671621 -271.937423)
			(xy 41.785369 -271.953056) (xy 41.897785 -271.976415) (xy 42.008345 -272.007391) (xy 42.116533 -272.045839)
			(xy 42.221845 -272.091581) (xy 42.323791 -272.144402) (xy 42.421895 -272.204056) (xy 42.515699 -272.270266)
			(xy 42.604766 -272.342723) (xy 42.688681 -272.421089) (xy 42.767054 -272.504998) (xy 42.839517 -272.59406)
			(xy 42.905734 -272.687859) (xy 42.965396 -272.785958) (xy 43.018225 -272.8879) (xy 43.063974 -272.993209)
			(xy 43.10243 -273.101394) (xy 43.133415 -273.211952) (xy 43.156782 -273.324366) (xy 43.172424 -273.438113)
			(xy 43.180268 -273.552661) (xy 43.180762 -273.61007) (xy 43.180576 -273.643253) (xy 43.177909 -273.709567)
			(xy 43.175428 -273.742658) (xy 43.170272 -273.800942) (xy 43.152948 -273.916671) (xy 43.127616 -274.030914)
			(xy 43.094401 -274.143119) (xy 43.053462 -274.252742) (xy 43.004999 -274.359253) (xy 42.949245 -274.462135)
			(xy 42.886471 -274.560891) (xy 42.816981 -274.655042) (xy 42.741111 -274.744132) (xy 42.659229 -274.827729)
			(xy 42.571732 -274.90543) (xy 42.500813 -274.96008) (xy 93.154506 -274.96008) (xy 93.158522 -274.84381)
			(xy 93.170549 -274.728095) (xy 93.190531 -274.613485) (xy 93.218373 -274.500526) (xy 93.253942 -274.389758)
			(xy 93.297068 -274.281707) (xy 93.347545 -274.176889) (xy 93.405134 -274.075804) (xy 93.46956 -273.978932)
			(xy 93.540515 -273.886736) (xy 93.617662 -273.799655) (xy 93.700633 -273.718104) (xy 93.789033 -273.642472)
			(xy 93.88244 -273.573118) (xy 93.980409 -273.510375) (xy 94.082473 -273.454539) (xy 94.188147 -273.405878)
			(xy 94.296926 -273.364624) (xy 94.408291 -273.330973) (xy 94.521714 -273.305085) (xy 94.636651 -273.287084)
			(xy 94.752557 -273.277055) (xy 94.868879 -273.275047) (xy 94.985062 -273.281069) (xy 95.100553 -273.295092)
			(xy 95.214801 -273.31705) (xy 95.327262 -273.346837) (xy 95.4374 -273.384312) (xy 95.54469 -273.429297)
			(xy 95.648621 -273.481576) (xy 95.748697 -273.540901) (xy 95.844443 -273.606989) (xy 95.9354 -273.679525)
			(xy 96.021136 -273.758164) (xy 96.101243 -273.84253) (xy 96.175339 -273.932222) (xy 96.243069 -274.026812)
			(xy 96.304113 -274.12585) (xy 96.358178 -274.228863) (xy 96.405008 -274.33536) (xy 96.444379 -274.444835)
			(xy 96.476103 -274.556765) (xy 96.500029 -274.670617) (xy 96.516043 -274.785849) (xy 96.52407 -274.901911)
			(xy 96.524572 -274.96008) (xy 96.52407 -275.018249) (xy 96.516043 -275.134311) (xy 96.500029 -275.249543)
			(xy 96.476103 -275.363395) (xy 96.444379 -275.475325) (xy 96.405008 -275.5848) (xy 96.358178 -275.691297)
			(xy 96.304113 -275.79431) (xy 96.243069 -275.893348) (xy 96.175339 -275.987938) (xy 96.101243 -276.07763)
			(xy 96.021136 -276.161996) (xy 95.9354 -276.240635) (xy 95.844443 -276.313171) (xy 95.748697 -276.379259)
			(xy 95.648621 -276.438584) (xy 95.54469 -276.490863) (xy 95.4374 -276.535848) (xy 95.327262 -276.573323)
			(xy 95.214801 -276.60311) (xy 95.100553 -276.625068) (xy 94.985062 -276.639091) (xy 94.868879 -276.645113)
			(xy 94.752557 -276.643105) (xy 94.636651 -276.633076) (xy 94.521714 -276.615075) (xy 94.408291 -276.589187)
			(xy 94.296926 -276.555536) (xy 94.188147 -276.514282) (xy 94.082473 -276.465621) (xy 93.980409 -276.409785)
			(xy 93.88244 -276.347042) (xy 93.789033 -276.277688) (xy 93.700633 -276.202056) (xy 93.617662 -276.120505)
			(xy 93.540515 -276.033424) (xy 93.46956 -275.941228) (xy 93.405134 -275.844356) (xy 93.347545 -275.743271)
			(xy 93.297068 -275.638453) (xy 93.253942 -275.530402) (xy 93.218373 -275.419634) (xy 93.190531 -275.306675)
			(xy 93.170549 -275.192065) (xy 93.158522 -275.07635) (xy 93.154506 -274.96008) (xy 42.500813 -274.96008)
			(xy 42.479042 -274.976857) (xy 42.381609 -275.041665) (xy 42.279905 -275.09954) (xy 42.174422 -275.150202)
			(xy 42.065671 -275.193404) (xy 41.954179 -275.228939) (xy 41.840485 -275.256634) (xy 41.725141 -275.276354)
			(xy 41.608704 -275.288005) (xy 41.491739 -275.29153) (xy 41.374812 -275.286912) (xy 41.258489 -275.274173)
			(xy 41.143334 -275.253375) (xy 41.029905 -275.224618) (xy 40.91875 -275.188042) (xy 40.810407 -275.143825)
			(xy 40.705403 -275.092179) (xy 40.604244 -275.033356) (xy 40.507421 -274.96764) (xy 40.415403 -274.895349)
			(xy 40.328636 -274.816834) (xy 40.247539 -274.732474) (xy 40.172506 -274.642679) (xy 40.103899 -274.547883)
			(xy 40.042051 -274.448544) (xy 39.987262 -274.345145) (xy 39.939796 -274.238186) (xy 39.899884 -274.128185)
			(xy 39.86772 -274.015674) (xy 39.843457 -273.901199) (xy 39.827215 -273.785313) (xy 39.819072 -273.668579)
			(xy 39.818564 -273.61007) (xy 0.509016 -273.61007) (xy 0.509016 -286.709866) (xy 86.877404 -286.709866)
			(xy 86.881424 -286.519215) (xy 86.893478 -286.328902) (xy 86.913544 -286.139267) (xy 86.941587 -285.950646)
			(xy 86.977556 -285.763376) (xy 87.021388 -285.577788) (xy 87.073005 -285.394213) (xy 87.132315 -285.212977)
			(xy 87.199213 -285.034402) (xy 87.273579 -284.858807) (xy 87.355281 -284.686502) (xy 87.444175 -284.517795)
			(xy 87.540101 -284.352985) (xy 87.64289 -284.192366) (xy 87.752359 -284.036223) (xy 87.868313 -283.884834)
			(xy 87.990547 -283.738467) (xy 88.118841 -283.597383) (xy 88.252969 -283.461834) (xy 88.392693 -283.332059)
			(xy 88.537763 -283.208289) (xy 88.687921 -283.090746) (xy 88.842902 -282.979637) (xy 89.002429 -282.87516)
			(xy 89.166218 -282.777501) (xy 89.333978 -282.686834) (xy 89.505412 -282.60332) (xy 89.680214 -282.527107)
			(xy 89.858073 -282.458331) (xy 90.038674 -282.397113) (xy 90.221694 -282.343564) (xy 90.40681 -282.297778)
			(xy 90.593691 -282.259836) (xy 90.782006 -282.229807) (xy 90.971419 -282.207742) (xy 91.161593 -282.193683)
			(xy 91.352192 -282.187653) (xy 91.542875 -282.189663) (xy 91.733304 -282.19971) (xy 91.92314 -282.217776)
			(xy 92.112046 -282.243829) (xy 92.299685 -282.277822) (xy 92.485725 -282.319695) (xy 92.669834 -282.369374)
			(xy 92.851685 -282.42677) (xy 93.030955 -282.491781) (xy 93.207325 -282.564292) (xy 93.380481 -282.644173)
			(xy 93.550116 -282.731283) (xy 93.715928 -282.825467) (xy 93.877622 -282.926558) (xy 94.03491 -283.034374)
			(xy 94.187513 -283.148726) (xy 94.335161 -283.269409) (xy 94.477589 -283.39621) (xy 94.614545 -283.528901)
			(xy 94.745786 -283.667249) (xy 94.871078 -283.811006) (xy 94.990198 -283.959917) (xy 95.102934 -284.113718)
			(xy 95.209087 -284.272134) (xy 95.308467 -284.434885) (xy 95.400897 -284.60168) (xy 95.486214 -284.772224)
			(xy 95.564266 -284.946212) (xy 95.634913 -285.123337) (xy 95.698031 -285.303282) (xy 95.753507 -285.485728)
			(xy 95.801242 -285.670351) (xy 95.841152 -285.856821) (xy 95.873165 -286.044809) (xy 95.897225 -286.233979)
			(xy 95.913288 -286.423995) (xy 95.921327 -286.614519) (xy 95.92183 -286.709866) (xy 95.921327 -286.805213)
			(xy 95.913288 -286.995737) (xy 95.897225 -287.185753) (xy 95.873165 -287.374923) (xy 95.841152 -287.562911)
			(xy 95.801242 -287.749381) (xy 95.753507 -287.934004) (xy 95.698031 -288.11645) (xy 95.634913 -288.296395)
			(xy 95.564266 -288.47352) (xy 95.486214 -288.647508) (xy 95.400897 -288.818052) (xy 95.308467 -288.984847)
			(xy 95.209087 -289.147598) (xy 95.102934 -289.306014) (xy 94.990198 -289.459815) (xy 94.871078 -289.608726)
			(xy 94.745786 -289.752483) (xy 94.614545 -289.890831) (xy 94.477589 -290.023522) (xy 94.335161 -290.150323)
			(xy 94.187513 -290.271006) (xy 94.03491 -290.385358) (xy 93.877622 -290.493174) (xy 93.715928 -290.594265)
			(xy 93.550116 -290.688449) (xy 93.380481 -290.775559) (xy 93.207325 -290.85544) (xy 93.030955 -290.927951)
			(xy 92.851685 -290.992962) (xy 92.669834 -291.050358) (xy 92.485725 -291.100037) (xy 92.299685 -291.14191)
			(xy 92.112046 -291.175903) (xy 91.92314 -291.201956) (xy 91.733304 -291.220022) (xy 91.542875 -291.230069)
			(xy 91.352192 -291.232079) (xy 91.161593 -291.226049) (xy 90.971419 -291.21199) (xy 90.782006 -291.189925)
			(xy 90.593691 -291.159896) (xy 90.40681 -291.121954) (xy 90.221694 -291.076168) (xy 90.038674 -291.022619)
			(xy 89.858073 -290.961401) (xy 89.680214 -290.892625) (xy 89.505412 -290.816412) (xy 89.333978 -290.732898)
			(xy 89.166218 -290.642231) (xy 89.002429 -290.544572) (xy 88.842902 -290.440095) (xy 88.687921 -290.328986)
			(xy 88.537763 -290.211443) (xy 88.392693 -290.087673) (xy 88.252969 -289.957898) (xy 88.118841 -289.822349)
			(xy 87.990547 -289.681265) (xy 87.868313 -289.534898) (xy 87.752359 -289.383509) (xy 87.64289 -289.227366)
			(xy 87.540101 -289.066747) (xy 87.444175 -288.901937) (xy 87.355281 -288.73323) (xy 87.273579 -288.560925)
			(xy 87.199213 -288.38533) (xy 87.132315 -288.206755) (xy 87.073005 -288.025519) (xy 87.021388 -287.841944)
			(xy 86.977556 -287.656356) (xy 86.941587 -287.469086) (xy 86.913544 -287.280465) (xy 86.893478 -287.09083)
			(xy 86.881424 -286.900517) (xy 86.877404 -286.709866) (xy 0.509016 -286.709866) (xy 0.509016 -295.89984)
			(xy 14.086591 -295.89984) (xy 14.090616 -295.757648) (xy 14.102679 -295.615912) (xy 14.122742 -295.475086)
			(xy 14.15074 -295.33562) (xy 14.186584 -295.197961) (xy 14.230158 -295.062551) (xy 14.281323 -294.929823)
			(xy 14.339916 -294.800202) (xy 14.405747 -294.674104) (xy 14.478608 -294.551932) (xy 14.558263 -294.434078)
			(xy 14.644459 -294.320919) (xy 14.736918 -294.212817) (xy 14.835346 -294.11012) (xy 14.939425 -294.013156)
			(xy 15.048824 -293.922236) (xy 15.163192 -293.83765) (xy 15.282161 -293.75967) (xy 15.405352 -293.688546)
			(xy 15.532369 -293.624505) (xy 15.662806 -293.567753) (xy 15.796245 -293.518471) (xy 15.932258 -293.476817)
			(xy 16.07041 -293.442925) (xy 16.210259 -293.416904) (xy 16.351355 -293.398836) (xy 16.493247 -293.388779)
			(xy 16.635482 -293.386766) (xy 16.777602 -293.392803) (xy 16.919153 -293.406871) (xy 17.059682 -293.428925)
			(xy 17.198737 -293.458894) (xy 17.335875 -293.496682) (xy 17.470655 -293.542168) (xy 17.602646 -293.595206)
			(xy 17.731425 -293.655627) (xy 17.856579 -293.723236) (xy 17.977707 -293.797818) (xy 18.094423 -293.879134)
			(xy 18.206351 -293.966922) (xy 18.313133 -294.060902) (xy 18.414427 -294.160772) (xy 18.509908 -294.266214)
			(xy 18.599272 -294.376888) (xy 18.68223 -294.492441) (xy 18.758519 -294.612502) (xy 18.827893 -294.736687)
			(xy 18.89013 -294.864598) (xy 18.945031 -294.995825) (xy 18.992419 -295.129948) (xy 19.032144 -295.266537)
			(xy 19.064077 -295.405155) (xy 19.088118 -295.545357) (xy 19.104187 -295.686695) (xy 19.112235 -295.828716)
			(xy 19.112738 -295.89984) (xy 19.112235 -295.970964) (xy 19.104187 -296.112985) (xy 19.088118 -296.254323)
			(xy 19.064077 -296.394525) (xy 19.032144 -296.533143) (xy 18.992419 -296.669732) (xy 18.945031 -296.803855)
			(xy 18.89013 -296.935082) (xy 18.827893 -297.062993) (xy 18.758519 -297.187178) (xy 18.68223 -297.307239)
			(xy 18.599272 -297.422792) (xy 18.509908 -297.533466) (xy 18.414427 -297.638908) (xy 18.313133 -297.738778)
			(xy 18.206351 -297.832758) (xy 18.094423 -297.920546) (xy 17.977707 -298.001862) (xy 17.856579 -298.076444)
			(xy 17.731425 -298.144053) (xy 17.602646 -298.204474) (xy 17.470655 -298.257512) (xy 17.335875 -298.302998)
			(xy 17.198737 -298.340786) (xy 17.059682 -298.370755) (xy 16.919153 -298.392809) (xy 16.777602 -298.406877)
			(xy 16.635482 -298.412914) (xy 16.493247 -298.410901) (xy 16.351355 -298.400844) (xy 16.210259 -298.382776)
			(xy 16.07041 -298.356755) (xy 15.932258 -298.322863) (xy 15.796245 -298.281209) (xy 15.662806 -298.231927)
			(xy 15.532369 -298.175175) (xy 15.405352 -298.111134) (xy 15.282161 -298.04001) (xy 15.163192 -297.96203)
			(xy 15.048824 -297.877444) (xy 14.939425 -297.786524) (xy 14.835346 -297.68956) (xy 14.736918 -297.586863)
			(xy 14.644459 -297.478761) (xy 14.558263 -297.365602) (xy 14.478608 -297.247748) (xy 14.405747 -297.125576)
			(xy 14.339916 -296.999478) (xy 14.281323 -296.869857) (xy 14.230158 -296.737129) (xy 14.186584 -296.601719)
			(xy 14.15074 -296.46406) (xy 14.122742 -296.324594) (xy 14.102679 -296.183768) (xy 14.090616 -296.042032)
			(xy 14.086591 -295.89984) (xy 0.509016 -295.89984) (xy 0.509016 -318.06007) (xy 39.818564 -318.06007)
			(xy 39.819058 -318.002661) (xy 39.826902 -317.888113) (xy 39.842544 -317.774366) (xy 39.865911 -317.661952)
			(xy 39.896896 -317.551394) (xy 39.935352 -317.443209) (xy 39.981101 -317.3379) (xy 40.03393 -317.235958)
			(xy 40.093592 -317.137859) (xy 40.159809 -317.04406) (xy 40.232272 -316.954998) (xy 40.310645 -316.871089)
			(xy 40.39456 -316.792723) (xy 40.483627 -316.720266) (xy 40.577431 -316.654056) (xy 40.675535 -316.594402)
			(xy 40.777481 -316.541581) (xy 40.882793 -316.495839) (xy 40.990981 -316.457391) (xy 41.101541 -316.426415)
			(xy 41.213957 -316.403056) (xy 41.327705 -316.387423) (xy 41.442254 -316.379588) (xy 41.557072 -316.379588)
			(xy 41.671621 -316.387423) (xy 41.785369 -316.403056) (xy 41.897785 -316.426415) (xy 42.008345 -316.457391)
			(xy 42.116533 -316.495839) (xy 42.221845 -316.541581) (xy 42.323791 -316.594402) (xy 42.421895 -316.654056)
			(xy 42.515699 -316.720266) (xy 42.604766 -316.792723) (xy 42.688681 -316.871089) (xy 42.767054 -316.954998)
			(xy 42.839517 -317.04406) (xy 42.905734 -317.137859) (xy 42.965396 -317.235958) (xy 43.018225 -317.3379)
			(xy 43.063974 -317.443209) (xy 43.10243 -317.551394) (xy 43.133415 -317.661952) (xy 43.156782 -317.774366)
			(xy 43.172424 -317.888113) (xy 43.180268 -318.002661) (xy 43.180762 -318.06007) (xy 43.180576 -318.093253)
			(xy 43.177909 -318.159567) (xy 43.175428 -318.192658) (xy 43.170272 -318.250942) (xy 43.152948 -318.366671)
			(xy 43.127616 -318.480914) (xy 43.094401 -318.593119) (xy 43.053462 -318.702742) (xy 43.004999 -318.809253)
			(xy 42.949245 -318.912135) (xy 42.886471 -319.010891) (xy 42.816981 -319.105042) (xy 42.741111 -319.194132)
			(xy 42.659229 -319.277729) (xy 42.571732 -319.35543) (xy 42.500813 -319.41008) (xy 93.154506 -319.41008)
			(xy 93.158522 -319.29381) (xy 93.170549 -319.178095) (xy 93.190531 -319.063485) (xy 93.218373 -318.950526)
			(xy 93.253942 -318.839758) (xy 93.297068 -318.731707) (xy 93.347545 -318.626889) (xy 93.405134 -318.525804)
			(xy 93.46956 -318.428932) (xy 93.540515 -318.336736) (xy 93.617662 -318.249655) (xy 93.700633 -318.168104)
			(xy 93.789033 -318.092472) (xy 93.88244 -318.023118) (xy 93.980409 -317.960375) (xy 94.082473 -317.904539)
			(xy 94.188147 -317.855878) (xy 94.296926 -317.814624) (xy 94.408291 -317.780973) (xy 94.521714 -317.755085)
			(xy 94.636651 -317.737084) (xy 94.752557 -317.727055) (xy 94.868879 -317.725047) (xy 94.985062 -317.731069)
			(xy 95.100553 -317.745092) (xy 95.214801 -317.76705) (xy 95.327262 -317.796837) (xy 95.4374 -317.834312)
			(xy 95.54469 -317.879297) (xy 95.648621 -317.931576) (xy 95.748697 -317.990901) (xy 95.844443 -318.056989)
			(xy 95.9354 -318.129525) (xy 96.021136 -318.208164) (xy 96.101243 -318.29253) (xy 96.175339 -318.382222)
			(xy 96.243069 -318.476812) (xy 96.304113 -318.57585) (xy 96.358178 -318.678863) (xy 96.405008 -318.78536)
			(xy 96.444379 -318.894835) (xy 96.476103 -319.006765) (xy 96.500029 -319.120617) (xy 96.516043 -319.235849)
			(xy 96.52407 -319.351911) (xy 96.524572 -319.41008) (xy 96.52407 -319.468249) (xy 96.516043 -319.584311)
			(xy 96.500029 -319.699543) (xy 96.476103 -319.813395) (xy 96.444379 -319.925325) (xy 96.405008 -320.0348)
			(xy 96.358178 -320.141297) (xy 96.304113 -320.24431) (xy 96.243069 -320.343348) (xy 96.175339 -320.437938)
			(xy 96.101243 -320.52763) (xy 96.021136 -320.611996) (xy 95.9354 -320.690635) (xy 95.844443 -320.763171)
			(xy 95.748697 -320.829259) (xy 95.648621 -320.888584) (xy 95.54469 -320.940863) (xy 95.4374 -320.985848)
			(xy 95.327262 -321.023323) (xy 95.214801 -321.05311) (xy 95.100553 -321.075068) (xy 94.985062 -321.089091)
			(xy 94.868879 -321.095113) (xy 94.752557 -321.093105) (xy 94.636651 -321.083076) (xy 94.521714 -321.065075)
			(xy 94.408291 -321.039187) (xy 94.296926 -321.005536) (xy 94.188147 -320.964282) (xy 94.082473 -320.915621)
			(xy 93.980409 -320.859785) (xy 93.88244 -320.797042) (xy 93.789033 -320.727688) (xy 93.700633 -320.652056)
			(xy 93.617662 -320.570505) (xy 93.540515 -320.483424) (xy 93.46956 -320.391228) (xy 93.405134 -320.294356)
			(xy 93.347545 -320.193271) (xy 93.297068 -320.088453) (xy 93.253942 -319.980402) (xy 93.218373 -319.869634)
			(xy 93.190531 -319.756675) (xy 93.170549 -319.642065) (xy 93.158522 -319.52635) (xy 93.154506 -319.41008)
			(xy 42.500813 -319.41008) (xy 42.479042 -319.426857) (xy 42.381609 -319.491665) (xy 42.279905 -319.54954)
			(xy 42.174422 -319.600202) (xy 42.065671 -319.643404) (xy 41.954179 -319.678939) (xy 41.840485 -319.706634)
			(xy 41.725141 -319.726354) (xy 41.608704 -319.738005) (xy 41.491739 -319.74153) (xy 41.374812 -319.736912)
			(xy 41.258489 -319.724173) (xy 41.143334 -319.703375) (xy 41.029905 -319.674618) (xy 40.91875 -319.638042)
			(xy 40.810407 -319.593825) (xy 40.705403 -319.542179) (xy 40.604244 -319.483356) (xy 40.507421 -319.41764)
			(xy 40.415403 -319.345349) (xy 40.328636 -319.266834) (xy 40.247539 -319.182474) (xy 40.172506 -319.092679)
			(xy 40.103899 -318.997883) (xy 40.042051 -318.898544) (xy 39.987262 -318.795145) (xy 39.939796 -318.688186)
			(xy 39.899884 -318.578185) (xy 39.86772 -318.465674) (xy 39.843457 -318.351199) (xy 39.827215 -318.235313)
			(xy 39.819072 -318.118579) (xy 39.818564 -318.06007) (xy 0.509016 -318.06007) (xy 0.509016 -331.16012)
			(xy 86.877404 -331.16012) (xy 86.881424 -330.969469) (xy 86.893478 -330.779156) (xy 86.913544 -330.589521)
			(xy 86.941587 -330.4009) (xy 86.977556 -330.21363) (xy 87.021388 -330.028042) (xy 87.073005 -329.844467)
			(xy 87.132315 -329.663231) (xy 87.199213 -329.484656) (xy 87.273579 -329.309061) (xy 87.355281 -329.136756)
			(xy 87.444175 -328.968049) (xy 87.540101 -328.803239) (xy 87.64289 -328.64262) (xy 87.752359 -328.486477)
			(xy 87.868313 -328.335088) (xy 87.990547 -328.188721) (xy 88.118841 -328.047637) (xy 88.252969 -327.912088)
			(xy 88.392693 -327.782313) (xy 88.537763 -327.658543) (xy 88.687921 -327.541) (xy 88.842902 -327.429891)
			(xy 89.002429 -327.325414) (xy 89.166218 -327.227755) (xy 89.333978 -327.137088) (xy 89.505412 -327.053574)
			(xy 89.680214 -326.977361) (xy 89.858073 -326.908585) (xy 90.038674 -326.847367) (xy 90.221694 -326.793818)
			(xy 90.40681 -326.748032) (xy 90.593691 -326.71009) (xy 90.782006 -326.680061) (xy 90.971419 -326.657996)
			(xy 91.161593 -326.643937) (xy 91.352192 -326.637907) (xy 91.542875 -326.639917) (xy 91.733304 -326.649964)
			(xy 91.92314 -326.66803) (xy 92.112046 -326.694083) (xy 92.299685 -326.728076) (xy 92.485725 -326.769949)
			(xy 92.669834 -326.819628) (xy 92.851685 -326.877024) (xy 93.030955 -326.942035) (xy 93.207325 -327.014546)
			(xy 93.380481 -327.094427) (xy 93.550116 -327.181537) (xy 93.715928 -327.275721) (xy 93.877622 -327.376812)
			(xy 94.03491 -327.484628) (xy 94.187513 -327.59898) (xy 94.335161 -327.719663) (xy 94.477589 -327.846464)
			(xy 94.614545 -327.979155) (xy 94.745786 -328.117503) (xy 94.871078 -328.26126) (xy 94.990198 -328.410171)
			(xy 95.102934 -328.563972) (xy 95.209087 -328.722388) (xy 95.308467 -328.885139) (xy 95.400897 -329.051934)
			(xy 95.486214 -329.222478) (xy 95.564266 -329.396466) (xy 95.634913 -329.573591) (xy 95.698031 -329.753536)
			(xy 95.753507 -329.935982) (xy 95.801242 -330.120605) (xy 95.841152 -330.307075) (xy 95.873165 -330.495063)
			(xy 95.897225 -330.684233) (xy 95.913288 -330.874249) (xy 95.921327 -331.064773) (xy 95.92183 -331.16012)
			(xy 95.921327 -331.255467) (xy 95.913288 -331.445991) (xy 95.897225 -331.636007) (xy 95.873165 -331.825177)
			(xy 95.841152 -332.013165) (xy 95.801242 -332.199635) (xy 95.753507 -332.384258) (xy 95.698031 -332.566704)
			(xy 95.634913 -332.746649) (xy 95.564266 -332.923774) (xy 95.486214 -333.097762) (xy 95.400897 -333.268306)
			(xy 95.308467 -333.435101) (xy 95.209087 -333.597852) (xy 95.102934 -333.756268) (xy 94.990198 -333.910069)
			(xy 94.871078 -334.05898) (xy 94.745786 -334.202737) (xy 94.614545 -334.341085) (xy 94.477589 -334.473776)
			(xy 94.335161 -334.600577) (xy 94.187513 -334.72126) (xy 94.03491 -334.835612) (xy 93.877622 -334.943428)
			(xy 93.715928 -335.044519) (xy 93.550116 -335.138703) (xy 93.380481 -335.225813) (xy 93.207325 -335.305694)
			(xy 93.030955 -335.378205) (xy 92.851685 -335.443216) (xy 92.669834 -335.500612) (xy 92.485725 -335.550291)
			(xy 92.299685 -335.592164) (xy 92.112046 -335.626157) (xy 91.92314 -335.65221) (xy 91.733304 -335.670276)
			(xy 91.542875 -335.680323) (xy 91.352192 -335.682333) (xy 91.161593 -335.676303) (xy 90.971419 -335.662244)
			(xy 90.782006 -335.640179) (xy 90.593691 -335.61015) (xy 90.40681 -335.572208) (xy 90.221694 -335.526422)
			(xy 90.038674 -335.472873) (xy 89.858073 -335.411655) (xy 89.680214 -335.342879) (xy 89.505412 -335.266666)
			(xy 89.333978 -335.183152) (xy 89.166218 -335.092485) (xy 89.002429 -334.994826) (xy 88.842902 -334.890349)
			(xy 88.687921 -334.77924) (xy 88.537763 -334.661697) (xy 88.392693 -334.537927) (xy 88.252969 -334.408152)
			(xy 88.118841 -334.272603) (xy 87.990547 -334.131519) (xy 87.868313 -333.985152) (xy 87.752359 -333.833763)
			(xy 87.64289 -333.67762) (xy 87.540101 -333.517001) (xy 87.444175 -333.352191) (xy 87.355281 -333.183484)
			(xy 87.273579 -333.011179) (xy 87.199213 -332.835584) (xy 87.132315 -332.657009) (xy 87.073005 -332.475773)
			(xy 87.021388 -332.292198) (xy 86.977556 -332.10661) (xy 86.941587 -331.91934) (xy 86.913544 -331.730719)
			(xy 86.893478 -331.541084) (xy 86.881424 -331.350771) (xy 86.877404 -331.16012) (xy 0.509016 -331.16012)
			(xy 0.509016 -341.019892) (xy 3.583178 -341.019892) (xy 3.583676 -340.962648) (xy 3.591778 -340.848447)
			(xy 3.607939 -340.735105) (xy 3.632078 -340.623191) (xy 3.664075 -340.513266) (xy 3.70377 -340.405879)
			(xy 3.750962 -340.30157) (xy 3.805417 -340.200862) (xy 3.86686 -340.104258) (xy 3.934984 -340.012244)
			(xy 4.009448 -339.92528) (xy 4.089877 -339.843803) (xy 4.17587 -339.76822) (xy 4.266995 -339.698911)
			(xy 4.362795 -339.636223) (xy 4.462791 -339.58047) (xy 4.56648 -339.531931) (xy 4.673344 -339.49085)
			(xy 4.782847 -339.457433) (xy 4.894439 -339.431847) (xy 5.007562 -339.414221) (xy 5.121648 -339.404642)
			(xy 5.236127 -339.40316) (xy 5.350423 -339.40978) (xy 5.463965 -339.42447) (xy 5.576183 -339.447157)
			(xy 5.686514 -339.477727) (xy 5.794406 -339.516026) (xy 5.899318 -339.561862) (xy 6.000724 -339.615007)
			(xy 6.098116 -339.675192) (xy 6.191005 -339.742118) (xy 6.278927 -339.815448) (xy 6.36144 -339.894815)
			(xy 6.438131 -339.97982) (xy 6.508616 -340.070039) (xy 6.57254 -340.165019) (xy 6.629585 -340.264283)
			(xy 6.679464 -340.367335) (xy 6.721926 -340.473657) (xy 6.75676 -340.582717) (xy 6.78379 -340.693968)
			(xy 6.802882 -340.806853) (xy 6.813939 -340.920806) (xy 6.816905 -341.035256) (xy 6.811767 -341.149628)
			(xy 6.8001 -341.250016) (xy 75.486519 -341.250016) (xy 75.490544 -341.107824) (xy 75.502607 -340.966088)
			(xy 75.52267 -340.825262) (xy 75.550668 -340.685796) (xy 75.586512 -340.548137) (xy 75.630086 -340.412727)
			(xy 75.681251 -340.279999) (xy 75.739844 -340.150378) (xy 75.805675 -340.02428) (xy 75.878536 -339.902108)
			(xy 75.958191 -339.784254) (xy 76.044387 -339.671095) (xy 76.136846 -339.562993) (xy 76.235274 -339.460296)
			(xy 76.339353 -339.363332) (xy 76.448752 -339.272412) (xy 76.56312 -339.187826) (xy 76.682089 -339.109846)
			(xy 76.80528 -339.038722) (xy 76.932297 -338.974681) (xy 77.062734 -338.917929) (xy 77.196173 -338.868647)
			(xy 77.332186 -338.826993) (xy 77.470338 -338.793101) (xy 77.610187 -338.76708) (xy 77.751283 -338.749012)
			(xy 77.893175 -338.738955) (xy 78.03541 -338.736942) (xy 78.17753 -338.742979) (xy 78.319081 -338.757047)
			(xy 78.45961 -338.779101) (xy 78.598665 -338.80907) (xy 78.735803 -338.846858) (xy 78.870583 -338.892344)
			(xy 79.002574 -338.945382) (xy 79.131353 -339.005803) (xy 79.256507 -339.073412) (xy 79.377635 -339.147994)
			(xy 79.494351 -339.22931) (xy 79.606279 -339.317098) (xy 79.713061 -339.411078) (xy 79.814355 -339.510948)
			(xy 79.909836 -339.61639) (xy 79.9992 -339.727064) (xy 80.082158 -339.842617) (xy 80.158447 -339.962678)
			(xy 80.227821 -340.086863) (xy 80.290058 -340.214774) (xy 80.344959 -340.346001) (xy 80.392347 -340.480124)
			(xy 80.432072 -340.616713) (xy 80.464005 -340.755331) (xy 80.488046 -340.895533) (xy 80.504115 -341.036871)
			(xy 80.512163 -341.178892) (xy 80.512666 -341.250016) (xy 80.512163 -341.32114) (xy 80.504115 -341.463161)
			(xy 80.488046 -341.604499) (xy 80.464005 -341.744701) (xy 80.432072 -341.883319) (xy 80.392347 -342.019908)
			(xy 80.344959 -342.154031) (xy 80.290058 -342.285258) (xy 80.227821 -342.413169) (xy 80.158447 -342.537354)
			(xy 80.082158 -342.657415) (xy 79.9992 -342.772968) (xy 79.909836 -342.883642) (xy 79.814355 -342.989084)
			(xy 79.713061 -343.088954) (xy 79.606279 -343.182934) (xy 79.494351 -343.270722) (xy 79.377635 -343.352038)
			(xy 79.256507 -343.42662) (xy 79.131353 -343.494229) (xy 79.002574 -343.55465) (xy 78.870583 -343.607688)
			(xy 78.735803 -343.653174) (xy 78.598665 -343.690962) (xy 78.45961 -343.720931) (xy 78.319081 -343.742985)
			(xy 78.17753 -343.757053) (xy 78.03541 -343.76309) (xy 77.893175 -343.761077) (xy 77.751283 -343.75102)
			(xy 77.610187 -343.732952) (xy 77.470338 -343.706931) (xy 77.332186 -343.673039) (xy 77.196173 -343.631385)
			(xy 77.062734 -343.582103) (xy 76.932297 -343.525351) (xy 76.80528 -343.46131) (xy 76.682089 -343.390186)
			(xy 76.56312 -343.312206) (xy 76.448752 -343.22762) (xy 76.339353 -343.1367) (xy 76.235274 -343.039736)
			(xy 76.136846 -342.937039) (xy 76.044387 -342.828937) (xy 75.958191 -342.715778) (xy 75.878536 -342.597924)
			(xy 75.805675 -342.475752) (xy 75.739844 -342.349654) (xy 75.681251 -342.220033) (xy 75.630086 -342.087305)
			(xy 75.586512 -341.951895) (xy 75.550668 -341.814236) (xy 75.52267 -341.67477) (xy 75.502607 -341.533944)
			(xy 75.490544 -341.392208) (xy 75.486519 -341.250016) (xy 6.8001 -341.250016) (xy 6.79855 -341.263351)
			(xy 6.77732 -341.375853) (xy 6.748183 -341.486571) (xy 6.711286 -341.594951) (xy 6.666813 -341.700448)
			(xy 6.614988 -341.802534) (xy 6.556069 -341.900698) (xy 6.490353 -341.994448) (xy 6.454648 -342.039194)
			(xy 6.454394 -342.039448) (xy 6.060186 -342.039448) (xy 6.021179 -342.071737) (xy 5.939048 -342.130983)
			(xy 5.896102 -342.157812) (xy 5.882524 -342.166761) (xy 5.860006 -342.190206) (xy 5.844123 -342.218568)
			(xy 5.8359 -342.250017) (xy 5.835396 -342.26627) (xy 5.835396 -342.5063) (xy 5.835142 -342.5063)
			(xy 5.780469 -342.529093) (xy 5.668424 -342.567559) (xy 5.553864 -342.597719) (xy 5.437404 -342.619413)
			(xy 5.319668 -342.632524) (xy 5.201288 -342.636981) (xy 5.0829 -342.632761) (xy 4.965138 -342.619886)
			(xy 4.848635 -342.598425) (xy 4.734015 -342.568494) (xy 4.621893 -342.530253) (xy 4.567174 -342.50757)
			(xy 4.56692 -342.50757) (xy 4.56692 -342.26754) (xy 4.566441 -342.251261) (xy 4.558186 -342.219766)
			(xy 4.542229 -342.191387) (xy 4.519608 -342.167969) (xy 4.50596 -342.159082) (xy 4.459776 -342.130343)
			(xy 4.371783 -342.066378) (xy 4.330192 -342.03132) (xy 3.938778 -342.03132) (xy 3.904941 -341.988409)
			(xy 3.842477 -341.898728) (xy 3.78621 -341.805035) (xy 3.736399 -341.707756) (xy 3.69327 -341.607335)
			(xy 3.657021 -341.504231) (xy 3.627816 -341.398915) (xy 3.60579 -341.291867) (xy 3.591042 -341.183577)
			(xy 3.583641 -341.074537) (xy 3.583178 -341.019892) (xy 0.509016 -341.019892) (xy 0.509016 -362.51007)
			(xy 39.818564 -362.51007) (xy 39.819058 -362.452661) (xy 39.826902 -362.338113) (xy 39.842544 -362.224366)
			(xy 39.865911 -362.111952) (xy 39.896896 -362.001394) (xy 39.935352 -361.893209) (xy 39.981101 -361.7879)
			(xy 40.03393 -361.685958) (xy 40.093592 -361.587859) (xy 40.159809 -361.49406) (xy 40.232272 -361.404998)
			(xy 40.310645 -361.321089) (xy 40.39456 -361.242723) (xy 40.483627 -361.170266) (xy 40.577431 -361.104056)
			(xy 40.675535 -361.044402) (xy 40.777481 -360.991581) (xy 40.882793 -360.945839) (xy 40.990981 -360.907391)
			(xy 41.101541 -360.876415) (xy 41.213957 -360.853056) (xy 41.327705 -360.837423) (xy 41.442254 -360.829588)
			(xy 41.557072 -360.829588) (xy 41.671621 -360.837423) (xy 41.785369 -360.853056) (xy 41.897785 -360.876415)
			(xy 42.008345 -360.907391) (xy 42.116533 -360.945839) (xy 42.221845 -360.991581) (xy 42.323791 -361.044402)
			(xy 42.421895 -361.104056) (xy 42.515699 -361.170266) (xy 42.604766 -361.242723) (xy 42.688681 -361.321089)
			(xy 42.767054 -361.404998) (xy 42.839517 -361.49406) (xy 42.905734 -361.587859) (xy 42.965396 -361.685958)
			(xy 43.018225 -361.7879) (xy 43.063974 -361.893209) (xy 43.10243 -362.001394) (xy 43.133415 -362.111952)
			(xy 43.156782 -362.224366) (xy 43.172424 -362.338113) (xy 43.180268 -362.452661) (xy 43.180762 -362.51007)
			(xy 43.180576 -362.543253) (xy 43.177909 -362.609567) (xy 43.175428 -362.642658) (xy 43.170272 -362.700942)
			(xy 43.152948 -362.816671) (xy 43.127616 -362.930914) (xy 43.094401 -363.043119) (xy 43.053462 -363.152742)
			(xy 43.004999 -363.259253) (xy 42.949245 -363.362135) (xy 42.886471 -363.460891) (xy 42.816981 -363.555042)
			(xy 42.741111 -363.644132) (xy 42.659229 -363.727729) (xy 42.571732 -363.80543) (xy 42.500813 -363.86008)
			(xy 93.154506 -363.86008) (xy 93.158522 -363.74381) (xy 93.170549 -363.628095) (xy 93.190531 -363.513485)
			(xy 93.218373 -363.400526) (xy 93.253942 -363.289758) (xy 93.297068 -363.181707) (xy 93.347545 -363.076889)
			(xy 93.405134 -362.975804) (xy 93.46956 -362.878932) (xy 93.540515 -362.786736) (xy 93.617662 -362.699655)
			(xy 93.700633 -362.618104) (xy 93.789033 -362.542472) (xy 93.88244 -362.473118) (xy 93.980409 -362.410375)
			(xy 94.082473 -362.354539) (xy 94.188147 -362.305878) (xy 94.296926 -362.264624) (xy 94.408291 -362.230973)
			(xy 94.521714 -362.205085) (xy 94.636651 -362.187084) (xy 94.752557 -362.177055) (xy 94.868879 -362.175047)
			(xy 94.985062 -362.181069) (xy 95.100553 -362.195092) (xy 95.214801 -362.21705) (xy 95.327262 -362.246837)
			(xy 95.4374 -362.284312) (xy 95.54469 -362.329297) (xy 95.648621 -362.381576) (xy 95.748697 -362.440901)
			(xy 95.844443 -362.506989) (xy 95.9354 -362.579525) (xy 96.021136 -362.658164) (xy 96.101243 -362.74253)
			(xy 96.175339 -362.832222) (xy 96.243069 -362.926812) (xy 96.304113 -363.02585) (xy 96.358178 -363.128863)
			(xy 96.405008 -363.23536) (xy 96.444379 -363.344835) (xy 96.476103 -363.456765) (xy 96.500029 -363.570617)
			(xy 96.516043 -363.685849) (xy 96.52407 -363.801911) (xy 96.524572 -363.86008) (xy 96.52407 -363.918249)
			(xy 96.516043 -364.034311) (xy 96.500029 -364.149543) (xy 96.476103 -364.263395) (xy 96.444379 -364.375325)
			(xy 96.405008 -364.4848) (xy 96.358178 -364.591297) (xy 96.304113 -364.69431) (xy 96.243069 -364.793348)
			(xy 96.175339 -364.887938) (xy 96.101243 -364.97763) (xy 96.021136 -365.061996) (xy 95.9354 -365.140635)
			(xy 95.844443 -365.213171) (xy 95.748697 -365.279259) (xy 95.648621 -365.338584) (xy 95.54469 -365.390863)
			(xy 95.4374 -365.435848) (xy 95.327262 -365.473323) (xy 95.214801 -365.50311) (xy 95.100553 -365.525068)
			(xy 94.985062 -365.539091) (xy 94.868879 -365.545113) (xy 94.752557 -365.543105) (xy 94.636651 -365.533076)
			(xy 94.521714 -365.515075) (xy 94.408291 -365.489187) (xy 94.296926 -365.455536) (xy 94.188147 -365.414282)
			(xy 94.082473 -365.365621) (xy 93.980409 -365.309785) (xy 93.88244 -365.247042) (xy 93.789033 -365.177688)
			(xy 93.700633 -365.102056) (xy 93.617662 -365.020505) (xy 93.540515 -364.933424) (xy 93.46956 -364.841228)
			(xy 93.405134 -364.744356) (xy 93.347545 -364.643271) (xy 93.297068 -364.538453) (xy 93.253942 -364.430402)
			(xy 93.218373 -364.319634) (xy 93.190531 -364.206675) (xy 93.170549 -364.092065) (xy 93.158522 -363.97635)
			(xy 93.154506 -363.86008) (xy 42.500813 -363.86008) (xy 42.479042 -363.876857) (xy 42.381609 -363.941665)
			(xy 42.279905 -363.99954) (xy 42.174422 -364.050202) (xy 42.065671 -364.093404) (xy 41.954179 -364.128939)
			(xy 41.840485 -364.156634) (xy 41.725141 -364.176354) (xy 41.608704 -364.188005) (xy 41.491739 -364.19153)
			(xy 41.374812 -364.186912) (xy 41.258489 -364.174173) (xy 41.143334 -364.153375) (xy 41.029905 -364.124618)
			(xy 40.91875 -364.088042) (xy 40.810407 -364.043825) (xy 40.705403 -363.992179) (xy 40.604244 -363.933356)
			(xy 40.507421 -363.86764) (xy 40.415403 -363.795349) (xy 40.328636 -363.716834) (xy 40.247539 -363.632474)
			(xy 40.172506 -363.542679) (xy 40.103899 -363.447883) (xy 40.042051 -363.348544) (xy 39.987262 -363.245145)
			(xy 39.939796 -363.138186) (xy 39.899884 -363.028185) (xy 39.86772 -362.915674) (xy 39.843457 -362.801199)
			(xy 39.827215 -362.685313) (xy 39.819072 -362.568579) (xy 39.818564 -362.51007) (xy 0.509016 -362.51007)
			(xy 0.509016 -375.61012) (xy 86.877404 -375.61012) (xy 86.881424 -375.419469) (xy 86.893478 -375.229156)
			(xy 86.913544 -375.039521) (xy 86.941587 -374.8509) (xy 86.977556 -374.66363) (xy 87.021388 -374.478042)
			(xy 87.073005 -374.294467) (xy 87.132315 -374.113231) (xy 87.199213 -373.934656) (xy 87.273579 -373.759061)
			(xy 87.355281 -373.586756) (xy 87.444175 -373.418049) (xy 87.540101 -373.253239) (xy 87.64289 -373.09262)
			(xy 87.752359 -372.936477) (xy 87.868313 -372.785088) (xy 87.990547 -372.638721) (xy 88.118841 -372.497637)
			(xy 88.252969 -372.362088) (xy 88.392693 -372.232313) (xy 88.537763 -372.108543) (xy 88.687921 -371.991)
			(xy 88.842902 -371.879891) (xy 89.002429 -371.775414) (xy 89.166218 -371.677755) (xy 89.333978 -371.587088)
			(xy 89.505412 -371.503574) (xy 89.680214 -371.427361) (xy 89.858073 -371.358585) (xy 90.038674 -371.297367)
			(xy 90.221694 -371.243818) (xy 90.40681 -371.198032) (xy 90.593691 -371.16009) (xy 90.782006 -371.130061)
			(xy 90.971419 -371.107996) (xy 91.161593 -371.093937) (xy 91.352192 -371.087907) (xy 91.542875 -371.089917)
			(xy 91.733304 -371.099964) (xy 91.92314 -371.11803) (xy 92.112046 -371.144083) (xy 92.299685 -371.178076)
			(xy 92.485725 -371.219949) (xy 92.669834 -371.269628) (xy 92.851685 -371.327024) (xy 93.030955 -371.392035)
			(xy 93.207325 -371.464546) (xy 93.380481 -371.544427) (xy 93.550116 -371.631537) (xy 93.715928 -371.725721)
			(xy 93.877622 -371.826812) (xy 94.03491 -371.934628) (xy 94.187513 -372.04898) (xy 94.335161 -372.169663)
			(xy 94.477589 -372.296464) (xy 94.614545 -372.429155) (xy 94.745786 -372.567503) (xy 94.871078 -372.71126)
			(xy 94.990198 -372.860171) (xy 95.102934 -373.013972) (xy 95.209087 -373.172388) (xy 95.308467 -373.335139)
			(xy 95.400897 -373.501934) (xy 95.486214 -373.672478) (xy 95.564266 -373.846466) (xy 95.634913 -374.023591)
			(xy 95.698031 -374.203536) (xy 95.753507 -374.385982) (xy 95.801242 -374.570605) (xy 95.841152 -374.757075)
			(xy 95.873165 -374.945063) (xy 95.897225 -375.134233) (xy 95.913288 -375.324249) (xy 95.921327 -375.514773)
			(xy 95.92183 -375.61012) (xy 95.921327 -375.705467) (xy 95.913288 -375.895991) (xy 95.897225 -376.086007)
			(xy 95.873165 -376.275177) (xy 95.841152 -376.463165) (xy 95.801242 -376.649635) (xy 95.753507 -376.834258)
			(xy 95.698031 -377.016704) (xy 95.634913 -377.196649) (xy 95.564266 -377.373774) (xy 95.486214 -377.547762)
			(xy 95.400897 -377.718306) (xy 95.308467 -377.885101) (xy 95.209087 -378.047852) (xy 95.102934 -378.206268)
			(xy 94.990198 -378.360069) (xy 94.871078 -378.50898) (xy 94.745786 -378.652737) (xy 94.614545 -378.791085)
			(xy 94.477589 -378.923776) (xy 94.335161 -379.050577) (xy 94.187513 -379.17126) (xy 94.03491 -379.285612)
			(xy 93.877622 -379.393428) (xy 93.715928 -379.494519) (xy 93.550116 -379.588703) (xy 93.380481 -379.675813)
			(xy 93.207325 -379.755694) (xy 93.030955 -379.828205) (xy 92.851685 -379.893216) (xy 92.669834 -379.950612)
			(xy 92.485725 -380.000291) (xy 92.299685 -380.042164) (xy 92.112046 -380.076157) (xy 91.92314 -380.10221)
			(xy 91.733304 -380.120276) (xy 91.542875 -380.130323) (xy 91.352192 -380.132333) (xy 91.161593 -380.126303)
			(xy 90.971419 -380.112244) (xy 90.782006 -380.090179) (xy 90.593691 -380.06015) (xy 90.40681 -380.022208)
			(xy 90.221694 -379.976422) (xy 90.038674 -379.922873) (xy 89.858073 -379.861655) (xy 89.680214 -379.792879)
			(xy 89.505412 -379.716666) (xy 89.333978 -379.633152) (xy 89.166218 -379.542485) (xy 89.002429 -379.444826)
			(xy 88.842902 -379.340349) (xy 88.687921 -379.22924) (xy 88.537763 -379.111697) (xy 88.392693 -378.987927)
			(xy 88.252969 -378.858152) (xy 88.118841 -378.722603) (xy 87.990547 -378.581519) (xy 87.868313 -378.435152)
			(xy 87.752359 -378.283763) (xy 87.64289 -378.12762) (xy 87.540101 -377.967001) (xy 87.444175 -377.802191)
			(xy 87.355281 -377.633484) (xy 87.273579 -377.461179) (xy 87.199213 -377.285584) (xy 87.132315 -377.107009)
			(xy 87.073005 -376.925773) (xy 87.021388 -376.742198) (xy 86.977556 -376.55661) (xy 86.941587 -376.36934)
			(xy 86.913544 -376.180719) (xy 86.893478 -375.991084) (xy 86.881424 -375.800771) (xy 86.877404 -375.61012)
			(xy 0.509016 -375.61012) (xy 0.509016 -384.79984) (xy 14.086591 -384.79984) (xy 14.090616 -384.657648)
			(xy 14.102679 -384.515912) (xy 14.122742 -384.375086) (xy 14.15074 -384.23562) (xy 14.186584 -384.097961)
			(xy 14.230158 -383.962551) (xy 14.281323 -383.829823) (xy 14.339916 -383.700202) (xy 14.405747 -383.574104)
			(xy 14.478608 -383.451932) (xy 14.558263 -383.334078) (xy 14.644459 -383.220919) (xy 14.736918 -383.112817)
			(xy 14.835346 -383.01012) (xy 14.939425 -382.913156) (xy 15.048824 -382.822236) (xy 15.163192 -382.73765)
			(xy 15.282161 -382.65967) (xy 15.405352 -382.588546) (xy 15.532369 -382.524505) (xy 15.662806 -382.467753)
			(xy 15.796245 -382.418471) (xy 15.932258 -382.376817) (xy 16.07041 -382.342925) (xy 16.210259 -382.316904)
			(xy 16.351355 -382.298836) (xy 16.493247 -382.288779) (xy 16.635482 -382.286766) (xy 16.777602 -382.292803)
			(xy 16.919153 -382.306871) (xy 17.059682 -382.328925) (xy 17.198737 -382.358894) (xy 17.335875 -382.396682)
			(xy 17.470655 -382.442168) (xy 17.602646 -382.495206) (xy 17.731425 -382.555627) (xy 17.856579 -382.623236)
			(xy 17.977707 -382.697818) (xy 18.094423 -382.779134) (xy 18.206351 -382.866922) (xy 18.313133 -382.960902)
			(xy 18.414427 -383.060772) (xy 18.509908 -383.166214) (xy 18.599272 -383.276888) (xy 18.68223 -383.392441)
			(xy 18.758519 -383.512502) (xy 18.827893 -383.636687) (xy 18.89013 -383.764598) (xy 18.945031 -383.895825)
			(xy 18.992419 -384.029948) (xy 19.032144 -384.166537) (xy 19.064077 -384.305155) (xy 19.088118 -384.445357)
			(xy 19.104187 -384.586695) (xy 19.112235 -384.728716) (xy 19.112738 -384.79984) (xy 19.112235 -384.870964)
			(xy 19.104187 -385.012985) (xy 19.088118 -385.154323) (xy 19.064077 -385.294525) (xy 19.032144 -385.433143)
			(xy 18.992419 -385.569732) (xy 18.945031 -385.703855) (xy 18.89013 -385.835082) (xy 18.827893 -385.962993)
			(xy 18.758519 -386.087178) (xy 18.68223 -386.207239) (xy 18.599272 -386.322792) (xy 18.509908 -386.433466)
			(xy 18.414427 -386.538908) (xy 18.313133 -386.638778) (xy 18.206351 -386.732758) (xy 18.094423 -386.820546)
			(xy 17.977707 -386.901862) (xy 17.856579 -386.976444) (xy 17.731425 -387.044053) (xy 17.602646 -387.104474)
			(xy 17.470655 -387.157512) (xy 17.335875 -387.202998) (xy 17.198737 -387.240786) (xy 17.059682 -387.270755)
			(xy 16.919153 -387.292809) (xy 16.777602 -387.306877) (xy 16.635482 -387.312914) (xy 16.493247 -387.310901)
			(xy 16.351355 -387.300844) (xy 16.210259 -387.282776) (xy 16.07041 -387.256755) (xy 15.932258 -387.222863)
			(xy 15.796245 -387.181209) (xy 15.662806 -387.131927) (xy 15.532369 -387.075175) (xy 15.405352 -387.011134)
			(xy 15.282161 -386.94001) (xy 15.163192 -386.86203) (xy 15.048824 -386.777444) (xy 14.939425 -386.686524)
			(xy 14.835346 -386.58956) (xy 14.736918 -386.486863) (xy 14.644459 -386.378761) (xy 14.558263 -386.265602)
			(xy 14.478608 -386.147748) (xy 14.405747 -386.025576) (xy 14.339916 -385.899478) (xy 14.281323 -385.769857)
			(xy 14.230158 -385.637129) (xy 14.186584 -385.501719) (xy 14.15074 -385.36406) (xy 14.122742 -385.224594)
			(xy 14.102679 -385.083768) (xy 14.090616 -384.942032) (xy 14.086591 -384.79984) (xy 0.509016 -384.79984)
			(xy 0.509016 -399.479084) (xy 5.677649 -399.479084) (xy 5.677649 -399.352948) (xy 5.685569 -399.22706)
			(xy 5.701379 -399.101918) (xy 5.725014 -398.978015) (xy 5.756383 -398.855842) (xy 5.795361 -398.735879)
			(xy 5.841795 -398.6186) (xy 5.895502 -398.504468) (xy 5.956269 -398.393933) (xy 6.023856 -398.287433)
			(xy 6.097997 -398.185386) (xy 6.1784 -398.088196) (xy 6.264746 -397.996246) (xy 6.356696 -397.9099)
			(xy 6.453886 -397.829497) (xy 6.555933 -397.755356) (xy 6.662433 -397.687769) (xy 6.772968 -397.627002)
			(xy 6.8871 -397.573295) (xy 7.004379 -397.526861) (xy 7.124342 -397.487883) (xy 7.246515 -397.456514)
			(xy 7.370418 -397.432879) (xy 7.49556 -397.417069) (xy 7.621448 -397.409149) (xy 7.747584 -397.409149)
			(xy 7.873472 -397.417069) (xy 7.998614 -397.432879) (xy 8.122517 -397.456514) (xy 8.24469 -397.487883)
			(xy 8.364653 -397.526861) (xy 8.481932 -397.573295) (xy 8.596064 -397.627002) (xy 8.706599 -397.687769)
			(xy 8.813099 -397.755356) (xy 8.915146 -397.829497) (xy 9.012336 -397.9099) (xy 9.104286 -397.996246)
			(xy 9.190632 -398.088196) (xy 9.271035 -398.185386) (xy 9.345176 -398.287433) (xy 9.412763 -398.393933)
			(xy 9.47353 -398.504468) (xy 9.527237 -398.6186) (xy 9.573671 -398.735879) (xy 9.612649 -398.855842)
			(xy 9.644018 -398.978015) (xy 9.667653 -399.101918) (xy 9.683463 -399.22706) (xy 9.691383 -399.352948)
			(xy 9.691878 -399.416016) (xy 9.691383 -399.479084) (xy 9.683463 -399.604972) (xy 9.667653 -399.730114)
			(xy 9.644018 -399.854017) (xy 9.612649 -399.97619) (xy 9.573671 -400.096153) (xy 9.527237 -400.213432)
			(xy 9.47353 -400.327564) (xy 9.412763 -400.438099) (xy 9.345176 -400.544599) (xy 9.271035 -400.646646)
			(xy 9.190632 -400.743836) (xy 9.104286 -400.835786) (xy 9.012336 -400.922132) (xy 8.915146 -401.002535)
			(xy 8.813099 -401.076676) (xy 8.706599 -401.144263) (xy 8.596064 -401.20503) (xy 8.481932 -401.258737)
			(xy 8.364653 -401.305171) (xy 8.24469 -401.344149) (xy 8.122517 -401.375518) (xy 7.998614 -401.399153)
			(xy 7.873472 -401.414963) (xy 7.747584 -401.422883) (xy 7.621448 -401.422883) (xy 7.49556 -401.414963)
			(xy 7.370418 -401.399153) (xy 7.246515 -401.375518) (xy 7.124342 -401.344149) (xy 7.004379 -401.305171)
			(xy 6.8871 -401.258737) (xy 6.772968 -401.20503) (xy 6.662433 -401.144263) (xy 6.555933 -401.076676)
			(xy 6.453886 -401.002535) (xy 6.356696 -400.922132) (xy 6.264746 -400.835786) (xy 6.1784 -400.743836)
			(xy 6.097997 -400.646646) (xy 6.023856 -400.544599) (xy 5.956269 -400.438099) (xy 5.895502 -400.327564)
			(xy 5.841795 -400.213432) (xy 5.795361 -400.096153) (xy 5.756383 -399.97619) (xy 5.725014 -399.854017)
			(xy 5.701379 -399.730114) (xy 5.685569 -399.604972) (xy 5.677649 -399.479084) (xy 0.509016 -399.479084)
			(xy 0.509016 -406.96007) (xy 39.818564 -406.96007) (xy 39.819058 -406.902661) (xy 39.826902 -406.788113)
			(xy 39.842544 -406.674366) (xy 39.865911 -406.561952) (xy 39.896896 -406.451394) (xy 39.935352 -406.343209)
			(xy 39.981101 -406.2379) (xy 40.03393 -406.135958) (xy 40.093592 -406.037859) (xy 40.159809 -405.94406)
			(xy 40.232272 -405.854998) (xy 40.310645 -405.771089) (xy 40.39456 -405.692723) (xy 40.483627 -405.620266)
			(xy 40.577431 -405.554056) (xy 40.675535 -405.494402) (xy 40.777481 -405.441581) (xy 40.882793 -405.395839)
			(xy 40.990981 -405.357391) (xy 41.101541 -405.326415) (xy 41.213957 -405.303056) (xy 41.327705 -405.287423)
			(xy 41.442254 -405.279588) (xy 41.557072 -405.279588) (xy 41.671621 -405.287423) (xy 41.785369 -405.303056)
			(xy 41.897785 -405.326415) (xy 42.008345 -405.357391) (xy 42.116533 -405.395839) (xy 42.221845 -405.441581)
			(xy 42.323791 -405.494402) (xy 42.421895 -405.554056) (xy 42.515699 -405.620266) (xy 42.604766 -405.692723)
			(xy 42.688681 -405.771089) (xy 42.767054 -405.854998) (xy 42.839517 -405.94406) (xy 42.905734 -406.037859)
			(xy 42.965396 -406.135958) (xy 43.018225 -406.2379) (xy 43.063974 -406.343209) (xy 43.10243 -406.451394)
			(xy 43.133415 -406.561952) (xy 43.156782 -406.674366) (xy 43.172424 -406.788113) (xy 43.180268 -406.902661)
			(xy 43.180762 -406.96007) (xy 43.180576 -406.993253) (xy 43.177909 -407.059567) (xy 43.175428 -407.092658)
			(xy 43.170272 -407.150942) (xy 43.152948 -407.266671) (xy 43.127616 -407.380914) (xy 43.094401 -407.493119)
			(xy 43.053462 -407.602742) (xy 43.004999 -407.709253) (xy 42.949245 -407.812135) (xy 42.886471 -407.910891)
			(xy 42.816981 -408.005042) (xy 42.741111 -408.094132) (xy 42.659229 -408.177729) (xy 42.571732 -408.25543)
			(xy 42.500813 -408.31008) (xy 93.154506 -408.31008) (xy 93.158522 -408.19381) (xy 93.170549 -408.078095)
			(xy 93.190531 -407.963485) (xy 93.218373 -407.850526) (xy 93.253942 -407.739758) (xy 93.297068 -407.631707)
			(xy 93.347545 -407.526889) (xy 93.405134 -407.425804) (xy 93.46956 -407.328932) (xy 93.540515 -407.236736)
			(xy 93.617662 -407.149655) (xy 93.700633 -407.068104) (xy 93.789033 -406.992472) (xy 93.88244 -406.923118)
			(xy 93.980409 -406.860375) (xy 94.082473 -406.804539) (xy 94.188147 -406.755878) (xy 94.296926 -406.714624)
			(xy 94.408291 -406.680973) (xy 94.521714 -406.655085) (xy 94.636651 -406.637084) (xy 94.752557 -406.627055)
			(xy 94.868879 -406.625047) (xy 94.985062 -406.631069) (xy 95.100553 -406.645092) (xy 95.214801 -406.66705)
			(xy 95.327262 -406.696837) (xy 95.4374 -406.734312) (xy 95.54469 -406.779297) (xy 95.648621 -406.831576)
			(xy 95.748697 -406.890901) (xy 95.844443 -406.956989) (xy 95.9354 -407.029525) (xy 96.021136 -407.108164)
			(xy 96.101243 -407.19253) (xy 96.175339 -407.282222) (xy 96.243069 -407.376812) (xy 96.304113 -407.47585)
			(xy 96.358178 -407.578863) (xy 96.405008 -407.68536) (xy 96.444379 -407.794835) (xy 96.476103 -407.906765)
			(xy 96.500029 -408.020617) (xy 96.516043 -408.135849) (xy 96.52407 -408.251911) (xy 96.524572 -408.31008)
			(xy 96.52407 -408.368249) (xy 96.516043 -408.484311) (xy 96.500029 -408.599543) (xy 96.476103 -408.713395)
			(xy 96.444379 -408.825325) (xy 96.405008 -408.9348) (xy 96.358178 -409.041297) (xy 96.304113 -409.14431)
			(xy 96.243069 -409.243348) (xy 96.175339 -409.337938) (xy 96.101243 -409.42763) (xy 96.021136 -409.511996)
			(xy 95.9354 -409.590635) (xy 95.844443 -409.663171) (xy 95.748697 -409.729259) (xy 95.648621 -409.788584)
			(xy 95.54469 -409.840863) (xy 95.4374 -409.885848) (xy 95.327262 -409.923323) (xy 95.214801 -409.95311)
			(xy 95.100553 -409.975068) (xy 94.985062 -409.989091) (xy 94.868879 -409.995113) (xy 94.752557 -409.993105)
			(xy 94.636651 -409.983076) (xy 94.521714 -409.965075) (xy 94.408291 -409.939187) (xy 94.296926 -409.905536)
			(xy 94.188147 -409.864282) (xy 94.082473 -409.815621) (xy 93.980409 -409.759785) (xy 93.88244 -409.697042)
			(xy 93.789033 -409.627688) (xy 93.700633 -409.552056) (xy 93.617662 -409.470505) (xy 93.540515 -409.383424)
			(xy 93.46956 -409.291228) (xy 93.405134 -409.194356) (xy 93.347545 -409.093271) (xy 93.297068 -408.988453)
			(xy 93.253942 -408.880402) (xy 93.218373 -408.769634) (xy 93.190531 -408.656675) (xy 93.170549 -408.542065)
			(xy 93.158522 -408.42635) (xy 93.154506 -408.31008) (xy 42.500813 -408.31008) (xy 42.479042 -408.326857)
			(xy 42.381609 -408.391665) (xy 42.279905 -408.44954) (xy 42.174422 -408.500202) (xy 42.065671 -408.543404)
			(xy 41.954179 -408.578939) (xy 41.840485 -408.606634) (xy 41.725141 -408.626354) (xy 41.608704 -408.638005)
			(xy 41.491739 -408.64153) (xy 41.374812 -408.636912) (xy 41.258489 -408.624173) (xy 41.143334 -408.603375)
			(xy 41.029905 -408.574618) (xy 40.91875 -408.538042) (xy 40.810407 -408.493825) (xy 40.705403 -408.442179)
			(xy 40.604244 -408.383356) (xy 40.507421 -408.31764) (xy 40.415403 -408.245349) (xy 40.328636 -408.166834)
			(xy 40.247539 -408.082474) (xy 40.172506 -407.992679) (xy 40.103899 -407.897883) (xy 40.042051 -407.798544)
			(xy 39.987262 -407.695145) (xy 39.939796 -407.588186) (xy 39.899884 -407.478185) (xy 39.86772 -407.365674)
			(xy 39.843457 -407.251199) (xy 39.827215 -407.135313) (xy 39.819072 -407.018579) (xy 39.818564 -406.96007)
			(xy 0.509016 -406.96007) (xy 0.509016 -410.909084) (xy 5.677649 -410.909084) (xy 5.677649 -410.782948)
			(xy 5.685569 -410.65706) (xy 5.701379 -410.531918) (xy 5.725014 -410.408015) (xy 5.756383 -410.285842)
			(xy 5.795361 -410.165879) (xy 5.841795 -410.0486) (xy 5.895502 -409.934468) (xy 5.956269 -409.823933)
			(xy 6.023856 -409.717433) (xy 6.097997 -409.615386) (xy 6.1784 -409.518196) (xy 6.264746 -409.426246)
			(xy 6.356696 -409.3399) (xy 6.453886 -409.259497) (xy 6.555933 -409.185356) (xy 6.662433 -409.117769)
			(xy 6.772968 -409.057002) (xy 6.8871 -409.003295) (xy 7.004379 -408.956861) (xy 7.124342 -408.917883)
			(xy 7.246515 -408.886514) (xy 7.370418 -408.862879) (xy 7.49556 -408.847069) (xy 7.621448 -408.839149)
			(xy 7.747584 -408.839149) (xy 7.873472 -408.847069) (xy 7.998614 -408.862879) (xy 8.122517 -408.886514)
			(xy 8.24469 -408.917883) (xy 8.364653 -408.956861) (xy 8.481932 -409.003295) (xy 8.596064 -409.057002)
			(xy 8.706599 -409.117769) (xy 8.813099 -409.185356) (xy 8.915146 -409.259497) (xy 9.012336 -409.3399)
			(xy 9.104286 -409.426246) (xy 9.190632 -409.518196) (xy 9.271035 -409.615386) (xy 9.345176 -409.717433)
			(xy 9.412763 -409.823933) (xy 9.47353 -409.934468) (xy 9.527237 -410.0486) (xy 9.573671 -410.165879)
			(xy 9.612649 -410.285842) (xy 9.644018 -410.408015) (xy 9.667653 -410.531918) (xy 9.683463 -410.65706)
			(xy 9.691383 -410.782948) (xy 9.691878 -410.846016) (xy 9.691383 -410.909084) (xy 9.683463 -411.034972)
			(xy 9.667653 -411.160114) (xy 9.644018 -411.284017) (xy 9.612649 -411.40619) (xy 9.573671 -411.526153)
			(xy 9.527237 -411.643432) (xy 9.47353 -411.757564) (xy 9.412763 -411.868099) (xy 9.345176 -411.974599)
			(xy 9.271035 -412.076646) (xy 9.190632 -412.173836) (xy 9.104286 -412.265786) (xy 9.012336 -412.352132)
			(xy 8.915146 -412.432535) (xy 8.813099 -412.506676) (xy 8.706599 -412.574263) (xy 8.596064 -412.63503)
			(xy 8.481932 -412.688737) (xy 8.364653 -412.735171) (xy 8.24469 -412.774149) (xy 8.122517 -412.805518)
			(xy 7.998614 -412.829153) (xy 7.873472 -412.844963) (xy 7.747584 -412.852883) (xy 7.621448 -412.852883)
			(xy 7.49556 -412.844963) (xy 7.370418 -412.829153) (xy 7.246515 -412.805518) (xy 7.124342 -412.774149)
			(xy 7.004379 -412.735171) (xy 6.8871 -412.688737) (xy 6.772968 -412.63503) (xy 6.662433 -412.574263)
			(xy 6.555933 -412.506676) (xy 6.453886 -412.432535) (xy 6.356696 -412.352132) (xy 6.264746 -412.265786)
			(xy 6.1784 -412.173836) (xy 6.097997 -412.076646) (xy 6.023856 -411.974599) (xy 5.956269 -411.868099)
			(xy 5.895502 -411.757564) (xy 5.841795 -411.643432) (xy 5.795361 -411.526153) (xy 5.756383 -411.40619)
			(xy 5.725014 -411.284017) (xy 5.701379 -411.160114) (xy 5.685569 -411.034972) (xy 5.677649 -410.909084)
			(xy 0.509016 -410.909084) (xy 0.509016 -420.06012) (xy 86.877404 -420.06012) (xy 86.881424 -419.869469)
			(xy 86.893478 -419.679156) (xy 86.913544 -419.489521) (xy 86.941587 -419.3009) (xy 86.977556 -419.11363)
			(xy 87.021388 -418.928042) (xy 87.073005 -418.744467) (xy 87.132315 -418.563231) (xy 87.199213 -418.384656)
			(xy 87.273579 -418.209061) (xy 87.355281 -418.036756) (xy 87.444175 -417.868049) (xy 87.540101 -417.703239)
			(xy 87.64289 -417.54262) (xy 87.752359 -417.386477) (xy 87.868313 -417.235088) (xy 87.990547 -417.088721)
			(xy 88.118841 -416.947637) (xy 88.252969 -416.812088) (xy 88.392693 -416.682313) (xy 88.537763 -416.558543)
			(xy 88.687921 -416.441) (xy 88.842902 -416.329891) (xy 89.002429 -416.225414) (xy 89.166218 -416.127755)
			(xy 89.333978 -416.037088) (xy 89.505412 -415.953574) (xy 89.680214 -415.877361) (xy 89.858073 -415.808585)
			(xy 90.038674 -415.747367) (xy 90.221694 -415.693818) (xy 90.40681 -415.648032) (xy 90.593691 -415.61009)
			(xy 90.782006 -415.580061) (xy 90.971419 -415.557996) (xy 91.161593 -415.543937) (xy 91.352192 -415.537907)
			(xy 91.542875 -415.539917) (xy 91.733304 -415.549964) (xy 91.92314 -415.56803) (xy 92.112046 -415.594083)
			(xy 92.299685 -415.628076) (xy 92.485725 -415.669949) (xy 92.669834 -415.719628) (xy 92.851685 -415.777024)
			(xy 93.030955 -415.842035) (xy 93.207325 -415.914546) (xy 93.380481 -415.994427) (xy 93.550116 -416.081537)
			(xy 93.715928 -416.175721) (xy 93.877622 -416.276812) (xy 94.03491 -416.384628) (xy 94.187513 -416.49898)
			(xy 94.335161 -416.619663) (xy 94.477589 -416.746464) (xy 94.614545 -416.879155) (xy 94.745786 -417.017503)
			(xy 94.871078 -417.16126) (xy 94.990198 -417.310171) (xy 95.102934 -417.463972) (xy 95.209087 -417.622388)
			(xy 95.308467 -417.785139) (xy 95.400897 -417.951934) (xy 95.486214 -418.122478) (xy 95.564266 -418.296466)
			(xy 95.634913 -418.473591) (xy 95.698031 -418.653536) (xy 95.753507 -418.835982) (xy 95.801242 -419.020605)
			(xy 95.841152 -419.207075) (xy 95.873165 -419.395063) (xy 95.897225 -419.584233) (xy 95.913288 -419.774249)
			(xy 95.921327 -419.964773) (xy 95.92183 -420.06012) (xy 95.921327 -420.155467) (xy 95.913288 -420.345991)
			(xy 95.897225 -420.536007) (xy 95.873165 -420.725177) (xy 95.841152 -420.913165) (xy 95.801242 -421.099635)
			(xy 95.753507 -421.284258) (xy 95.698031 -421.466704) (xy 95.634913 -421.646649) (xy 95.564266 -421.823774)
			(xy 95.486214 -421.997762) (xy 95.400897 -422.168306) (xy 95.308467 -422.335101) (xy 95.209087 -422.497852)
			(xy 95.102934 -422.656268) (xy 94.990198 -422.810069) (xy 94.871078 -422.95898) (xy 94.745786 -423.102737)
			(xy 94.614545 -423.241085) (xy 94.477589 -423.373776) (xy 94.335161 -423.500577) (xy 94.187513 -423.62126)
			(xy 94.03491 -423.735612) (xy 93.877622 -423.843428) (xy 93.715928 -423.944519) (xy 93.550116 -424.038703)
			(xy 93.380481 -424.125813) (xy 93.207325 -424.205694) (xy 93.030955 -424.278205) (xy 92.851685 -424.343216)
			(xy 92.669834 -424.400612) (xy 92.485725 -424.450291) (xy 92.299685 -424.492164) (xy 92.112046 -424.526157)
			(xy 91.92314 -424.55221) (xy 91.733304 -424.570276) (xy 91.542875 -424.580323) (xy 91.352192 -424.582333)
			(xy 91.161593 -424.576303) (xy 90.971419 -424.562244) (xy 90.782006 -424.540179) (xy 90.593691 -424.51015)
			(xy 90.40681 -424.472208) (xy 90.221694 -424.426422) (xy 90.038674 -424.372873) (xy 89.858073 -424.311655)
			(xy 89.680214 -424.242879) (xy 89.505412 -424.166666) (xy 89.333978 -424.083152) (xy 89.166218 -423.992485)
			(xy 89.002429 -423.894826) (xy 88.842902 -423.790349) (xy 88.687921 -423.67924) (xy 88.537763 -423.561697)
			(xy 88.392693 -423.437927) (xy 88.252969 -423.308152) (xy 88.118841 -423.172603) (xy 87.990547 -423.031519)
			(xy 87.868313 -422.885152) (xy 87.752359 -422.733763) (xy 87.64289 -422.57762) (xy 87.540101 -422.417001)
			(xy 87.444175 -422.252191) (xy 87.355281 -422.083484) (xy 87.273579 -421.911179) (xy 87.199213 -421.735584)
			(xy 87.132315 -421.557009) (xy 87.073005 -421.375773) (xy 87.021388 -421.192198) (xy 86.977556 -421.00661)
			(xy 86.941587 -420.81934) (xy 86.913544 -420.630719) (xy 86.893478 -420.441084) (xy 86.881424 -420.250771)
			(xy 86.877404 -420.06012) (xy 0.509016 -420.06012) (xy 0.509016 -430.150016) (xy 75.486519 -430.150016)
			(xy 75.490544 -430.007824) (xy 75.502607 -429.866088) (xy 75.52267 -429.725262) (xy 75.550668 -429.585796)
			(xy 75.586512 -429.448137) (xy 75.630086 -429.312727) (xy 75.681251 -429.179999) (xy 75.739844 -429.050378)
			(xy 75.805675 -428.92428) (xy 75.878536 -428.802108) (xy 75.958191 -428.684254) (xy 76.044387 -428.571095)
			(xy 76.136846 -428.462993) (xy 76.235274 -428.360296) (xy 76.339353 -428.263332) (xy 76.448752 -428.172412)
			(xy 76.56312 -428.087826) (xy 76.682089 -428.009846) (xy 76.80528 -427.938722) (xy 76.932297 -427.874681)
			(xy 77.062734 -427.817929) (xy 77.196173 -427.768647) (xy 77.332186 -427.726993) (xy 77.470338 -427.693101)
			(xy 77.610187 -427.66708) (xy 77.751283 -427.649012) (xy 77.893175 -427.638955) (xy 78.03541 -427.636942)
			(xy 78.17753 -427.642979) (xy 78.319081 -427.657047) (xy 78.45961 -427.679101) (xy 78.598665 -427.70907)
			(xy 78.735803 -427.746858) (xy 78.870583 -427.792344) (xy 79.002574 -427.845382) (xy 79.131353 -427.905803)
			(xy 79.256507 -427.973412) (xy 79.377635 -428.047994) (xy 79.494351 -428.12931) (xy 79.606279 -428.217098)
			(xy 79.713061 -428.311078) (xy 79.814355 -428.410948) (xy 79.909836 -428.51639) (xy 79.9992 -428.627064)
			(xy 80.082158 -428.742617) (xy 80.158447 -428.862678) (xy 80.227821 -428.986863) (xy 80.290058 -429.114774)
			(xy 80.344959 -429.246001) (xy 80.392347 -429.380124) (xy 80.432072 -429.516713) (xy 80.464005 -429.655331)
			(xy 80.488046 -429.795533) (xy 80.504115 -429.936871) (xy 80.512163 -430.078892) (xy 80.512666 -430.150016)
			(xy 80.512163 -430.22114) (xy 80.504115 -430.363161) (xy 80.488046 -430.504499) (xy 80.464005 -430.644701)
			(xy 80.432072 -430.783319) (xy 80.392347 -430.919908) (xy 80.344959 -431.054031) (xy 80.290058 -431.185258)
			(xy 80.227821 -431.313169) (xy 80.158447 -431.437354) (xy 80.082158 -431.557415) (xy 79.9992 -431.672968)
			(xy 79.909836 -431.783642) (xy 79.814355 -431.889084) (xy 79.713061 -431.988954) (xy 79.606279 -432.082934)
			(xy 79.494351 -432.170722) (xy 79.377635 -432.252038) (xy 79.256507 -432.32662) (xy 79.131353 -432.394229)
			(xy 79.002574 -432.45465) (xy 78.870583 -432.507688) (xy 78.735803 -432.553174) (xy 78.598665 -432.590962)
			(xy 78.45961 -432.620931) (xy 78.319081 -432.642985) (xy 78.17753 -432.657053) (xy 78.03541 -432.66309)
			(xy 77.893175 -432.661077) (xy 77.751283 -432.65102) (xy 77.610187 -432.632952) (xy 77.470338 -432.606931)
			(xy 77.332186 -432.573039) (xy 77.196173 -432.531385) (xy 77.062734 -432.482103) (xy 76.932297 -432.425351)
			(xy 76.80528 -432.36131) (xy 76.682089 -432.290186) (xy 76.56312 -432.212206) (xy 76.448752 -432.12762)
			(xy 76.339353 -432.0367) (xy 76.235274 -431.939736) (xy 76.136846 -431.837039) (xy 76.044387 -431.728937)
			(xy 75.958191 -431.615778) (xy 75.878536 -431.497924) (xy 75.805675 -431.375752) (xy 75.739844 -431.249654)
			(xy 75.681251 -431.120033) (xy 75.630086 -430.987305) (xy 75.586512 -430.851895) (xy 75.550668 -430.714236)
			(xy 75.52267 -430.57477) (xy 75.502607 -430.433944) (xy 75.490544 -430.292208) (xy 75.486519 -430.150016)
			(xy 0.509016 -430.150016) (xy 0.509016 -451.41007) (xy 39.818564 -451.41007) (xy 39.819058 -451.352661)
			(xy 39.826902 -451.238113) (xy 39.842544 -451.124366) (xy 39.865911 -451.011952) (xy 39.896896 -450.901394)
			(xy 39.935352 -450.793209) (xy 39.981101 -450.6879) (xy 40.03393 -450.585958) (xy 40.093592 -450.487859)
			(xy 40.159809 -450.39406) (xy 40.232272 -450.304998) (xy 40.310645 -450.221089) (xy 40.39456 -450.142723)
			(xy 40.483627 -450.070266) (xy 40.577431 -450.004056) (xy 40.675535 -449.944402) (xy 40.777481 -449.891581)
			(xy 40.882793 -449.845839) (xy 40.990981 -449.807391) (xy 41.101541 -449.776415) (xy 41.213957 -449.753056)
			(xy 41.327705 -449.737423) (xy 41.442254 -449.729588) (xy 41.557072 -449.729588) (xy 41.671621 -449.737423)
			(xy 41.785369 -449.753056) (xy 41.897785 -449.776415) (xy 42.008345 -449.807391) (xy 42.116533 -449.845839)
			(xy 42.221845 -449.891581) (xy 42.323791 -449.944402) (xy 42.421895 -450.004056) (xy 42.515699 -450.070266)
			(xy 42.604766 -450.142723) (xy 42.688681 -450.221089) (xy 42.767054 -450.304998) (xy 42.839517 -450.39406)
			(xy 42.905734 -450.487859) (xy 42.965396 -450.585958) (xy 43.018225 -450.6879) (xy 43.063974 -450.793209)
			(xy 43.10243 -450.901394) (xy 43.133415 -451.011952) (xy 43.156782 -451.124366) (xy 43.172424 -451.238113)
			(xy 43.180268 -451.352661) (xy 43.180762 -451.41007) (xy 43.180576 -451.443253) (xy 43.177909 -451.509567)
			(xy 43.175428 -451.542658) (xy 43.170272 -451.600942) (xy 43.152948 -451.716671) (xy 43.127616 -451.830914)
			(xy 43.094401 -451.943119) (xy 43.053462 -452.052742) (xy 43.004999 -452.159253) (xy 42.949245 -452.262135)
			(xy 42.886471 -452.360891) (xy 42.816981 -452.455042) (xy 42.741111 -452.544132) (xy 42.659229 -452.627729)
			(xy 42.571732 -452.70543) (xy 42.500813 -452.76008) (xy 93.154506 -452.76008) (xy 93.158522 -452.64381)
			(xy 93.170549 -452.528095) (xy 93.190531 -452.413485) (xy 93.218373 -452.300526) (xy 93.253942 -452.189758)
			(xy 93.297068 -452.081707) (xy 93.347545 -451.976889) (xy 93.405134 -451.875804) (xy 93.46956 -451.778932)
			(xy 93.540515 -451.686736) (xy 93.617662 -451.599655) (xy 93.700633 -451.518104) (xy 93.789033 -451.442472)
			(xy 93.88244 -451.373118) (xy 93.980409 -451.310375) (xy 94.082473 -451.254539) (xy 94.188147 -451.205878)
			(xy 94.296926 -451.164624) (xy 94.408291 -451.130973) (xy 94.521714 -451.105085) (xy 94.636651 -451.087084)
			(xy 94.752557 -451.077055) (xy 94.868879 -451.075047) (xy 94.985062 -451.081069) (xy 95.100553 -451.095092)
			(xy 95.214801 -451.11705) (xy 95.327262 -451.146837) (xy 95.4374 -451.184312) (xy 95.54469 -451.229297)
			(xy 95.648621 -451.281576) (xy 95.748697 -451.340901) (xy 95.844443 -451.406989) (xy 95.9354 -451.479525)
			(xy 96.021136 -451.558164) (xy 96.101243 -451.64253) (xy 96.175339 -451.732222) (xy 96.243069 -451.826812)
			(xy 96.304113 -451.92585) (xy 96.358178 -452.028863) (xy 96.405008 -452.13536) (xy 96.444379 -452.244835)
			(xy 96.476103 -452.356765) (xy 96.500029 -452.470617) (xy 96.516043 -452.585849) (xy 96.52407 -452.701911)
			(xy 96.524572 -452.76008) (xy 96.52407 -452.818249) (xy 96.516043 -452.934311) (xy 96.500029 -453.049543)
			(xy 96.476103 -453.163395) (xy 96.444379 -453.275325) (xy 96.405008 -453.3848) (xy 96.358178 -453.491297)
			(xy 96.304113 -453.59431) (xy 96.243069 -453.693348) (xy 96.175339 -453.787938) (xy 96.101243 -453.87763)
			(xy 96.021136 -453.961996) (xy 95.9354 -454.040635) (xy 95.844443 -454.113171) (xy 95.748697 -454.179259)
			(xy 95.648621 -454.238584) (xy 95.54469 -454.290863) (xy 95.4374 -454.335848) (xy 95.327262 -454.373323)
			(xy 95.214801 -454.40311) (xy 95.100553 -454.425068) (xy 94.985062 -454.439091) (xy 94.868879 -454.445113)
			(xy 94.752557 -454.443105) (xy 94.636651 -454.433076) (xy 94.521714 -454.415075) (xy 94.408291 -454.389187)
			(xy 94.296926 -454.355536) (xy 94.188147 -454.314282) (xy 94.082473 -454.265621) (xy 93.980409 -454.209785)
			(xy 93.88244 -454.147042) (xy 93.789033 -454.077688) (xy 93.700633 -454.002056) (xy 93.617662 -453.920505)
			(xy 93.540515 -453.833424) (xy 93.46956 -453.741228) (xy 93.405134 -453.644356) (xy 93.347545 -453.543271)
			(xy 93.297068 -453.438453) (xy 93.253942 -453.330402) (xy 93.218373 -453.219634) (xy 93.190531 -453.106675)
			(xy 93.170549 -452.992065) (xy 93.158522 -452.87635) (xy 93.154506 -452.76008) (xy 42.500813 -452.76008)
			(xy 42.479042 -452.776857) (xy 42.381609 -452.841665) (xy 42.279905 -452.89954) (xy 42.174422 -452.950202)
			(xy 42.065671 -452.993404) (xy 41.954179 -453.028939) (xy 41.840485 -453.056634) (xy 41.725141 -453.076354)
			(xy 41.608704 -453.088005) (xy 41.491739 -453.09153) (xy 41.374812 -453.086912) (xy 41.258489 -453.074173)
			(xy 41.143334 -453.053375) (xy 41.029905 -453.024618) (xy 40.91875 -452.988042) (xy 40.810407 -452.943825)
			(xy 40.705403 -452.892179) (xy 40.604244 -452.833356) (xy 40.507421 -452.76764) (xy 40.415403 -452.695349)
			(xy 40.328636 -452.616834) (xy 40.247539 -452.532474) (xy 40.172506 -452.442679) (xy 40.103899 -452.347883)
			(xy 40.042051 -452.248544) (xy 39.987262 -452.145145) (xy 39.939796 -452.038186) (xy 39.899884 -451.928185)
			(xy 39.86772 -451.815674) (xy 39.843457 -451.701199) (xy 39.827215 -451.585313) (xy 39.819072 -451.468579)
			(xy 39.818564 -451.41007) (xy 0.509016 -451.41007) (xy 0.509016 -464.509866) (xy 86.877404 -464.509866)
			(xy 86.881424 -464.319215) (xy 86.893478 -464.128902) (xy 86.913544 -463.939267) (xy 86.941587 -463.750646)
			(xy 86.977556 -463.563376) (xy 87.021388 -463.377788) (xy 87.073005 -463.194213) (xy 87.132315 -463.012977)
			(xy 87.199213 -462.834402) (xy 87.273579 -462.658807) (xy 87.355281 -462.486502) (xy 87.444175 -462.317795)
			(xy 87.540101 -462.152985) (xy 87.64289 -461.992366) (xy 87.752359 -461.836223) (xy 87.868313 -461.684834)
			(xy 87.990547 -461.538467) (xy 88.118841 -461.397383) (xy 88.252969 -461.261834) (xy 88.392693 -461.132059)
			(xy 88.537763 -461.008289) (xy 88.687921 -460.890746) (xy 88.842902 -460.779637) (xy 89.002429 -460.67516)
			(xy 89.166218 -460.577501) (xy 89.333978 -460.486834) (xy 89.505412 -460.40332) (xy 89.680214 -460.327107)
			(xy 89.858073 -460.258331) (xy 90.038674 -460.197113) (xy 90.221694 -460.143564) (xy 90.40681 -460.097778)
			(xy 90.593691 -460.059836) (xy 90.782006 -460.029807) (xy 90.971419 -460.007742) (xy 91.161593 -459.993683)
			(xy 91.352192 -459.987653) (xy 91.542875 -459.989663) (xy 91.733304 -459.99971) (xy 91.92314 -460.017776)
			(xy 92.112046 -460.043829) (xy 92.299685 -460.077822) (xy 92.485725 -460.119695) (xy 92.669834 -460.169374)
			(xy 92.851685 -460.22677) (xy 93.030955 -460.291781) (xy 93.207325 -460.364292) (xy 93.380481 -460.444173)
			(xy 93.550116 -460.531283) (xy 93.715928 -460.625467) (xy 93.877622 -460.726558) (xy 94.03491 -460.834374)
			(xy 94.187513 -460.948726) (xy 94.335161 -461.069409) (xy 94.477589 -461.19621) (xy 94.614545 -461.328901)
			(xy 94.745786 -461.467249) (xy 94.871078 -461.611006) (xy 94.990198 -461.759917) (xy 95.102934 -461.913718)
			(xy 95.209087 -462.072134) (xy 95.308467 -462.234885) (xy 95.400897 -462.40168) (xy 95.486214 -462.572224)
			(xy 95.564266 -462.746212) (xy 95.634913 -462.923337) (xy 95.698031 -463.103282) (xy 95.753507 -463.285728)
			(xy 95.801242 -463.470351) (xy 95.841152 -463.656821) (xy 95.873165 -463.844809) (xy 95.897225 -464.033979)
			(xy 95.913288 -464.223995) (xy 95.921327 -464.414519) (xy 95.92183 -464.509866) (xy 95.921327 -464.605213)
			(xy 95.913288 -464.795737) (xy 95.897225 -464.985753) (xy 95.873165 -465.174923) (xy 95.841152 -465.362911)
			(xy 95.801242 -465.549381) (xy 95.753507 -465.734004) (xy 95.698031 -465.91645) (xy 95.634913 -466.096395)
			(xy 95.564266 -466.27352) (xy 95.486214 -466.447508) (xy 95.400897 -466.618052) (xy 95.308467 -466.784847)
			(xy 95.209087 -466.947598) (xy 95.102934 -467.106014) (xy 94.990198 -467.259815) (xy 94.871078 -467.408726)
			(xy 94.745786 -467.552483) (xy 94.614545 -467.690831) (xy 94.477589 -467.823522) (xy 94.335161 -467.950323)
			(xy 94.187513 -468.071006) (xy 94.03491 -468.185358) (xy 93.877622 -468.293174) (xy 93.715928 -468.394265)
			(xy 93.550116 -468.488449) (xy 93.380481 -468.575559) (xy 93.207325 -468.65544) (xy 93.030955 -468.727951)
			(xy 92.851685 -468.792962) (xy 92.669834 -468.850358) (xy 92.485725 -468.900037) (xy 92.299685 -468.94191)
			(xy 92.112046 -468.975903) (xy 91.92314 -469.001956) (xy 91.733304 -469.020022) (xy 91.542875 -469.030069)
			(xy 91.352192 -469.032079) (xy 91.161593 -469.026049) (xy 90.971419 -469.01199) (xy 90.782006 -468.989925)
			(xy 90.593691 -468.959896) (xy 90.40681 -468.921954) (xy 90.221694 -468.876168) (xy 90.038674 -468.822619)
			(xy 89.858073 -468.761401) (xy 89.680214 -468.692625) (xy 89.505412 -468.616412) (xy 89.333978 -468.532898)
			(xy 89.166218 -468.442231) (xy 89.002429 -468.344572) (xy 88.842902 -468.240095) (xy 88.687921 -468.128986)
			(xy 88.537763 -468.011443) (xy 88.392693 -467.887673) (xy 88.252969 -467.757898) (xy 88.118841 -467.622349)
			(xy 87.990547 -467.481265) (xy 87.868313 -467.334898) (xy 87.752359 -467.183509) (xy 87.64289 -467.027366)
			(xy 87.540101 -466.866747) (xy 87.444175 -466.701937) (xy 87.355281 -466.53323) (xy 87.273579 -466.360925)
			(xy 87.199213 -466.18533) (xy 87.132315 -466.006755) (xy 87.073005 -465.825519) (xy 87.021388 -465.641944)
			(xy 86.977556 -465.456356) (xy 86.941587 -465.269086) (xy 86.913544 -465.080465) (xy 86.893478 -464.89083)
			(xy 86.881424 -464.700517) (xy 86.877404 -464.509866) (xy 0.509016 -464.509866) (xy 0.509016 -471.172032)
			(xy 6.671831 -471.172032) (xy 6.675786 -471.080195) (xy 6.687621 -470.989038) (xy 6.707248 -470.899235)
			(xy 6.734522 -470.811453) (xy 6.769242 -470.726339) (xy 6.81115 -470.644526) (xy 6.859936 -470.566618)
			(xy 6.915239 -470.493193) (xy 6.976649 -470.424793) (xy 7.043711 -470.361926) (xy 7.11593 -470.305056)
			(xy 7.19277 -470.254605) (xy 7.273663 -470.210946) (xy 7.358009 -470.174403) (xy 7.445185 -470.145246)
			(xy 7.534544 -470.123692) (xy 7.625425 -470.109898) (xy 7.717156 -470.103968) (xy 7.809057 -470.105946)
			(xy 7.900448 -470.115817) (xy 7.990652 -470.133507) (xy 8.079001 -470.158887) (xy 8.164841 -470.191767)
			(xy 8.247537 -470.231905) (xy 8.326477 -470.279004) (xy 8.401075 -470.332714) (xy 8.470781 -470.392638)
			(xy 8.535076 -470.458332) (xy 8.593487 -470.52931) (xy 8.645579 -470.605047) (xy 8.690968 -470.684982)
			(xy 8.729318 -470.768522) (xy 8.760343 -470.85505) (xy 8.783816 -470.943925) (xy 8.799562 -471.034489)
			(xy 8.807464 -471.126071) (xy 8.807958 -471.172032) (xy 8.807464 -471.217993) (xy 8.799562 -471.309575)
			(xy 8.783816 -471.400139) (xy 8.760343 -471.489014) (xy 8.729318 -471.575542) (xy 8.690968 -471.659082)
			(xy 8.645579 -471.739017) (xy 8.593487 -471.814754) (xy 8.535076 -471.885732) (xy 8.470781 -471.951426)
			(xy 8.401075 -472.01135) (xy 8.326477 -472.06506) (xy 8.247537 -472.112159) (xy 8.164841 -472.152297)
			(xy 8.079001 -472.185177) (xy 7.990652 -472.210557) (xy 7.900448 -472.228247) (xy 7.809057 -472.238118)
			(xy 7.717156 -472.240096) (xy 7.625425 -472.234166) (xy 7.534544 -472.220372) (xy 7.445185 -472.198818)
			(xy 7.358009 -472.169661) (xy 7.273663 -472.133118) (xy 7.19277 -472.089459) (xy 7.11593 -472.039008)
			(xy 7.043711 -471.982138) (xy 6.976649 -471.919271) (xy 6.915239 -471.850871) (xy 6.859936 -471.777446)
			(xy 6.81115 -471.699538) (xy 6.769242 -471.617725) (xy 6.734522 -471.532611) (xy 6.707248 -471.444829)
			(xy 6.687621 -471.355026) (xy 6.675786 -471.263869) (xy 6.671831 -471.172032) (xy 0.509016 -471.172032)
			(xy 0.509016 -473.69984) (xy 14.086591 -473.69984) (xy 14.090616 -473.557648) (xy 14.102679 -473.415912)
			(xy 14.122742 -473.275086) (xy 14.15074 -473.13562) (xy 14.186584 -472.997961) (xy 14.230158 -472.862551)
			(xy 14.281323 -472.729823) (xy 14.339916 -472.600202) (xy 14.405747 -472.474104) (xy 14.478608 -472.351932)
			(xy 14.558263 -472.234078) (xy 14.644459 -472.120919) (xy 14.736918 -472.012817) (xy 14.835346 -471.91012)
			(xy 14.939425 -471.813156) (xy 15.048824 -471.722236) (xy 15.163192 -471.63765) (xy 15.282161 -471.55967)
			(xy 15.405352 -471.488546) (xy 15.532369 -471.424505) (xy 15.662806 -471.367753) (xy 15.796245 -471.318471)
			(xy 15.932258 -471.276817) (xy 16.07041 -471.242925) (xy 16.210259 -471.216904) (xy 16.351355 -471.198836)
			(xy 16.493247 -471.188779) (xy 16.635482 -471.186766) (xy 16.777602 -471.192803) (xy 16.919153 -471.206871)
			(xy 17.059682 -471.228925) (xy 17.198737 -471.258894) (xy 17.335875 -471.296682) (xy 17.470655 -471.342168)
			(xy 17.602646 -471.395206) (xy 17.731425 -471.455627) (xy 17.856579 -471.523236) (xy 17.977707 -471.597818)
			(xy 18.094423 -471.679134) (xy 18.206351 -471.766922) (xy 18.313133 -471.860902) (xy 18.414427 -471.960772)
			(xy 18.509908 -472.066214) (xy 18.599272 -472.176888) (xy 18.68223 -472.292441) (xy 18.758519 -472.412502)
			(xy 18.827893 -472.536687) (xy 18.89013 -472.664598) (xy 18.945031 -472.795825) (xy 18.992419 -472.929948)
			(xy 19.032144 -473.066537) (xy 19.064077 -473.205155) (xy 19.088118 -473.345357) (xy 19.104187 -473.486695)
			(xy 19.112235 -473.628716) (xy 19.112738 -473.69984) (xy 19.112235 -473.770964) (xy 19.104187 -473.912985)
			(xy 19.088118 -474.054323) (xy 19.064077 -474.194525) (xy 19.032144 -474.333143) (xy 18.992419 -474.469732)
			(xy 18.945031 -474.603855) (xy 18.89013 -474.735082) (xy 18.827893 -474.862993) (xy 18.758519 -474.987178)
			(xy 18.68223 -475.107239) (xy 18.599272 -475.222792) (xy 18.509908 -475.333466) (xy 18.414427 -475.438908)
			(xy 18.313133 -475.538778) (xy 18.206351 -475.632758) (xy 18.094423 -475.720546) (xy 17.977707 -475.801862)
			(xy 17.856579 -475.876444) (xy 17.731425 -475.944053) (xy 17.602646 -476.004474) (xy 17.470655 -476.057512)
			(xy 17.335875 -476.102998) (xy 17.198737 -476.140786) (xy 17.059682 -476.170755) (xy 16.919153 -476.192809)
			(xy 16.777602 -476.206877) (xy 16.635482 -476.212914) (xy 16.493247 -476.210901) (xy 16.351355 -476.200844)
			(xy 16.210259 -476.182776) (xy 16.07041 -476.156755) (xy 15.932258 -476.122863) (xy 15.796245 -476.081209)
			(xy 15.662806 -476.031927) (xy 15.532369 -475.975175) (xy 15.405352 -475.911134) (xy 15.282161 -475.84001)
			(xy 15.163192 -475.76203) (xy 15.048824 -475.677444) (xy 14.939425 -475.586524) (xy 14.835346 -475.48956)
			(xy 14.736918 -475.386863) (xy 14.644459 -475.278761) (xy 14.558263 -475.165602) (xy 14.478608 -475.047748)
			(xy 14.405747 -474.925576) (xy 14.339916 -474.799478) (xy 14.281323 -474.669857) (xy 14.230158 -474.537129)
			(xy 14.186584 -474.401719) (xy 14.15074 -474.26406) (xy 14.122742 -474.124594) (xy 14.102679 -473.983768)
			(xy 14.090616 -473.842032) (xy 14.086591 -473.69984) (xy 0.509016 -473.69984) (xy 0.509016 -477.804734)
			(xy 74.887582 -477.804734) (xy 74.888063 -477.725879) (xy 74.896049 -477.56837) (xy 74.912003 -477.411469)
			(xy 74.935883 -477.255577) (xy 74.967629 -477.101094) (xy 75.007158 -476.948418) (xy 75.05437 -476.79794)
			(xy 75.109143 -476.650046) (xy 75.171337 -476.505116) (xy 75.240791 -476.363523) (xy 75.317328 -476.225629)
			(xy 75.400751 -476.091789) (xy 75.490846 -475.962345) (xy 75.587381 -475.837632) (xy 75.69011 -475.717967)
			(xy 75.798767 -475.60366) (xy 75.913075 -475.495003) (xy 76.032739 -475.392275) (xy 76.157453 -475.29574)
			(xy 76.286897 -475.205645) (xy 76.420738 -475.122223) (xy 76.558632 -475.045686) (xy 76.700225 -474.976233)
			(xy 76.845155 -474.91404) (xy 76.993049 -474.859267) (xy 77.143528 -474.812056) (xy 77.296204 -474.772527)
			(xy 77.450687 -474.740781) (xy 77.606579 -474.716902) (xy 77.76348 -474.700948) (xy 77.920989 -474.692962)
			(xy 77.999844 -474.692472) (xy 77.999844 -474.692726) (xy 78.078692 -474.693217) (xy 78.236187 -474.701205)
			(xy 78.393074 -474.717159) (xy 78.548952 -474.741039) (xy 78.703421 -474.772783) (xy 78.856084 -474.81231)
			(xy 79.006548 -474.859519) (xy 79.154429 -474.914288) (xy 79.299345 -474.976477) (xy 79.440926 -475.045926)
			(xy 79.578807 -475.122457) (xy 79.712636 -475.205873) (xy 79.842067 -475.29596) (xy 79.96677 -475.392487)
			(xy 80.086424 -475.495207) (xy 80.200721 -475.603855) (xy 80.309368 -475.718152) (xy 80.412088 -475.837806)
			(xy 80.508615 -475.962509) (xy 80.598702 -476.091941) (xy 80.682117 -476.225769) (xy 80.758648 -476.363651)
			(xy 80.828096 -476.505232) (xy 80.890285 -476.650149) (xy 80.945053 -476.798029) (xy 80.992262 -476.948494)
			(xy 81.031789 -477.101157) (xy 81.063533 -477.255625) (xy 81.087412 -477.411504) (xy 81.103366 -477.568391)
			(xy 81.111353 -477.725886) (xy 81.111852 -477.804734) (xy 81.111852 -478.795334) (xy 81.111342 -478.874182)
			(xy 81.103353 -479.031675) (xy 81.087398 -479.188562) (xy 81.063517 -479.344439) (xy 81.031772 -479.498906)
			(xy 80.992244 -479.651567) (xy 80.945035 -479.802031) (xy 80.890265 -479.94991) (xy 80.828077 -480.094826)
			(xy 80.758628 -480.236405) (xy 80.682097 -480.374286) (xy 80.598682 -480.508113) (xy 80.508595 -480.637544)
			(xy 80.412068 -480.762246) (xy 80.30935 -480.881899) (xy 80.200703 -480.996196) (xy 80.086406 -481.104843)
			(xy 79.966754 -481.207562) (xy 79.842052 -481.304089) (xy 79.712621 -481.394176) (xy 79.578794 -481.477592)
			(xy 79.440914 -481.554123) (xy 79.299335 -481.623572) (xy 79.154419 -481.685762) (xy 79.00654 -481.740531)
			(xy 78.856077 -481.787741) (xy 78.703416 -481.82727) (xy 78.548948 -481.859015) (xy 78.393072 -481.882896)
			(xy 78.236185 -481.898852) (xy 78.078692 -481.906842) (xy 77.999844 -481.907342) (xy 77.920996 -481.906835)
			(xy 77.763502 -481.898848) (xy 77.606615 -481.882894) (xy 77.450737 -481.859015) (xy 77.296268 -481.827271)
			(xy 77.143606 -481.787744) (xy 76.993142 -481.740536) (xy 76.845262 -481.685767) (xy 76.700345 -481.623579)
			(xy 76.558765 -481.554131) (xy 76.420884 -481.4776) (xy 76.287055 -481.394185) (xy 76.157624 -481.304098)
			(xy 76.032921 -481.207571) (xy 75.913268 -481.104853) (xy 75.79897 -480.996205) (xy 75.690323 -480.881908)
			(xy 75.587604 -480.762255) (xy 75.491077 -480.637553) (xy 75.40099 -480.508121) (xy 75.317574 -480.374293)
			(xy 75.241043 -480.236412) (xy 75.171594 -480.094832) (xy 75.109406 -479.949916) (xy 75.054637 -479.802036)
			(xy 75.007428 -479.651571) (xy 74.967901 -479.498909) (xy 74.936157 -479.344441) (xy 74.912277 -479.188563)
			(xy 74.896323 -479.031676) (xy 74.888335 -478.874182) (xy 74.887836 -478.795334) (xy 74.887582 -477.804734)
			(xy 0.509016 -477.804734) (xy 0.509016 -480.172014) (xy 6.671831 -480.172014) (xy 6.675786 -480.080177)
			(xy 6.687621 -479.98902) (xy 6.707248 -479.899217) (xy 6.734522 -479.811435) (xy 6.769242 -479.726321)
			(xy 6.81115 -479.644508) (xy 6.859936 -479.5666) (xy 6.915239 -479.493175) (xy 6.976649 -479.424775)
			(xy 7.043711 -479.361908) (xy 7.11593 -479.305038) (xy 7.19277 -479.254587) (xy 7.273663 -479.210928)
			(xy 7.358009 -479.174385) (xy 7.445185 -479.145228) (xy 7.534544 -479.123674) (xy 7.625425 -479.10988)
			(xy 7.717156 -479.10395) (xy 7.809057 -479.105928) (xy 7.900448 -479.115799) (xy 7.990652 -479.133489)
			(xy 8.079001 -479.158869) (xy 8.164841 -479.191749) (xy 8.247537 -479.231887) (xy 8.326477 -479.278986)
			(xy 8.401075 -479.332696) (xy 8.470781 -479.39262) (xy 8.535076 -479.458314) (xy 8.593487 -479.529292)
			(xy 8.645579 -479.605029) (xy 8.690968 -479.684964) (xy 8.729318 -479.768504) (xy 8.760343 -479.855032)
			(xy 8.783816 -479.943907) (xy 8.799562 -480.034471) (xy 8.807464 -480.126053) (xy 8.807958 -480.172014)
			(xy 8.807464 -480.217975) (xy 8.799562 -480.309557) (xy 8.783816 -480.400121) (xy 8.760343 -480.488996)
			(xy 8.729318 -480.575524) (xy 8.690968 -480.659064) (xy 8.645579 -480.738999) (xy 8.593487 -480.814736)
			(xy 8.535076 -480.885714) (xy 8.470781 -480.951408) (xy 8.401075 -481.011332) (xy 8.326477 -481.065042)
			(xy 8.247537 -481.112141) (xy 8.164841 -481.152279) (xy 8.079001 -481.185159) (xy 7.990652 -481.210539)
			(xy 7.900448 -481.228229) (xy 7.809057 -481.2381) (xy 7.717156 -481.240078) (xy 7.625425 -481.234148)
			(xy 7.534544 -481.220354) (xy 7.445185 -481.1988) (xy 7.358009 -481.169643) (xy 7.273663 -481.1331)
			(xy 7.19277 -481.089441) (xy 7.11593 -481.03899) (xy 7.043711 -480.98212) (xy 6.976649 -480.919253)
			(xy 6.915239 -480.850853) (xy 6.859936 -480.777428) (xy 6.81115 -480.69952) (xy 6.769242 -480.617707)
			(xy 6.734522 -480.532593) (xy 6.707248 -480.444811) (xy 6.687621 -480.355008) (xy 6.675786 -480.263851)
			(xy 6.671831 -480.172014) (xy 0.509016 -480.172014) (xy 0.509016 -491.999778) (xy 6.671831 -491.999778)
			(xy 6.675786 -491.907941) (xy 6.687621 -491.816784) (xy 6.707248 -491.726981) (xy 6.734522 -491.639199)
			(xy 6.769242 -491.554085) (xy 6.81115 -491.472272) (xy 6.859936 -491.394364) (xy 6.915239 -491.320939)
			(xy 6.976649 -491.252539) (xy 7.043711 -491.189672) (xy 7.11593 -491.132802) (xy 7.19277 -491.082351)
			(xy 7.273663 -491.038692) (xy 7.358009 -491.002149) (xy 7.445185 -490.972992) (xy 7.534544 -490.951438)
			(xy 7.625425 -490.937644) (xy 7.717156 -490.931714) (xy 7.809057 -490.933692) (xy 7.900448 -490.943563)
			(xy 7.990652 -490.961253) (xy 8.079001 -490.986633) (xy 8.164841 -491.019513) (xy 8.247537 -491.059651)
			(xy 8.326477 -491.10675) (xy 8.401075 -491.16046) (xy 8.470781 -491.220384) (xy 8.535076 -491.286078)
			(xy 8.593487 -491.357056) (xy 8.645579 -491.432793) (xy 8.690968 -491.512728) (xy 8.729318 -491.596268)
			(xy 8.760343 -491.682796) (xy 8.783816 -491.771671) (xy 8.799562 -491.862235) (xy 8.807464 -491.953817)
			(xy 8.807958 -491.999778) (xy 8.807464 -492.045739) (xy 8.799562 -492.137321) (xy 8.783816 -492.227885)
			(xy 8.760343 -492.31676) (xy 8.729318 -492.403288) (xy 8.690968 -492.486828) (xy 8.645579 -492.566763)
			(xy 8.593487 -492.6425) (xy 8.535076 -492.713478) (xy 8.470781 -492.779172) (xy 8.401075 -492.839096)
			(xy 8.326477 -492.892806) (xy 8.247537 -492.939905) (xy 8.164841 -492.980043) (xy 8.079001 -493.012923)
			(xy 7.990652 -493.038303) (xy 7.900448 -493.055993) (xy 7.809057 -493.065864) (xy 7.717156 -493.067842)
			(xy 7.625425 -493.061912) (xy 7.534544 -493.048118) (xy 7.445185 -493.026564) (xy 7.358009 -492.997407)
			(xy 7.273663 -492.960864) (xy 7.19277 -492.917205) (xy 7.11593 -492.866754) (xy 7.043711 -492.809884)
			(xy 6.976649 -492.747017) (xy 6.915239 -492.678617) (xy 6.859936 -492.605192) (xy 6.81115 -492.527284)
			(xy 6.769242 -492.445471) (xy 6.734522 -492.360357) (xy 6.707248 -492.272575) (xy 6.687621 -492.182772)
			(xy 6.675786 -492.091615) (xy 6.671831 -491.999778) (xy 0.509016 -491.999778) (xy 0.509016 -495.86007)
			(xy 39.818564 -495.86007) (xy 39.819058 -495.802661) (xy 39.826902 -495.688113) (xy 39.842544 -495.574366)
			(xy 39.865911 -495.461952) (xy 39.896896 -495.351394) (xy 39.935352 -495.243209) (xy 39.981101 -495.1379)
			(xy 40.03393 -495.035958) (xy 40.093592 -494.937859) (xy 40.159809 -494.84406) (xy 40.232272 -494.754998)
			(xy 40.310645 -494.671089) (xy 40.39456 -494.592723) (xy 40.483627 -494.520266) (xy 40.577431 -494.454056)
			(xy 40.675535 -494.394402) (xy 40.777481 -494.341581) (xy 40.882793 -494.295839) (xy 40.990981 -494.257391)
			(xy 41.101541 -494.226415) (xy 41.213957 -494.203056) (xy 41.327705 -494.187423) (xy 41.442254 -494.179588)
			(xy 41.557072 -494.179588) (xy 41.671621 -494.187423) (xy 41.785369 -494.203056) (xy 41.897785 -494.226415)
			(xy 42.008345 -494.257391) (xy 42.116533 -494.295839) (xy 42.221845 -494.341581) (xy 42.323791 -494.394402)
			(xy 42.421895 -494.454056) (xy 42.515699 -494.520266) (xy 42.604766 -494.592723) (xy 42.688681 -494.671089)
			(xy 42.767054 -494.754998) (xy 42.839517 -494.84406) (xy 42.905734 -494.937859) (xy 42.965396 -495.035958)
			(xy 43.018225 -495.1379) (xy 43.063974 -495.243209) (xy 43.10243 -495.351394) (xy 43.133415 -495.461952)
			(xy 43.156782 -495.574366) (xy 43.172424 -495.688113) (xy 43.180268 -495.802661) (xy 43.180762 -495.86007)
			(xy 43.180576 -495.893253) (xy 43.177909 -495.959567) (xy 43.175428 -495.992658) (xy 43.170272 -496.050942)
			(xy 43.152948 -496.166671) (xy 43.127616 -496.280914) (xy 43.094401 -496.393119) (xy 43.053462 -496.502742)
			(xy 43.004999 -496.609253) (xy 42.949245 -496.712135) (xy 42.886471 -496.810891) (xy 42.816981 -496.905042)
			(xy 42.741111 -496.994132) (xy 42.659229 -497.077729) (xy 42.571732 -497.15543) (xy 42.500813 -497.21008)
			(xy 93.154506 -497.21008) (xy 93.158522 -497.09381) (xy 93.170549 -496.978095) (xy 93.190531 -496.863485)
			(xy 93.218373 -496.750526) (xy 93.253942 -496.639758) (xy 93.297068 -496.531707) (xy 93.347545 -496.426889)
			(xy 93.405134 -496.325804) (xy 93.46956 -496.228932) (xy 93.540515 -496.136736) (xy 93.617662 -496.049655)
			(xy 93.700633 -495.968104) (xy 93.789033 -495.892472) (xy 93.88244 -495.823118) (xy 93.980409 -495.760375)
			(xy 94.082473 -495.704539) (xy 94.188147 -495.655878) (xy 94.296926 -495.614624) (xy 94.408291 -495.580973)
			(xy 94.521714 -495.555085) (xy 94.636651 -495.537084) (xy 94.752557 -495.527055) (xy 94.868879 -495.525047)
			(xy 94.985062 -495.531069) (xy 95.100553 -495.545092) (xy 95.214801 -495.56705) (xy 95.327262 -495.596837)
			(xy 95.4374 -495.634312) (xy 95.54469 -495.679297) (xy 95.648621 -495.731576) (xy 95.748697 -495.790901)
			(xy 95.844443 -495.856989) (xy 95.9354 -495.929525) (xy 96.021136 -496.008164) (xy 96.101243 -496.09253)
			(xy 96.175339 -496.182222) (xy 96.243069 -496.276812) (xy 96.304113 -496.37585) (xy 96.358178 -496.478863)
			(xy 96.405008 -496.58536) (xy 96.444379 -496.694835) (xy 96.476103 -496.806765) (xy 96.500029 -496.920617)
			(xy 96.516043 -497.035849) (xy 96.52407 -497.151911) (xy 96.524572 -497.21008) (xy 96.52407 -497.268249)
			(xy 96.516043 -497.384311) (xy 96.500029 -497.499543) (xy 96.476103 -497.613395) (xy 96.444379 -497.725325)
			(xy 96.405008 -497.8348) (xy 96.358178 -497.941297) (xy 96.304113 -498.04431) (xy 96.243069 -498.143348)
			(xy 96.175339 -498.237938) (xy 96.101243 -498.32763) (xy 96.021136 -498.411996) (xy 95.9354 -498.490635)
			(xy 95.844443 -498.563171) (xy 95.748697 -498.629259) (xy 95.648621 -498.688584) (xy 95.54469 -498.740863)
			(xy 95.4374 -498.785848) (xy 95.327262 -498.823323) (xy 95.214801 -498.85311) (xy 95.100553 -498.875068)
			(xy 94.985062 -498.889091) (xy 94.868879 -498.895113) (xy 94.752557 -498.893105) (xy 94.636651 -498.883076)
			(xy 94.521714 -498.865075) (xy 94.408291 -498.839187) (xy 94.296926 -498.805536) (xy 94.188147 -498.764282)
			(xy 94.082473 -498.715621) (xy 93.980409 -498.659785) (xy 93.88244 -498.597042) (xy 93.789033 -498.527688)
			(xy 93.700633 -498.452056) (xy 93.617662 -498.370505) (xy 93.540515 -498.283424) (xy 93.46956 -498.191228)
			(xy 93.405134 -498.094356) (xy 93.347545 -497.993271) (xy 93.297068 -497.888453) (xy 93.253942 -497.780402)
			(xy 93.218373 -497.669634) (xy 93.190531 -497.556675) (xy 93.170549 -497.442065) (xy 93.158522 -497.32635)
			(xy 93.154506 -497.21008) (xy 42.500813 -497.21008) (xy 42.479042 -497.226857) (xy 42.381609 -497.291665)
			(xy 42.279905 -497.34954) (xy 42.174422 -497.400202) (xy 42.065671 -497.443404) (xy 41.954179 -497.478939)
			(xy 41.840485 -497.506634) (xy 41.725141 -497.526354) (xy 41.608704 -497.538005) (xy 41.491739 -497.54153)
			(xy 41.374812 -497.536912) (xy 41.258489 -497.524173) (xy 41.143334 -497.503375) (xy 41.029905 -497.474618)
			(xy 40.91875 -497.438042) (xy 40.810407 -497.393825) (xy 40.705403 -497.342179) (xy 40.604244 -497.283356)
			(xy 40.507421 -497.21764) (xy 40.415403 -497.145349) (xy 40.328636 -497.066834) (xy 40.247539 -496.982474)
			(xy 40.172506 -496.892679) (xy 40.103899 -496.797883) (xy 40.042051 -496.698544) (xy 39.987262 -496.595145)
			(xy 39.939796 -496.488186) (xy 39.899884 -496.378185) (xy 39.86772 -496.265674) (xy 39.843457 -496.151199)
			(xy 39.827215 -496.035313) (xy 39.819072 -495.918579) (xy 39.818564 -495.86007) (xy 0.509016 -495.86007)
			(xy 0.509016 -500.99976) (xy 6.671831 -500.99976) (xy 6.675786 -500.907923) (xy 6.687621 -500.816766)
			(xy 6.707248 -500.726963) (xy 6.734522 -500.639181) (xy 6.769242 -500.554067) (xy 6.81115 -500.472254)
			(xy 6.859936 -500.394346) (xy 6.915239 -500.320921) (xy 6.976649 -500.252521) (xy 7.043711 -500.189654)
			(xy 7.11593 -500.132784) (xy 7.19277 -500.082333) (xy 7.273663 -500.038674) (xy 7.358009 -500.002131)
			(xy 7.445185 -499.972974) (xy 7.534544 -499.95142) (xy 7.625425 -499.937626) (xy 7.717156 -499.931696)
			(xy 7.809057 -499.933674) (xy 7.900448 -499.943545) (xy 7.990652 -499.961235) (xy 8.079001 -499.986615)
			(xy 8.164841 -500.019495) (xy 8.247537 -500.059633) (xy 8.326477 -500.106732) (xy 8.401075 -500.160442)
			(xy 8.470781 -500.220366) (xy 8.535076 -500.28606) (xy 8.593487 -500.357038) (xy 8.645579 -500.432775)
			(xy 8.690968 -500.51271) (xy 8.729318 -500.59625) (xy 8.760343 -500.682778) (xy 8.783816 -500.771653)
			(xy 8.799562 -500.862217) (xy 8.807464 -500.953799) (xy 8.807958 -500.99976) (xy 8.807464 -501.045721)
			(xy 8.799562 -501.137303) (xy 8.783816 -501.227867) (xy 8.760343 -501.316742) (xy 8.729318 -501.40327)
			(xy 8.690968 -501.48681) (xy 8.645579 -501.566745) (xy 8.593487 -501.642482) (xy 8.535076 -501.71346)
			(xy 8.470781 -501.779154) (xy 8.401075 -501.839078) (xy 8.326477 -501.892788) (xy 8.247537 -501.939887)
			(xy 8.164841 -501.980025) (xy 8.079001 -502.012905) (xy 7.990652 -502.038285) (xy 7.900448 -502.055975)
			(xy 7.809057 -502.065846) (xy 7.717156 -502.067824) (xy 7.625425 -502.061894) (xy 7.534544 -502.0481)
			(xy 7.445185 -502.026546) (xy 7.358009 -501.997389) (xy 7.273663 -501.960846) (xy 7.19277 -501.917187)
			(xy 7.11593 -501.866736) (xy 7.043711 -501.809866) (xy 6.976649 -501.746999) (xy 6.915239 -501.678599)
			(xy 6.859936 -501.605174) (xy 6.81115 -501.527266) (xy 6.769242 -501.445453) (xy 6.734522 -501.360339)
			(xy 6.707248 -501.272557) (xy 6.687621 -501.182754) (xy 6.675786 -501.091597) (xy 6.671831 -500.99976)
			(xy 0.509016 -500.99976) (xy 0.509016 -508.96012) (xy 86.877404 -508.96012) (xy 86.881424 -508.769469)
			(xy 86.893478 -508.579156) (xy 86.913544 -508.389521) (xy 86.941587 -508.2009) (xy 86.977556 -508.01363)
			(xy 87.021388 -507.828042) (xy 87.073005 -507.644467) (xy 87.132315 -507.463231) (xy 87.199213 -507.284656)
			(xy 87.273579 -507.109061) (xy 87.355281 -506.936756) (xy 87.444175 -506.768049) (xy 87.540101 -506.603239)
			(xy 87.64289 -506.44262) (xy 87.752359 -506.286477) (xy 87.868313 -506.135088) (xy 87.990547 -505.988721)
			(xy 88.118841 -505.847637) (xy 88.252969 -505.712088) (xy 88.392693 -505.582313) (xy 88.537763 -505.458543)
			(xy 88.687921 -505.341) (xy 88.842902 -505.229891) (xy 89.002429 -505.125414) (xy 89.166218 -505.027755)
			(xy 89.333978 -504.937088) (xy 89.505412 -504.853574) (xy 89.680214 -504.777361) (xy 89.858073 -504.708585)
			(xy 90.038674 -504.647367) (xy 90.221694 -504.593818) (xy 90.40681 -504.548032) (xy 90.593691 -504.51009)
			(xy 90.782006 -504.480061) (xy 90.971419 -504.457996) (xy 91.161593 -504.443937) (xy 91.352192 -504.437907)
			(xy 91.542875 -504.439917) (xy 91.733304 -504.449964) (xy 91.92314 -504.46803) (xy 92.112046 -504.494083)
			(xy 92.299685 -504.528076) (xy 92.485725 -504.569949) (xy 92.669834 -504.619628) (xy 92.851685 -504.677024)
			(xy 93.030955 -504.742035) (xy 93.207325 -504.814546) (xy 93.380481 -504.894427) (xy 93.550116 -504.981537)
			(xy 93.715928 -505.075721) (xy 93.877622 -505.176812) (xy 94.03491 -505.284628) (xy 94.187513 -505.39898)
			(xy 94.335161 -505.519663) (xy 94.477589 -505.646464) (xy 94.614545 -505.779155) (xy 94.745786 -505.917503)
			(xy 94.871078 -506.06126) (xy 94.990198 -506.210171) (xy 95.102934 -506.363972) (xy 95.209087 -506.522388)
			(xy 95.308467 -506.685139) (xy 95.400897 -506.851934) (xy 95.486214 -507.022478) (xy 95.564266 -507.196466)
			(xy 95.634913 -507.373591) (xy 95.698031 -507.553536) (xy 95.753507 -507.735982) (xy 95.801242 -507.920605)
			(xy 95.841152 -508.107075) (xy 95.873165 -508.295063) (xy 95.897225 -508.484233) (xy 95.913288 -508.674249)
			(xy 95.921327 -508.864773) (xy 95.92183 -508.96012) (xy 95.921327 -509.055467) (xy 95.913288 -509.245991)
			(xy 95.897225 -509.436007) (xy 95.873165 -509.625177) (xy 95.841152 -509.813165) (xy 95.801242 -509.999635)
			(xy 95.753507 -510.184258) (xy 95.698031 -510.366704) (xy 95.634913 -510.546649) (xy 95.564266 -510.723774)
			(xy 95.486214 -510.897762) (xy 95.400897 -511.068306) (xy 95.308467 -511.235101) (xy 95.209087 -511.397852)
			(xy 95.102934 -511.556268) (xy 94.990198 -511.710069) (xy 94.871078 -511.85898) (xy 94.745786 -512.002737)
			(xy 94.614545 -512.141085) (xy 94.477589 -512.273776) (xy 94.335161 -512.400577) (xy 94.187513 -512.52126)
			(xy 94.03491 -512.635612) (xy 93.877622 -512.743428) (xy 93.715928 -512.844519) (xy 93.550116 -512.938703)
			(xy 93.380481 -513.025813) (xy 93.207325 -513.105694) (xy 93.030955 -513.178205) (xy 92.851685 -513.243216)
			(xy 92.669834 -513.300612) (xy 92.485725 -513.350291) (xy 92.299685 -513.392164) (xy 92.112046 -513.426157)
			(xy 91.92314 -513.45221) (xy 91.733304 -513.470276) (xy 91.542875 -513.480323) (xy 91.352192 -513.482333)
			(xy 91.161593 -513.476303) (xy 90.971419 -513.462244) (xy 90.782006 -513.440179) (xy 90.593691 -513.41015)
			(xy 90.40681 -513.372208) (xy 90.221694 -513.326422) (xy 90.038674 -513.272873) (xy 89.858073 -513.211655)
			(xy 89.680214 -513.142879) (xy 89.505412 -513.066666) (xy 89.333978 -512.983152) (xy 89.166218 -512.892485)
			(xy 89.002429 -512.794826) (xy 88.842902 -512.690349) (xy 88.687921 -512.57924) (xy 88.537763 -512.461697)
			(xy 88.392693 -512.337927) (xy 88.252969 -512.208152) (xy 88.118841 -512.072603) (xy 87.990547 -511.931519)
			(xy 87.868313 -511.785152) (xy 87.752359 -511.633763) (xy 87.64289 -511.47762) (xy 87.540101 -511.317001)
			(xy 87.444175 -511.152191) (xy 87.355281 -510.983484) (xy 87.273579 -510.811179) (xy 87.199213 -510.635584)
			(xy 87.132315 -510.457009) (xy 87.073005 -510.275773) (xy 87.021388 -510.092198) (xy 86.977556 -509.90661)
			(xy 86.941587 -509.71934) (xy 86.913544 -509.530719) (xy 86.893478 -509.341084) (xy 86.881424 -509.150771)
			(xy 86.877404 -508.96012) (xy 0.509016 -508.96012) (xy 0.509016 -511.049778) (xy 6.671831 -511.049778)
			(xy 6.675786 -510.957941) (xy 6.687621 -510.866784) (xy 6.707248 -510.776981) (xy 6.734522 -510.689199)
			(xy 6.769242 -510.604085) (xy 6.81115 -510.522272) (xy 6.859936 -510.444364) (xy 6.915239 -510.370939)
			(xy 6.976649 -510.302539) (xy 7.043711 -510.239672) (xy 7.11593 -510.182802) (xy 7.19277 -510.132351)
			(xy 7.273663 -510.088692) (xy 7.358009 -510.052149) (xy 7.445185 -510.022992) (xy 7.534544 -510.001438)
			(xy 7.625425 -509.987644) (xy 7.717156 -509.981714) (xy 7.809057 -509.983692) (xy 7.900448 -509.993563)
			(xy 7.990652 -510.011253) (xy 8.079001 -510.036633) (xy 8.164841 -510.069513) (xy 8.247537 -510.109651)
			(xy 8.326477 -510.15675) (xy 8.401075 -510.21046) (xy 8.470781 -510.270384) (xy 8.535076 -510.336078)
			(xy 8.593487 -510.407056) (xy 8.645579 -510.482793) (xy 8.690968 -510.562728) (xy 8.729318 -510.646268)
			(xy 8.760343 -510.732796) (xy 8.783816 -510.821671) (xy 8.799562 -510.912235) (xy 8.807464 -511.003817)
			(xy 8.807958 -511.049778) (xy 8.807464 -511.095739) (xy 8.799562 -511.187321) (xy 8.783816 -511.277885)
			(xy 8.760343 -511.36676) (xy 8.729318 -511.453288) (xy 8.690968 -511.536828) (xy 8.645579 -511.616763)
			(xy 8.593487 -511.6925) (xy 8.535076 -511.763478) (xy 8.470781 -511.829172) (xy 8.401075 -511.889096)
			(xy 8.326477 -511.942806) (xy 8.247537 -511.989905) (xy 8.164841 -512.030043) (xy 8.079001 -512.062923)
			(xy 7.990652 -512.088303) (xy 7.900448 -512.105993) (xy 7.809057 -512.115864) (xy 7.717156 -512.117842)
			(xy 7.625425 -512.111912) (xy 7.534544 -512.098118) (xy 7.445185 -512.076564) (xy 7.358009 -512.047407)
			(xy 7.273663 -512.010864) (xy 7.19277 -511.967205) (xy 7.11593 -511.916754) (xy 7.043711 -511.859884)
			(xy 6.976649 -511.797017) (xy 6.915239 -511.728617) (xy 6.859936 -511.655192) (xy 6.81115 -511.577284)
			(xy 6.769242 -511.495471) (xy 6.734522 -511.410357) (xy 6.707248 -511.322575) (xy 6.687621 -511.232772)
			(xy 6.675786 -511.141615) (xy 6.671831 -511.049778) (xy 0.509016 -511.049778) (xy 0.509016 -520.04976)
			(xy 6.671831 -520.04976) (xy 6.675786 -519.957923) (xy 6.687621 -519.866766) (xy 6.707248 -519.776963)
			(xy 6.734522 -519.689181) (xy 6.769242 -519.604067) (xy 6.81115 -519.522254) (xy 6.859936 -519.444346)
			(xy 6.915239 -519.370921) (xy 6.976649 -519.302521) (xy 7.043711 -519.239654) (xy 7.11593 -519.182784)
			(xy 7.19277 -519.132333) (xy 7.273663 -519.088674) (xy 7.358009 -519.052131) (xy 7.445185 -519.022974)
			(xy 7.534544 -519.00142) (xy 7.625425 -518.987626) (xy 7.717156 -518.981696) (xy 7.809057 -518.983674)
			(xy 7.900448 -518.993545) (xy 7.990652 -519.011235) (xy 8.079001 -519.036615) (xy 8.113324 -519.049762)
			(xy 75.486773 -519.049762) (xy 75.490798 -518.90757) (xy 75.502861 -518.765834) (xy 75.522924 -518.625008)
			(xy 75.550922 -518.485542) (xy 75.586766 -518.347883) (xy 75.63034 -518.212473) (xy 75.681505 -518.079745)
			(xy 75.740098 -517.950124) (xy 75.805929 -517.824026) (xy 75.87879 -517.701854) (xy 75.958445 -517.584)
			(xy 76.044641 -517.470841) (xy 76.1371 -517.362739) (xy 76.235528 -517.260042) (xy 76.339607 -517.163078)
			(xy 76.449006 -517.072158) (xy 76.563374 -516.987572) (xy 76.682343 -516.909592) (xy 76.805534 -516.838468)
			(xy 76.932551 -516.774427) (xy 77.062988 -516.717675) (xy 77.196427 -516.668393) (xy 77.33244 -516.626739)
			(xy 77.470592 -516.592847) (xy 77.610441 -516.566826) (xy 77.751537 -516.548758) (xy 77.893429 -516.538701)
			(xy 78.035664 -516.536688) (xy 78.177784 -516.542725) (xy 78.319335 -516.556793) (xy 78.459864 -516.578847)
			(xy 78.598919 -516.608816) (xy 78.736057 -516.646604) (xy 78.870837 -516.69209) (xy 79.002828 -516.745128)
			(xy 79.131607 -516.805549) (xy 79.256761 -516.873158) (xy 79.377889 -516.94774) (xy 79.494605 -517.029056)
			(xy 79.606533 -517.116844) (xy 79.713315 -517.210824) (xy 79.814609 -517.310694) (xy 79.91009 -517.416136)
			(xy 79.999454 -517.52681) (xy 80.082412 -517.642363) (xy 80.158701 -517.762424) (xy 80.228075 -517.886609)
			(xy 80.290312 -518.01452) (xy 80.345213 -518.145747) (xy 80.392601 -518.27987) (xy 80.432326 -518.416459)
			(xy 80.464259 -518.555077) (xy 80.4883 -518.695279) (xy 80.504369 -518.836617) (xy 80.512417 -518.978638)
			(xy 80.51292 -519.049762) (xy 80.512417 -519.120886) (xy 80.504369 -519.262907) (xy 80.4883 -519.404245)
			(xy 80.464259 -519.544447) (xy 80.432326 -519.683065) (xy 80.392601 -519.819654) (xy 80.345213 -519.953777)
			(xy 80.290312 -520.085004) (xy 80.228075 -520.212915) (xy 80.158701 -520.3371) (xy 80.082412 -520.457161)
			(xy 79.999454 -520.572714) (xy 79.91009 -520.683388) (xy 79.814609 -520.78883) (xy 79.713315 -520.8887)
			(xy 79.606533 -520.98268) (xy 79.494605 -521.070468) (xy 79.377889 -521.151784) (xy 79.256761 -521.226366)
			(xy 79.131607 -521.293975) (xy 79.002828 -521.354396) (xy 78.870837 -521.407434) (xy 78.736057 -521.45292)
			(xy 78.598919 -521.490708) (xy 78.459864 -521.520677) (xy 78.319335 -521.542731) (xy 78.177784 -521.556799)
			(xy 78.035664 -521.562836) (xy 77.893429 -521.560823) (xy 77.751537 -521.550766) (xy 77.610441 -521.532698)
			(xy 77.470592 -521.506677) (xy 77.33244 -521.472785) (xy 77.196427 -521.431131) (xy 77.062988 -521.381849)
			(xy 76.932551 -521.325097) (xy 76.805534 -521.261056) (xy 76.682343 -521.189932) (xy 76.563374 -521.111952)
			(xy 76.449006 -521.027366) (xy 76.339607 -520.936446) (xy 76.235528 -520.839482) (xy 76.1371 -520.736785)
			(xy 76.044641 -520.628683) (xy 75.958445 -520.515524) (xy 75.87879 -520.39767) (xy 75.805929 -520.275498)
			(xy 75.740098 -520.1494) (xy 75.681505 -520.019779) (xy 75.63034 -519.887051) (xy 75.586766 -519.751641)
			(xy 75.550922 -519.613982) (xy 75.522924 -519.474516) (xy 75.502861 -519.33369) (xy 75.490798 -519.191954)
			(xy 75.486773 -519.049762) (xy 8.113324 -519.049762) (xy 8.164841 -519.069495) (xy 8.247537 -519.109633)
			(xy 8.326477 -519.156732) (xy 8.401075 -519.210442) (xy 8.470781 -519.270366) (xy 8.535076 -519.33606)
			(xy 8.593487 -519.407038) (xy 8.645579 -519.482775) (xy 8.690968 -519.56271) (xy 8.729318 -519.64625)
			(xy 8.760343 -519.732778) (xy 8.783816 -519.821653) (xy 8.799562 -519.912217) (xy 8.807464 -520.003799)
			(xy 8.807958 -520.04976) (xy 8.807464 -520.095721) (xy 8.799562 -520.187303) (xy 8.783816 -520.277867)
			(xy 8.760343 -520.366742) (xy 8.729318 -520.45327) (xy 8.690968 -520.53681) (xy 8.645579 -520.616745)
			(xy 8.593487 -520.692482) (xy 8.535076 -520.76346) (xy 8.470781 -520.829154) (xy 8.401075 -520.889078)
			(xy 8.326477 -520.942788) (xy 8.247537 -520.989887) (xy 8.164841 -521.030025) (xy 8.079001 -521.062905)
			(xy 7.990652 -521.088285) (xy 7.900448 -521.105975) (xy 7.809057 -521.115846) (xy 7.717156 -521.117824)
			(xy 7.625425 -521.111894) (xy 7.534544 -521.0981) (xy 7.445185 -521.076546) (xy 7.358009 -521.047389)
			(xy 7.273663 -521.010846) (xy 7.19277 -520.967187) (xy 7.11593 -520.916736) (xy 7.043711 -520.859866)
			(xy 6.976649 -520.796999) (xy 6.915239 -520.728599) (xy 6.859936 -520.655174) (xy 6.81115 -520.577266)
			(xy 6.769242 -520.495453) (xy 6.734522 -520.410339) (xy 6.707248 -520.322557) (xy 6.687621 -520.232754)
			(xy 6.675786 -520.141597) (xy 6.671831 -520.04976) (xy 0.509016 -520.04976) (xy 0.509016 -524.500094)
			(xy 0.509529 -524.54588) (xy 0.517978 -524.637062) (xy 0.534804 -524.727075) (xy 0.559864 -524.815152)
			(xy 0.592944 -524.900541) (xy 0.633761 -524.982513) (xy 0.681968 -525.06037) (xy 0.737153 -525.133446)
			(xy 0.798845 -525.201119) (xy 0.866518 -525.262811) (xy 0.939594 -525.317996) (xy 1.017451 -525.366203)
			(xy 1.099423 -525.40702) (xy 1.184812 -525.4401) (xy 1.272889 -525.46516) (xy 1.362902 -525.481986)
			(xy 1.454084 -525.490435) (xy 1.49987 -525.490948) (xy 23.50008 -525.490948) (xy 23.563199 -525.491452)
			(xy 23.689186 -525.499396) (xy 23.814426 -525.515233) (xy 23.938425 -525.538903) (xy 24.060692 -525.570311)
			(xy 24.180747 -525.609334) (xy 24.298115 -525.655817) (xy 24.412333 -525.709578) (xy 24.52295 -525.770404)
			(xy 24.62953 -525.838054) (xy 24.731652 -525.912263) (xy 24.828913 -525.992737) (xy 24.920931 -526.079159)
			(xy 25.00734 -526.171188) (xy 25.087801 -526.26846) (xy 25.161996 -526.370592) (xy 25.229633 -526.477181)
			(xy 25.290444 -526.587806) (xy 25.344189 -526.702031) (xy 25.390657 -526.819405) (xy 25.429664 -526.939465)
			(xy 25.461055 -527.061737) (xy 25.484709 -527.185739) (xy 25.50053 -527.310981) (xy 25.508456 -527.436969)
			(xy 25.508966 -527.500088) (xy 25.508966 -528.500086) (xy 25.509507 -528.545875) (xy 25.517982 -528.637061)
			(xy 25.534832 -528.727076) (xy 25.559914 -528.815153) (xy 25.593014 -528.90054) (xy 25.633851 -528.98251)
			(xy 25.682074 -529.060363) (xy 25.737274 -529.133435) (xy 25.79898 -529.201104) (xy 25.866665 -529.262792)
			(xy 25.939752 -529.317973) (xy 26.017618 -529.366176) (xy 26.099598 -529.406991) (xy 26.184994 -529.440069)
			(xy 26.273077 -529.465128) (xy 26.363097 -529.481954) (xy 26.454285 -529.490405) (xy 26.500074 -529.49094)
		)
		(stroke
			(width 0)
			(type solid)
		)
		(fill yes)
		(layer "In1.Cu")
		(net "GND")
	)
	(gr_arc
		(start 1.500124 -3.999992)
		(mid 0.439376 -4.439368)
		(end 0 -5.500116)
		(stroke
			(width 1.016)
			(type default)
		)
		(layer "In1.Cu")
	)
	(gr_line
		(start 1.500124 -3.999992)
		(end 23.50008 -3.999992)
		(stroke
			(width 1.016)
			(type default)
		)
		(layer "In1.Cu")
	)
	(gr_line
		(start 23.50008 -525.999964)
		(end 1.500124 -525.999964)
		(stroke
			(width 1.016)
			(type default)
		)
		(layer "In1.Cu")
	)
	(gr_arc
		(start 23.50008 -3.999992)
		(mid 24.560648 -3.56069)
		(end 24.99995 -2.500122)
		(stroke
			(width 1.016)
			(type default)
		)
		(layer "In1.Cu")
	)
	(gr_line
		(start 24.99995 -528.500086)
		(end 24.99995 -527.500088)
		(stroke
			(width 1.016)
			(type default)
		)
		(layer "In1.Cu")
	)
	(gr_arc
		(start 24.99995 -528.500086)
		(mid 25.439426 -529.560658)
		(end 26.500074 -529.999956)
		(stroke
			(width 1.016)
			(type default)
		)
		(layer "In1.Cu")
	)
	(gr_arc
		(start 24.99995 -527.500088)
		(mid 24.560738 -526.439356)
		(end 23.50008 -525.999964)
		(stroke
			(width 1.016)
			(type default)
		)
		(layer "In1.Cu")
	)
	(gr_line
		(start 24.99995 -2.500122)
		(end 24.99995 -1.500124)
		(stroke
			(width 1.016)
			(type default)
		)
		(layer "In1.Cu")
	)
	(gr_arc
		(start 26.500074 0)
		(mid 25.439325 -0.439375)
		(end 24.99995 -1.500124)
		(stroke
			(width 1.016)
			(type default)
		)
		(layer "In1.Cu")
	)
	(gr_line
		(start 26.500074 0)
		(end 101.000052 0)
		(stroke
			(width 1.016)
			(type default)
		)
		(layer "In1.Cu")
	)
	(gr_line
		(start 101.000052 -529.999956)
		(end 26.500074 -529.999956)
		(stroke
			(width 1.016)
			(type default)
		)
		(layer "In1.Cu")
	)
	(gr_arc
		(start 101.000052 -529.999956)
		(mid 102.41428 -529.414185)
		(end 103.000048 -527.99996)
		(stroke
			(width 1.016)
			(type default)
		)
		(layer "In1.Cu")
	)
	(gr_arc
		(start 103.000048 -1.999996)
		(mid 102.414258 -0.585805)
		(end 101.000052 0)
		(stroke
			(width 1.016)
			(type default)
		)
		(layer "In1.Cu")
	)
	(gr_line
		(start 103.000048 -1.999996)
		(end 103.000048 -527.99996)
		(stroke
			(width 1.016)
			(type default)
		)
		(layer "In1.Cu")
	)
	(gr_poly
		(pts
			(xy 101.000052 -529.49094) (xy 101.055822 -529.490433) (xy 101.167051 -529.482101) (xy 101.277346 -529.46548)
			(xy 101.38609 -529.440662) (xy 101.492675 -529.407788) (xy 101.596506 -529.367039) (xy 101.697001 -529.318645)
			(xy 101.793598 -529.262876) (xy 101.885758 -529.200044) (xy 101.972964 -529.130501) (xy 102.054729 -529.054635)
			(xy 102.130596 -528.97287) (xy 102.20014 -528.885664) (xy 102.262972 -528.793505) (xy 102.318742 -528.696908)
			(xy 102.367136 -528.596413) (xy 102.407885 -528.492583) (xy 102.44076 -528.385998) (xy 102.465578 -528.277253)
			(xy 102.4822 -528.166959) (xy 102.490533 -528.05573) (xy 102.491032 -527.99996) (xy 102.491032 -1.999996)
			(xy 102.490523 -1.944227) (xy 102.482188 -1.833002) (xy 102.465563 -1.72271) (xy 102.440743 -1.613969)
			(xy 102.407866 -1.507387) (xy 102.367116 -1.40356) (xy 102.31872 -1.303069) (xy 102.26295 -1.206475)
			(xy 102.200118 -1.11432) (xy 102.130574 -1.027117) (xy 102.054708 -0.945356) (xy 101.972944 -0.869492)
			(xy 101.885739 -0.799951) (xy 101.793581 -0.737122) (xy 101.696985 -0.681355) (xy 101.596492 -0.632964)
			(xy 101.492664 -0.592217) (xy 101.386081 -0.559343) (xy 101.277339 -0.534527) (xy 101.167047 -0.517907)
			(xy 101.055821 -0.509575) (xy 101.000052 -0.509016) (xy 26.500074 -0.509016) (xy 26.454278 -0.509546)
			(xy 26.363077 -0.517999) (xy 26.273045 -0.534832) (xy 26.184949 -0.559899) (xy 26.099543 -0.592988)
			(xy 26.017554 -0.633817) (xy 25.939682 -0.682036) (xy 25.866592 -0.737234) (xy 25.798906 -0.798941)
			(xy 25.737202 -0.86663) (xy 25.682007 -0.939724) (xy 25.633792 -1.017598) (xy 25.592968 -1.099589)
			(xy 25.559883 -1.184997) (xy 25.53482 -1.273093) (xy 25.517992 -1.363126) (xy 25.509543 -1.454328)
			(xy 25.508966 -1.500124) (xy 25.508966 -2.500122) (xy 25.50847 -2.563238) (xy 25.500544 -2.689221)
			(xy 25.484723 -2.814458) (xy 25.461069 -2.938455) (xy 25.429676 -3.060721) (xy 25.390668 -3.180775)
			(xy 25.344199 -3.298143) (xy 25.290452 -3.412362) (xy 25.229639 -3.52298) (xy 25.162 -3.629561) (xy 25.087803 -3.731685)
			(xy 25.007339 -3.828949) (xy 24.920927 -3.920968) (xy 24.828907 -4.00738) (xy 24.731644 -4.087844)
			(xy 24.62952 -4.162041) (xy 24.522938 -4.22968) (xy 24.41232 -4.290493) (xy 24.298101 -4.34424) (xy 24.180733 -4.390709)
			(xy 24.060679 -4.429717) (xy 23.938413 -4.46111) (xy 23.814416 -4.484763) (xy 23.689179 -4.500584)
			(xy 23.563196 -4.50851) (xy 23.50008 -4.509008) (xy 1.500124 -4.509008) (xy 1.454327 -4.509537) (xy 1.363123 -4.517988)
			(xy 1.273088 -4.534819) (xy 1.18499 -4.559885) (xy 1.099581 -4.592972) (xy 1.017589 -4.6338) (xy 0.939714 -4.682018)
			(xy 0.86662 -4.737216) (xy 0.798931 -4.798923) (xy 0.737224 -4.866612) (xy 0.682026 -4.939706) (xy 0.633808 -5.017581)
			(xy 0.59298 -5.099573) (xy 0.559893 -5.184982) (xy 0.534827 -5.27308) (xy 0.517996 -5.363115) (xy 0.509545 -5.454319)
			(xy 0.509222 -5.482255) (xy 1.01507 -5.482255) (xy 1.021763 -5.417929) (xy 1.036946 -5.355063) (xy 1.06035 -5.294772)
			(xy 1.091558 -5.238126) (xy 1.130019 -5.186131) (xy 1.175048 -5.139708) (xy 1.225848 -5.099682) (xy 1.281516 -5.066762)
			(xy 1.341066 -5.041533) (xy 1.403441 -5.024442) (xy 1.467534 -5.015793) (xy 1.49987 -5.01523) (xy 1.500124 -5.01523)
			(xy 1.500124 -5.015484) (xy 23.266908 -5.015484) (xy 23.266908 -5.01523) (xy 23.50008 -5.01523) (xy 23.570631 -5.014727)
			(xy 23.711511 -5.006802) (xy 23.851725 -4.990991) (xy 23.990832 -4.967345) (xy 24.128395 -4.935937)
			(xy 24.26398 -4.896866) (xy 24.397162 -4.850255) (xy 24.527521 -4.796251) (xy 24.654648 -4.735024)
			(xy 24.778142 -4.666765) (xy 24.897614 -4.591691) (xy 25.01269 -4.510037) (xy 25.123008 -4.422059)
			(xy 25.228219 -4.328035) (xy 25.327994 -4.228261) (xy 25.422018 -4.123049) (xy 25.509995 -4.012732)
			(xy 25.59165 -3.897656) (xy 25.666724 -3.778183) (xy 25.734983 -3.654689) (xy 25.796211 -3.527563)
			(xy 25.850215 -3.397204) (xy 25.896826 -3.264022) (xy 25.935897 -3.128437) (xy 25.967305 -2.990874)
			(xy 25.990951 -2.851767) (xy 26.006762 -2.711553) (xy 26.014687 -2.570673) (xy 26.015188 -2.500122)
			(xy 26.015188 -1.500124) (xy 26.01562 -1.46838) (xy 26.023881 -1.405431) (xy 26.04029 -1.3441) (xy 26.064566 -1.285437)
			(xy 26.096294 -1.230445) (xy 26.13493 -1.180067) (xy 26.179813 -1.135165) (xy 26.230175 -1.096507)
			(xy 26.285154 -1.064756) (xy 26.343807 -1.040455) (xy 26.405131 -1.024021) (xy 26.468076 -1.015734)
			(xy 26.49982 -1.015238) (xy 26.500074 -1.015238) (xy 26.500074 -1.015492) (xy 101.000052 -1.015492)
			(xy 101.045544 -1.016051) (xy 101.13614 -1.024442) (xy 101.225575 -1.041156) (xy 101.313087 -1.066052)
			(xy 101.397928 -1.098916) (xy 101.479375 -1.139468) (xy 101.556732 -1.187362) (xy 101.629341 -1.24219)
			(xy 101.69658 -1.303483) (xy 101.757877 -1.370719) (xy 101.812709 -1.443325) (xy 101.860607 -1.52068)
			(xy 101.901163 -1.602124) (xy 101.934032 -1.686964) (xy 101.958932 -1.774474) (xy 101.975651 -1.863909)
			(xy 101.984046 -1.954504) (xy 101.984556 -1.999996) (xy 101.984556 -486.544366) (xy 101.98481 -486.544366)
			(xy 101.98481 -486.547414) (xy 101.984556 -486.549954) (xy 101.984556 -527.99996) (xy 101.984056 -528.045454)
			(xy 101.975664 -528.136053) (xy 101.958948 -528.225491) (xy 101.93405 -528.313006) (xy 101.901184 -528.397849)
			(xy 101.860628 -528.479298) (xy 101.812731 -528.556657) (xy 101.757899 -528.629267) (xy 101.696601 -528.696507)
			(xy 101.629361 -528.757804) (xy 101.556751 -528.812635) (xy 101.479391 -528.860532) (xy 101.397942 -528.901087)
			(xy 101.313098 -528.933953) (xy 101.225583 -528.95885) (xy 101.136145 -528.975565) (xy 101.045546 -528.983957)
			(xy 101.000052 -528.984464) (xy 26.500074 -528.984464) (xy 26.500074 -528.984718) (xy 26.49982 -528.984718)
			(xy 26.468088 -528.984217) (xy 26.405167 -528.975935) (xy 26.343864 -528.959512) (xy 26.285231 -528.935226)
			(xy 26.230269 -528.903495) (xy 26.179919 -528.864861) (xy 26.135043 -528.819986) (xy 26.096408 -528.769636)
			(xy 26.064676 -528.714675) (xy 26.04039 -528.656041) (xy 26.023966 -528.594739) (xy 26.015683 -528.531818)
			(xy 26.015188 -528.500086) (xy 26.015188 -527.500088) (xy 26.014716 -527.429524) (xy 26.006818 -527.288618)
			(xy 25.991032 -527.148377) (xy 25.967407 -527.009241) (xy 25.936016 -526.871649) (xy 25.89696 -526.736034)
			(xy 25.850361 -526.602822) (xy 25.796365 -526.472433) (xy 25.735143 -526.345277) (xy 25.666887 -526.221754)
			(xy 25.591812 -526.102252) (xy 25.510154 -525.987148) (xy 25.42217 -525.876805) (xy 25.328137 -525.771568)
			(xy 25.278588 -525.721326) (xy 25.228345 -525.671786) (xy 25.123129 -525.577747) (xy 25.012807 -525.489756)
			(xy 24.897725 -525.408088) (xy 24.778244 -525.333002) (xy 24.654742 -525.264732) (xy 24.527607 -525.203494)
			(xy 24.397238 -525.14948) (xy 24.264046 -525.102861) (xy 24.12845 -525.063783) (xy 23.990875 -525.032368)
			(xy 23.851756 -525.008716) (xy 23.71153 -524.992902) (xy 23.570638 -524.984974) (xy 23.50008 -524.984472)
			(xy 1.514856 -524.984472) (xy 1.481877 -524.984932) (xy 1.416287 -524.977997) (xy 1.352242 -524.962233)
			(xy 1.290926 -524.937933) (xy 1.233471 -524.905544) (xy 1.180938 -524.865664) (xy 1.157224 -524.84274)
			(xy 1.135152 -524.81995) (xy 1.096547 -524.769602) (xy 1.064848 -524.714643) (xy 1.040598 -524.656016)
			(xy 1.02421 -524.594724) (xy 1.015968 -524.531817) (xy 1.015492 -524.500094) (xy 1.015492 -5.514594)
			(xy 1.01507 -5.482255) (xy 0.509222 -5.482255) (xy 0.509016 -5.500116) (xy 0.509016 -524.500094)
			(xy 0.509529 -524.54588) (xy 0.517978 -524.637062) (xy 0.534804 -524.727075) (xy 0.559864 -524.815152)
			(xy 0.592944 -524.900541) (xy 0.633761 -524.982513) (xy 0.681968 -525.06037) (xy 0.737153 -525.133446)
			(xy 0.798845 -525.201119) (xy 0.866518 -525.262811) (xy 0.939594 -525.317996) (xy 1.017451 -525.366203)
			(xy 1.099423 -525.40702) (xy 1.184812 -525.4401) (xy 1.272889 -525.46516) (xy 1.362902 -525.481986)
			(xy 1.454084 -525.490435) (xy 1.49987 -525.490948) (xy 23.50008 -525.490948) (xy 23.563202 -525.491433)
			(xy 23.689196 -525.499359) (xy 23.814444 -525.515182) (xy 23.93845 -525.538839) (xy 24.060727 -525.570236)
			(xy 24.180791 -525.60925) (xy 24.298167 -525.655726) (xy 24.412394 -525.709482) (xy 24.523019 -525.770304)
			(xy 24.629607 -525.837954) (xy 24.731736 -525.912163) (xy 24.829004 -525.992639) (xy 24.921025 -526.079064)
			(xy 25.007438 -526.171097) (xy 25.087902 -526.268376) (xy 25.162097 -526.370515) (xy 25.229732 -526.477111)
			(xy 25.29054 -526.587745) (xy 25.34428 -526.701979) (xy 25.390741 -526.819362) (xy 25.429739 -526.93943)
			(xy 25.46112 -527.061711) (xy 25.48476 -527.185721) (xy 25.500566 -527.310971) (xy 25.508475 -527.436966)
			(xy 25.508966 -527.500088) (xy 25.508966 -528.500086) (xy 25.509507 -528.545875) (xy 25.517982 -528.637061)
			(xy 25.534832 -528.727076) (xy 25.559914 -528.815153) (xy 25.593014 -528.90054) (xy 25.633851 -528.98251)
			(xy 25.682074 -529.060363) (xy 25.737274 -529.133435) (xy 25.79898 -529.201104) (xy 25.866665 -529.262792)
			(xy 25.939752 -529.317973) (xy 26.017618 -529.366176) (xy 26.099598 -529.406991) (xy 26.184994 -529.440069)
			(xy 26.273077 -529.465128) (xy 26.363097 -529.481954) (xy 26.454285 -529.490405) (xy 26.500074 -529.49094)
		)
		(stroke
			(width 0)
			(type solid)
		)
		(fill yes)
		(layer "In2.Cu")
		(net "GND")
	)
	(gr_poly
		(pts
			(xy 101.000052 -528.729956) (xy 101.038285 -528.729475) (xy 101.114333 -528.721487) (xy 101.189128 -528.705592)
			(xy 101.261853 -528.681966) (xy 101.331709 -528.650867) (xy 101.397931 -528.612636) (xy 101.459795 -528.567691)
			(xy 101.51662 -528.516526) (xy 101.567786 -528.459701) (xy 101.612731 -528.397838) (xy 101.650963 -528.331616)
			(xy 101.682063 -528.26176) (xy 101.70569 -528.189036) (xy 101.721586 -528.11424) (xy 101.729575 -528.038193)
			(xy 101.730048 -527.99996) (xy 101.730048 -1.999996) (xy 101.729479 -1.95943) (xy 101.720449 -1.878803)
			(xy 101.702534 -1.799673) (xy 101.675954 -1.723019) (xy 101.641039 -1.649784) (xy 101.598218 -1.580873)
			(xy 101.573584 -1.548638) (xy 101.564398 -1.537574) (xy 101.542012 -1.519532) (xy 101.516154 -1.506965)
			(xy 101.488137 -1.50051) (xy 101.473762 -1.500124) (xy 26.396696 -1.500124) (xy 26.380043 -1.500619)
			(xy 26.347872 -1.509241) (xy 26.319029 -1.525897) (xy 26.29548 -1.549451) (xy 26.278831 -1.578298)
			(xy 26.270215 -1.610471) (xy 26.269696 -1.627124) (xy 26.269696 -2.500122) (xy 26.269198 -2.574138)
			(xy 26.261274 -2.721959) (xy 26.245465 -2.869146) (xy 26.221817 -3.015277) (xy 26.190397 -3.159938)
			(xy 26.151294 -3.302713) (xy 26.104622 -3.443196) (xy 26.050512 -3.580985) (xy 25.989119 -3.715687)
			(xy 25.920619 -3.846918) (xy 25.845207 -3.974302) (xy 25.763099 -4.097477) (xy 25.674528 -4.21609)
			(xy 25.579748 -4.329802) (xy 25.47903 -4.43829) (xy 25.37266 -4.541242) (xy 25.266559 -4.633484)
			(xy 29.519874 -4.633484) (xy 29.519874 -4.546584) (xy 29.527892 -4.460055) (xy 29.54386 -4.374635)
			(xy 29.567641 -4.291053) (xy 29.599033 -4.210021) (xy 29.637767 -4.132232) (xy 29.683514 -4.058348)
			(xy 29.735883 -3.989001) (xy 29.794427 -3.924781) (xy 29.858647 -3.866237) (xy 29.927994 -3.813868)
			(xy 30.001878 -3.768121) (xy 30.079667 -3.729387) (xy 30.160699 -3.697995) (xy 30.244281 -3.674214)
			(xy 30.329701 -3.658246) (xy 30.41623 -3.650228) (xy 30.50313 -3.650228) (xy 30.589659 -3.658246)
			(xy 30.675079 -3.674214) (xy 30.758661 -3.697995) (xy 30.839693 -3.729387) (xy 30.917482 -3.768121)
			(xy 30.991366 -3.813868) (xy 31.060713 -3.866237) (xy 31.124933 -3.924781) (xy 31.183477 -3.989001)
			(xy 31.235846 -4.058348) (xy 31.281593 -4.132232) (xy 31.320327 -4.210021) (xy 31.351719 -4.291053)
			(xy 31.3755 -4.374635) (xy 31.391468 -4.460055) (xy 31.399486 -4.546584) (xy 31.399988 -4.590034)
			(xy 31.399486 -4.633484) (xy 34.599874 -4.633484) (xy 34.599874 -4.546584) (xy 34.607892 -4.460055)
			(xy 34.62386 -4.374635) (xy 34.647641 -4.291053) (xy 34.679033 -4.210021) (xy 34.717767 -4.132232)
			(xy 34.763514 -4.058348) (xy 34.815883 -3.989001) (xy 34.874427 -3.924781) (xy 34.938647 -3.866237)
			(xy 35.007994 -3.813868) (xy 35.081878 -3.768121) (xy 35.159667 -3.729387) (xy 35.240699 -3.697995)
			(xy 35.324281 -3.674214) (xy 35.409701 -3.658246) (xy 35.49623 -3.650228) (xy 35.58313 -3.650228)
			(xy 35.669659 -3.658246) (xy 35.755079 -3.674214) (xy 35.838661 -3.697995) (xy 35.919693 -3.729387)
			(xy 35.997482 -3.768121) (xy 36.071366 -3.813868) (xy 36.140713 -3.866237) (xy 36.204933 -3.924781)
			(xy 36.263477 -3.989001) (xy 36.315846 -4.058348) (xy 36.361593 -4.132232) (xy 36.400327 -4.210021)
			(xy 36.431719 -4.291053) (xy 36.4555 -4.374635) (xy 36.471468 -4.460055) (xy 36.479486 -4.546584)
			(xy 36.479988 -4.590034) (xy 36.479486 -4.633484) (xy 36.471468 -4.720013) (xy 36.4555 -4.805433)
			(xy 36.431719 -4.889015) (xy 36.400327 -4.970047) (xy 36.361593 -5.047836) (xy 36.315846 -5.12172)
			(xy 36.263477 -5.191067) (xy 36.204933 -5.255287) (xy 36.140713 -5.313831) (xy 36.071366 -5.3662)
			(xy 35.997482 -5.411947) (xy 35.919693 -5.450681) (xy 35.838661 -5.482073) (xy 35.755079 -5.505854)
			(xy 35.669659 -5.521822) (xy 35.58313 -5.52984) (xy 35.49623 -5.52984) (xy 35.409701 -5.521822) (xy 35.324281 -5.505854)
			(xy 35.240699 -5.482073) (xy 35.159667 -5.450681) (xy 35.081878 -5.411947) (xy 35.007994 -5.3662)
			(xy 34.938647 -5.313831) (xy 34.874427 -5.255287) (xy 34.815883 -5.191067) (xy 34.763514 -5.12172)
			(xy 34.717767 -5.047836) (xy 34.679033 -4.970047) (xy 34.647641 -4.889015) (xy 34.62386 -4.805433)
			(xy 34.607892 -4.720013) (xy 34.599874 -4.633484) (xy 31.399486 -4.633484) (xy 31.391468 -4.720013)
			(xy 31.3755 -4.805433) (xy 31.351719 -4.889015) (xy 31.320327 -4.970047) (xy 31.281593 -5.047836)
			(xy 31.235846 -5.12172) (xy 31.183477 -5.191067) (xy 31.124933 -5.255287) (xy 31.060713 -5.313831)
			(xy 30.991366 -5.3662) (xy 30.917482 -5.411947) (xy 30.839693 -5.450681) (xy 30.758661 -5.482073)
			(xy 30.675079 -5.505854) (xy 30.589659 -5.521822) (xy 30.50313 -5.52984) (xy 30.41623 -5.52984) (xy 30.329701 -5.521822)
			(xy 30.244281 -5.505854) (xy 30.160699 -5.482073) (xy 30.079667 -5.450681) (xy 30.001878 -5.411947)
			(xy 29.927994 -5.3662) (xy 29.858647 -5.313831) (xy 29.794427 -5.255287) (xy 29.735883 -5.191067)
			(xy 29.683514 -5.12172) (xy 29.637767 -5.047836) (xy 29.599033 -4.970047) (xy 29.567641 -4.889015)
			(xy 29.54386 -4.805433) (xy 29.527892 -4.720013) (xy 29.519874 -4.633484) (xy 25.266559 -4.633484)
			(xy 25.260943 -4.638366) (xy 25.144198 -4.729385) (xy 25.022757 -4.814037) (xy 24.896969 -4.892081)
			(xy 24.83231 -4.928108) (xy 24.766733 -4.963531) (xy 24.632387 -5.028113) (xy 24.494762 -5.085375)
			(xy 24.354256 -5.135154) (xy 24.282908 -5.156708) (xy 24.2055 -5.178898) (xy 24.048632 -5.215347)
			(xy 23.889912 -5.242622) (xy 23.80996 -5.252212) (xy 23.764748 -5.257038) (xy 23.720639 -5.261074)
			(xy 23.63223 -5.266663) (xy 23.587964 -5.268214) (xy 23.584408 -5.268214) (xy 23.521416 -5.269484)
			(xy 23.500334 -5.269738) (xy 23.499826 -5.269992) (xy 1.49225 -5.269992) (xy 1.471927 -5.271101)
			(xy 1.432122 -5.279576) (xy 1.394424 -5.294911) (xy 1.360006 -5.316628) (xy 1.329938 -5.344054) (xy 1.305154 -5.376334)
			(xy 1.2954 -5.394198) (xy 1.287449 -5.410366) (xy 1.276094 -5.444558) (xy 1.272794 -5.46227) (xy 1.27 -5.489702)
			(xy 1.269746 -5.503418) (xy 1.27 -5.512562) (xy 1.27 -7.747) (xy 5.5306 -7.747) (xy 5.534631 -7.617434)
			(xy 5.54671 -7.48837) (xy 5.566789 -7.360306) (xy 5.594791 -7.233739) (xy 5.630608 -7.109156) (xy 5.6741 -6.987042)
			(xy 5.7251 -6.867868) (xy 5.783411 -6.752095) (xy 5.848806 -6.640171) (xy 5.921033 -6.532529) (xy 5.999813 -6.429586)
			(xy 6.08484 -6.33174) (xy 6.175785 -6.239368) (xy 6.272297 -6.15283) (xy 6.374003 -6.072459) (xy 6.480509 -5.998567)
			(xy 6.591402 -5.931439) (xy 6.706254 -5.871335) (xy 6.824621 -5.818488) (xy 6.946044 -5.773101) (xy 7.070054 -5.735352)
			(xy 7.196171 -5.705385) (xy 7.323907 -5.683316) (xy 7.452768 -5.669232) (xy 7.582255 -5.663186) (xy 7.711868 -5.665202)
			(xy 7.841104 -5.675272) (xy 7.969465 -5.693357) (xy 8.096453 -5.719387) (xy 8.221577 -5.753262) (xy 8.239228 -5.759241)
			(xy 26.627809 -5.759241) (xy 26.628405 -5.703251) (xy 26.637179 -5.647949) (xy 26.653941 -5.594524)
			(xy 26.678333 -5.544123) (xy 26.70983 -5.497828) (xy 26.747755 -5.456634) (xy 26.791295 -5.421427)
			(xy 26.839513 -5.392961) (xy 26.891373 -5.37185) (xy 26.945763 -5.358545) (xy 27.001514 -5.353334)
			(xy 27.057427 -5.356327) (xy 27.112302 -5.367462) (xy 27.16496 -5.386497) (xy 27.21427 -5.413026)
			(xy 27.259174 -5.446477) (xy 27.298705 -5.486132) (xy 27.332015 -5.531139) (xy 27.358389 -5.580532)
			(xy 27.37726 -5.63325) (xy 27.388222 -5.68816) (xy 27.391041 -5.744082) (xy 27.385655 -5.799816)
			(xy 27.37218 -5.854164) (xy 27.350906 -5.905958) (xy 27.32229 -5.954087) (xy 27.305 -5.976112) (xy 27.29176 -5.993153)
			(xy 27.270581 -6.030748) (xy 27.256064 -6.071382) (xy 27.248627 -6.113885) (xy 27.248484 -6.157035)
			(xy 27.255639 -6.199587) (xy 27.269886 -6.240316) (xy 27.290815 -6.27805) (xy 27.317824 -6.311702)
			(xy 27.350134 -6.340302) (xy 27.368246 -6.352032) (xy 27.391817 -6.367153) (xy 27.43461 -6.403277)
			(xy 27.471662 -6.445268) (xy 27.502178 -6.492225) (xy 27.525504 -6.543137) (xy 27.541136 -6.596913)
			(xy 27.548741 -6.652395) (xy 27.548154 -6.708394) (xy 27.539388 -6.763705) (xy 27.522631 -6.81714)
			(xy 27.498244 -6.867553) (xy 27.46675 -6.913859) (xy 27.428825 -6.955065) (xy 27.385285 -6.990284)
			(xy 27.337065 -7.018761) (xy 27.2852 -7.039884) (xy 27.230804 -7.053198) (xy 27.175047 -7.058419)
			(xy 27.119125 -7.055434) (xy 27.06424 -7.044306) (xy 27.011571 -7.025276) (xy 26.96225 -6.998752)
			(xy 26.917335 -6.965303) (xy 26.877792 -6.925648) (xy 26.84447 -6.880639) (xy 26.818085 -6.831243)
			(xy 26.799204 -6.77852) (xy 26.788231 -6.723604) (xy 26.785404 -6.667674) (xy 26.790782 -6.611932)
			(xy 26.804251 -6.557574) (xy 26.82552 -6.505769) (xy 26.854133 -6.457629) (xy 26.871422 -6.435598)
			(xy 26.884645 -6.418545) (xy 26.905823 -6.380952) (xy 26.920339 -6.34032) (xy 26.927776 -6.297819)
			(xy 26.92792 -6.254672) (xy 26.920767 -6.212122) (xy 26.906522 -6.171395) (xy 26.885596 -6.133662)
			(xy 26.858592 -6.10001) (xy 26.826286 -6.071409) (xy 26.808176 -6.059678) (xy 26.784665 -6.044468)
			(xy 26.741885 -6.008342) (xy 26.704844 -5.96635) (xy 26.67434 -5.919396) (xy 26.651026 -5.868487)
			(xy 26.635404 -5.814717) (xy 26.627809 -5.759241) (xy 8.239228 -5.759241) (xy 8.344353 -5.79485)
			(xy 8.464306 -5.843991) (xy 8.580971 -5.900494) (xy 8.693899 -5.964141) (xy 8.802651 -6.034685) (xy 8.906807 -6.111854)
			(xy 9.005964 -6.195349) (xy 9.099738 -6.284847) (xy 9.187767 -6.380002) (xy 9.26971 -6.480445) (xy 9.345249 -6.585788)
			(xy 9.414094 -6.695624) (xy 9.475977 -6.809528) (xy 9.530658 -6.927058) (xy 9.577928 -7.047761) (xy 9.617601 -7.171169)
			(xy 9.618189 -7.173484) (xy 29.519874 -7.173484) (xy 29.519874 -7.086584) (xy 29.527892 -7.000055)
			(xy 29.54386 -6.914635) (xy 29.567641 -6.831053) (xy 29.599033 -6.750021) (xy 29.637767 -6.672232)
			(xy 29.683514 -6.598348) (xy 29.735883 -6.529001) (xy 29.794427 -6.464781) (xy 29.858647 -6.406237)
			(xy 29.927994 -6.353868) (xy 30.001878 -6.308121) (xy 30.079667 -6.269387) (xy 30.160699 -6.237995)
			(xy 30.244281 -6.214214) (xy 30.329701 -6.198246) (xy 30.41623 -6.190228) (xy 30.50313 -6.190228)
			(xy 30.589659 -6.198246) (xy 30.675079 -6.214214) (xy 30.758661 -6.237995) (xy 30.839693 -6.269387)
			(xy 30.917482 -6.308121) (xy 30.991366 -6.353868) (xy 31.060713 -6.406237) (xy 31.124933 -6.464781)
			(xy 31.183477 -6.529001) (xy 31.235846 -6.598348) (xy 31.281593 -6.672232) (xy 31.320327 -6.750021)
			(xy 31.351719 -6.831053) (xy 31.3755 -6.914635) (xy 31.391468 -7.000055) (xy 31.399486 -7.086584)
			(xy 31.399988 -7.130034) (xy 31.399486 -7.173484) (xy 34.599874 -7.173484) (xy 34.599874 -7.086584)
			(xy 34.607892 -7.000055) (xy 34.62386 -6.914635) (xy 34.647641 -6.831053) (xy 34.679033 -6.750021)
			(xy 34.717767 -6.672232) (xy 34.763514 -6.598348) (xy 34.815883 -6.529001) (xy 34.874427 -6.464781)
			(xy 34.938647 -6.406237) (xy 35.007994 -6.353868) (xy 35.081878 -6.308121) (xy 35.159667 -6.269387)
			(xy 35.240699 -6.237995) (xy 35.324281 -6.214214) (xy 35.409701 -6.198246) (xy 35.49623 -6.190228)
			(xy 35.58313 -6.190228) (xy 35.669659 -6.198246) (xy 35.755079 -6.214214) (xy 35.838661 -6.237995)
			(xy 35.919693 -6.269387) (xy 35.997482 -6.308121) (xy 36.071366 -6.353868) (xy 36.140713 -6.406237)
			(xy 36.204933 -6.464781) (xy 36.263477 -6.529001) (xy 36.315846 -6.598348) (xy 36.361593 -6.672232)
			(xy 36.400327 -6.750021) (xy 36.431719 -6.831053) (xy 36.454201 -6.91007) (xy 39.818564 -6.91007)
			(xy 39.819054 -6.852663) (xy 39.826889 -6.738117) (xy 39.842523 -6.624372) (xy 39.865882 -6.51196)
			(xy 39.896859 -6.401403) (xy 39.935308 -6.293218) (xy 39.98105 -6.18791) (xy 40.033872 -6.085968)
			(xy 40.093527 -5.987869) (xy 40.159738 -5.894069) (xy 40.232196 -5.805007) (xy 40.310562 -5.721096)
			(xy 40.394473 -5.64273) (xy 40.483535 -5.570272) (xy 40.577335 -5.504061) (xy 40.675434 -5.444406)
			(xy 40.777376 -5.391584) (xy 40.882684 -5.345842) (xy 40.990869 -5.307393) (xy 41.101426 -5.276416)
			(xy 41.213838 -5.253057) (xy 41.327583 -5.237423) (xy 41.442129 -5.229588) (xy 41.556943 -5.229588)
			(xy 41.671489 -5.237423) (xy 41.785234 -5.253057) (xy 41.897646 -5.276416) (xy 42.008203 -5.307393)
			(xy 42.116388 -5.345842) (xy 42.221696 -5.391584) (xy 42.323638 -5.444406) (xy 42.421737 -5.504061)
			(xy 42.50107 -5.56006) (xy 43.327577 -5.56006) (xy 43.331612 -5.484356) (xy 43.343671 -5.409511)
			(xy 43.363617 -5.33637) (xy 43.391224 -5.265765) (xy 43.42618 -5.198494) (xy 43.468088 -5.135319)
			(xy 43.516474 -5.076957) (xy 43.57079 -5.024069) (xy 43.630419 -4.977254) (xy 43.694687 -4.937042)
			(xy 43.762864 -4.90389) (xy 43.83418 -4.878172) (xy 43.907825 -4.86018) (xy 43.982965 -4.850118)
			(xy 44.058749 -4.848099) (xy 44.134319 -4.854148) (xy 44.208817 -4.868195) (xy 44.2814 -4.890081)
			(xy 44.351246 -4.919558) (xy 44.417563 -4.956293) (xy 44.479599 -4.999868) (xy 44.536652 -5.04979)
			(xy 44.588076 -5.105494) (xy 44.633287 -5.166349) (xy 44.671774 -5.231664) (xy 44.7031 -5.3007) (xy 44.72691 -5.372675)
			(xy 44.742935 -5.446773) (xy 44.750994 -5.522154) (xy 44.751498 -5.56006) (xy 45.867577 -5.56006)
			(xy 45.871612 -5.484356) (xy 45.883671 -5.409511) (xy 45.903617 -5.33637) (xy 45.931224 -5.265765)
			(xy 45.96618 -5.198494) (xy 46.008088 -5.135319) (xy 46.056474 -5.076957) (xy 46.11079 -5.024069)
			(xy 46.170419 -4.977254) (xy 46.234687 -4.937042) (xy 46.302864 -4.90389) (xy 46.37418 -4.878172)
			(xy 46.447825 -4.86018) (xy 46.522965 -4.850118) (xy 46.598749 -4.848099) (xy 46.674319 -4.854148)
			(xy 46.748817 -4.868195) (xy 46.8214 -4.890081) (xy 46.891246 -4.919558) (xy 46.957563 -4.956293)
			(xy 47.019599 -4.999868) (xy 47.076652 -5.04979) (xy 47.128076 -5.105494) (xy 47.173287 -5.166349)
			(xy 47.211774 -5.231664) (xy 47.2431 -5.3007) (xy 47.26691 -5.372675) (xy 47.282935 -5.446773) (xy 47.290994 -5.522154)
			(xy 47.291498 -5.56006) (xy 48.407577 -5.56006) (xy 48.411612 -5.484356) (xy 48.423671 -5.409511)
			(xy 48.443617 -5.33637) (xy 48.471224 -5.265765) (xy 48.50618 -5.198494) (xy 48.548088 -5.135319)
			(xy 48.596474 -5.076957) (xy 48.65079 -5.024069) (xy 48.710419 -4.977254) (xy 48.774687 -4.937042)
			(xy 48.842864 -4.90389) (xy 48.91418 -4.878172) (xy 48.987825 -4.86018) (xy 49.062965 -4.850118)
			(xy 49.138749 -4.848099) (xy 49.214319 -4.854148) (xy 49.288817 -4.868195) (xy 49.3614 -4.890081)
			(xy 49.431246 -4.919558) (xy 49.497563 -4.956293) (xy 49.559599 -4.999868) (xy 49.616652 -5.04979)
			(xy 49.668076 -5.105494) (xy 49.713287 -5.166349) (xy 49.751774 -5.231664) (xy 49.7831 -5.3007) (xy 49.80691 -5.372675)
			(xy 49.822935 -5.446773) (xy 49.830994 -5.522154) (xy 49.831498 -5.56006) (xy 50.947577 -5.56006)
			(xy 50.951612 -5.484356) (xy 50.963671 -5.409511) (xy 50.983617 -5.33637) (xy 51.011224 -5.265765)
			(xy 51.04618 -5.198494) (xy 51.088088 -5.135319) (xy 51.136474 -5.076957) (xy 51.19079 -5.024069)
			(xy 51.250419 -4.977254) (xy 51.314687 -4.937042) (xy 51.382864 -4.90389) (xy 51.45418 -4.878172)
			(xy 51.527825 -4.86018) (xy 51.602965 -4.850118) (xy 51.678749 -4.848099) (xy 51.754319 -4.854148)
			(xy 51.828817 -4.868195) (xy 51.9014 -4.890081) (xy 51.971246 -4.919558) (xy 52.037563 -4.956293)
			(xy 52.099599 -4.999868) (xy 52.156652 -5.04979) (xy 52.208076 -5.105494) (xy 52.253287 -5.166349)
			(xy 52.291774 -5.231664) (xy 52.3231 -5.3007) (xy 52.34691 -5.372675) (xy 52.362935 -5.446773) (xy 52.370994 -5.522154)
			(xy 52.371498 -5.56006) (xy 53.487577 -5.56006) (xy 53.491612 -5.484356) (xy 53.503671 -5.409511)
			(xy 53.523617 -5.33637) (xy 53.551224 -5.265765) (xy 53.58618 -5.198494) (xy 53.628088 -5.135319)
			(xy 53.676474 -5.076957) (xy 53.73079 -5.024069) (xy 53.790419 -4.977254) (xy 53.854687 -4.937042)
			(xy 53.922864 -4.90389) (xy 53.99418 -4.878172) (xy 54.067825 -4.86018) (xy 54.142965 -4.850118)
			(xy 54.218749 -4.848099) (xy 54.294319 -4.854148) (xy 54.368817 -4.868195) (xy 54.4414 -4.890081)
			(xy 54.511246 -4.919558) (xy 54.577563 -4.956293) (xy 54.639599 -4.999868) (xy 54.696652 -5.04979)
			(xy 54.748076 -5.105494) (xy 54.793287 -5.166349) (xy 54.831774 -5.231664) (xy 54.8631 -5.3007) (xy 54.88691 -5.372675)
			(xy 54.902935 -5.446773) (xy 54.910994 -5.522154) (xy 54.911498 -5.56006) (xy 56.027577 -5.56006)
			(xy 56.031612 -5.484356) (xy 56.043671 -5.409511) (xy 56.063617 -5.33637) (xy 56.091224 -5.265765)
			(xy 56.12618 -5.198494) (xy 56.168088 -5.135319) (xy 56.216474 -5.076957) (xy 56.27079 -5.024069)
			(xy 56.330419 -4.977254) (xy 56.394687 -4.937042) (xy 56.462864 -4.90389) (xy 56.53418 -4.878172)
			(xy 56.607825 -4.86018) (xy 56.682965 -4.850118) (xy 56.758749 -4.848099) (xy 56.834319 -4.854148)
			(xy 56.908817 -4.868195) (xy 56.9814 -4.890081) (xy 57.051246 -4.919558) (xy 57.117563 -4.956293)
			(xy 57.179599 -4.999868) (xy 57.236652 -5.04979) (xy 57.288076 -5.105494) (xy 57.333287 -5.166349)
			(xy 57.371774 -5.231664) (xy 57.4031 -5.3007) (xy 57.42691 -5.372675) (xy 57.442935 -5.446773) (xy 57.450994 -5.522154)
			(xy 57.451498 -5.56006) (xy 58.567577 -5.56006) (xy 58.571612 -5.484356) (xy 58.583671 -5.409511)
			(xy 58.603617 -5.33637) (xy 58.631224 -5.265765) (xy 58.66618 -5.198494) (xy 58.708088 -5.135319)
			(xy 58.756474 -5.076957) (xy 58.81079 -5.024069) (xy 58.870419 -4.977254) (xy 58.934687 -4.937042)
			(xy 59.002864 -4.90389) (xy 59.07418 -4.878172) (xy 59.147825 -4.86018) (xy 59.222965 -4.850118)
			(xy 59.298749 -4.848099) (xy 59.374319 -4.854148) (xy 59.448817 -4.868195) (xy 59.5214 -4.890081)
			(xy 59.591246 -4.919558) (xy 59.657563 -4.956293) (xy 59.719599 -4.999868) (xy 59.776652 -5.04979)
			(xy 59.828076 -5.105494) (xy 59.873287 -5.166349) (xy 59.911774 -5.231664) (xy 59.9431 -5.3007) (xy 59.96691 -5.372675)
			(xy 59.982935 -5.446773) (xy 59.990994 -5.522154) (xy 59.991498 -5.56006) (xy 61.107577 -5.56006)
			(xy 61.111612 -5.484356) (xy 61.123671 -5.409511) (xy 61.143617 -5.33637) (xy 61.171224 -5.265765)
			(xy 61.20618 -5.198494) (xy 61.248088 -5.135319) (xy 61.296474 -5.076957) (xy 61.35079 -5.024069)
			(xy 61.410419 -4.977254) (xy 61.474687 -4.937042) (xy 61.542864 -4.90389) (xy 61.61418 -4.878172)
			(xy 61.687825 -4.86018) (xy 61.762965 -4.850118) (xy 61.838749 -4.848099) (xy 61.914319 -4.854148)
			(xy 61.988817 -4.868195) (xy 62.0614 -4.890081) (xy 62.131246 -4.919558) (xy 62.197563 -4.956293)
			(xy 62.259599 -4.999868) (xy 62.316652 -5.04979) (xy 62.368076 -5.105494) (xy 62.413287 -5.166349)
			(xy 62.451774 -5.231664) (xy 62.4831 -5.3007) (xy 62.50691 -5.372675) (xy 62.522935 -5.446773) (xy 62.530994 -5.522154)
			(xy 62.531498 -5.56006) (xy 62.530994 -5.597966) (xy 62.522935 -5.673347) (xy 62.50691 -5.747445)
			(xy 62.4831 -5.81942) (xy 62.451774 -5.888456) (xy 62.413287 -5.953771) (xy 62.368076 -6.014626)
			(xy 62.316652 -6.07033) (xy 62.259599 -6.120252) (xy 62.197563 -6.163827) (xy 62.131246 -6.200562)
			(xy 62.0614 -6.230039) (xy 61.988817 -6.251925) (xy 61.914319 -6.265972) (xy 61.838749 -6.272021)
			(xy 61.762965 -6.270002) (xy 61.687825 -6.25994) (xy 61.61418 -6.241948) (xy 61.542864 -6.21623)
			(xy 61.474687 -6.183078) (xy 61.410419 -6.142866) (xy 61.35079 -6.096051) (xy 61.296474 -6.043163)
			(xy 61.248088 -5.984801) (xy 61.20618 -5.921626) (xy 61.171224 -5.854355) (xy 61.143617 -5.78375)
			(xy 61.123671 -5.710609) (xy 61.111612 -5.635764) (xy 61.107577 -5.56006) (xy 59.991498 -5.56006)
			(xy 59.990994 -5.597966) (xy 59.982935 -5.673347) (xy 59.96691 -5.747445) (xy 59.9431 -5.81942) (xy 59.911774 -5.888456)
			(xy 59.873287 -5.953771) (xy 59.828076 -6.014626) (xy 59.776652 -6.07033) (xy 59.719599 -6.120252)
			(xy 59.657563 -6.163827) (xy 59.591246 -6.200562) (xy 59.5214 -6.230039) (xy 59.448817 -6.251925)
			(xy 59.374319 -6.265972) (xy 59.298749 -6.272021) (xy 59.222965 -6.270002) (xy 59.147825 -6.25994)
			(xy 59.07418 -6.241948) (xy 59.002864 -6.21623) (xy 58.934687 -6.183078) (xy 58.870419 -6.142866)
			(xy 58.81079 -6.096051) (xy 58.756474 -6.043163) (xy 58.708088 -5.984801) (xy 58.66618 -5.921626)
			(xy 58.631224 -5.854355) (xy 58.603617 -5.78375) (xy 58.583671 -5.710609) (xy 58.571612 -5.635764)
			(xy 58.567577 -5.56006) (xy 57.451498 -5.56006) (xy 57.450994 -5.597966) (xy 57.442935 -5.673347)
			(xy 57.42691 -5.747445) (xy 57.4031 -5.81942) (xy 57.371774 -5.888456) (xy 57.333287 -5.953771) (xy 57.288076 -6.014626)
			(xy 57.236652 -6.07033) (xy 57.179599 -6.120252) (xy 57.117563 -6.163827) (xy 57.051246 -6.200562)
			(xy 56.9814 -6.230039) (xy 56.908817 -6.251925) (xy 56.834319 -6.265972) (xy 56.758749 -6.272021)
			(xy 56.682965 -6.270002) (xy 56.607825 -6.25994) (xy 56.53418 -6.241948) (xy 56.462864 -6.21623)
			(xy 56.394687 -6.183078) (xy 56.330419 -6.142866) (xy 56.27079 -6.096051) (xy 56.216474 -6.043163)
			(xy 56.168088 -5.984801) (xy 56.12618 -5.921626) (xy 56.091224 -5.854355) (xy 56.063617 -5.78375)
			(xy 56.043671 -5.710609) (xy 56.031612 -5.635764) (xy 56.027577 -5.56006) (xy 54.911498 -5.56006)
			(xy 54.910994 -5.597966) (xy 54.902935 -5.673347) (xy 54.88691 -5.747445) (xy 54.8631 -5.81942) (xy 54.831774 -5.888456)
			(xy 54.793287 -5.953771) (xy 54.748076 -6.014626) (xy 54.696652 -6.07033) (xy 54.639599 -6.120252)
			(xy 54.577563 -6.163827) (xy 54.511246 -6.200562) (xy 54.4414 -6.230039) (xy 54.368817 -6.251925)
			(xy 54.294319 -6.265972) (xy 54.218749 -6.272021) (xy 54.142965 -6.270002) (xy 54.067825 -6.25994)
			(xy 53.99418 -6.241948) (xy 53.922864 -6.21623) (xy 53.854687 -6.183078) (xy 53.790419 -6.142866)
			(xy 53.73079 -6.096051) (xy 53.676474 -6.043163) (xy 53.628088 -5.984801) (xy 53.58618 -5.921626)
			(xy 53.551224 -5.854355) (xy 53.523617 -5.78375) (xy 53.503671 -5.710609) (xy 53.491612 -5.635764)
			(xy 53.487577 -5.56006) (xy 52.371498 -5.56006) (xy 52.370994 -5.597966) (xy 52.362935 -5.673347)
			(xy 52.34691 -5.747445) (xy 52.3231 -5.81942) (xy 52.291774 -5.888456) (xy 52.253287 -5.953771) (xy 52.208076 -6.014626)
			(xy 52.156652 -6.07033) (xy 52.099599 -6.120252) (xy 52.037563 -6.163827) (xy 51.971246 -6.200562)
			(xy 51.9014 -6.230039) (xy 51.828817 -6.251925) (xy 51.754319 -6.265972) (xy 51.678749 -6.272021)
			(xy 51.602965 -6.270002) (xy 51.527825 -6.25994) (xy 51.45418 -6.241948) (xy 51.382864 -6.21623)
			(xy 51.314687 -6.183078) (xy 51.250419 -6.142866) (xy 51.19079 -6.096051) (xy 51.136474 -6.043163)
			(xy 51.088088 -5.984801) (xy 51.04618 -5.921626) (xy 51.011224 -5.854355) (xy 50.983617 -5.78375)
			(xy 50.963671 -5.710609) (xy 50.951612 -5.635764) (xy 50.947577 -5.56006) (xy 49.831498 -5.56006)
			(xy 49.830994 -5.597966) (xy 49.822935 -5.673347) (xy 49.80691 -5.747445) (xy 49.7831 -5.81942) (xy 49.751774 -5.888456)
			(xy 49.713287 -5.953771) (xy 49.668076 -6.014626) (xy 49.616652 -6.07033) (xy 49.559599 -6.120252)
			(xy 49.497563 -6.163827) (xy 49.431246 -6.200562) (xy 49.3614 -6.230039) (xy 49.288817 -6.251925)
			(xy 49.214319 -6.265972) (xy 49.138749 -6.272021) (xy 49.062965 -6.270002) (xy 48.987825 -6.25994)
			(xy 48.91418 -6.241948) (xy 48.842864 -6.21623) (xy 48.774687 -6.183078) (xy 48.710419 -6.142866)
			(xy 48.65079 -6.096051) (xy 48.596474 -6.043163) (xy 48.548088 -5.984801) (xy 48.50618 -5.921626)
			(xy 48.471224 -5.854355) (xy 48.443617 -5.78375) (xy 48.423671 -5.710609) (xy 48.411612 -5.635764)
			(xy 48.407577 -5.56006) (xy 47.291498 -5.56006) (xy 47.290994 -5.597966) (xy 47.282935 -5.673347)
			(xy 47.26691 -5.747445) (xy 47.2431 -5.81942) (xy 47.211774 -5.888456) (xy 47.173287 -5.953771) (xy 47.128076 -6.014626)
			(xy 47.076652 -6.07033) (xy 47.019599 -6.120252) (xy 46.957563 -6.163827) (xy 46.891246 -6.200562)
			(xy 46.8214 -6.230039) (xy 46.748817 -6.251925) (xy 46.674319 -6.265972) (xy 46.598749 -6.272021)
			(xy 46.522965 -6.270002) (xy 46.447825 -6.25994) (xy 46.37418 -6.241948) (xy 46.302864 -6.21623)
			(xy 46.234687 -6.183078) (xy 46.170419 -6.142866) (xy 46.11079 -6.096051) (xy 46.056474 -6.043163)
			(xy 46.008088 -5.984801) (xy 45.96618 -5.921626) (xy 45.931224 -5.854355) (xy 45.903617 -5.78375)
			(xy 45.883671 -5.710609) (xy 45.871612 -5.635764) (xy 45.867577 -5.56006) (xy 44.751498 -5.56006)
			(xy 44.750994 -5.597966) (xy 44.742935 -5.673347) (xy 44.72691 -5.747445) (xy 44.7031 -5.81942) (xy 44.671774 -5.888456)
			(xy 44.633287 -5.953771) (xy 44.588076 -6.014626) (xy 44.536652 -6.07033) (xy 44.479599 -6.120252)
			(xy 44.417563 -6.163827) (xy 44.351246 -6.200562) (xy 44.2814 -6.230039) (xy 44.208817 -6.251925)
			(xy 44.134319 -6.265972) (xy 44.058749 -6.272021) (xy 43.982965 -6.270002) (xy 43.907825 -6.25994)
			(xy 43.83418 -6.241948) (xy 43.762864 -6.21623) (xy 43.694687 -6.183078) (xy 43.630419 -6.142866)
			(xy 43.57079 -6.096051) (xy 43.516474 -6.043163) (xy 43.468088 -5.984801) (xy 43.42618 -5.921626)
			(xy 43.391224 -5.854355) (xy 43.363617 -5.78375) (xy 43.343671 -5.710609) (xy 43.331612 -5.635764)
			(xy 43.327577 -5.56006) (xy 42.50107 -5.56006) (xy 42.515537 -5.570272) (xy 42.604599 -5.64273) (xy 42.68851 -5.721096)
			(xy 42.766876 -5.805007) (xy 42.839334 -5.894069) (xy 42.905545 -5.987869) (xy 42.9652 -6.085968)
			(xy 43.018022 -6.18791) (xy 43.063764 -6.293218) (xy 43.102213 -6.401403) (xy 43.13319 -6.51196)
			(xy 43.156549 -6.624372) (xy 43.172183 -6.738117) (xy 43.180018 -6.852663) (xy 43.180508 -6.91007)
			(xy 43.180381 -6.943251) (xy 43.177842 -7.009565) (xy 43.175428 -7.042658) (xy 43.170272 -7.100942)
			(xy 43.152948 -7.216671) (xy 43.127616 -7.330914) (xy 43.094401 -7.443119) (xy 43.053462 -7.552742)
			(xy 43.004999 -7.659253) (xy 42.949245 -7.762135) (xy 42.886471 -7.860891) (xy 42.816981 -7.955042)
			(xy 42.741111 -8.044132) (xy 42.659229 -8.127729) (xy 42.571732 -8.20543) (xy 42.500813 -8.26008)
			(xy 43.327577 -8.26008) (xy 43.331612 -8.184376) (xy 43.343671 -8.109531) (xy 43.363617 -8.03639)
			(xy 43.391224 -7.965785) (xy 43.42618 -7.898514) (xy 43.468088 -7.835339) (xy 43.516474 -7.776977)
			(xy 43.57079 -7.724089) (xy 43.630419 -7.677274) (xy 43.694687 -7.637062) (xy 43.762864 -7.60391)
			(xy 43.83418 -7.578192) (xy 43.907825 -7.5602) (xy 43.982965 -7.550138) (xy 44.058749 -7.548119)
			(xy 44.134319 -7.554168) (xy 44.208817 -7.568215) (xy 44.2814 -7.590101) (xy 44.351246 -7.619578)
			(xy 44.417563 -7.656313) (xy 44.479599 -7.699888) (xy 44.536652 -7.74981) (xy 44.588076 -7.805514)
			(xy 44.633287 -7.866369) (xy 44.671774 -7.931684) (xy 44.7031 -8.00072) (xy 44.72691 -8.072695) (xy 44.742935 -8.146793)
			(xy 44.750994 -8.222174) (xy 44.751498 -8.26008) (xy 45.867577 -8.26008) (xy 45.871612 -8.184376)
			(xy 45.883671 -8.109531) (xy 45.903617 -8.03639) (xy 45.931224 -7.965785) (xy 45.96618 -7.898514)
			(xy 46.008088 -7.835339) (xy 46.056474 -7.776977) (xy 46.11079 -7.724089) (xy 46.170419 -7.677274)
			(xy 46.234687 -7.637062) (xy 46.302864 -7.60391) (xy 46.37418 -7.578192) (xy 46.447825 -7.5602) (xy 46.522965 -7.550138)
			(xy 46.598749 -7.548119) (xy 46.674319 -7.554168) (xy 46.748817 -7.568215) (xy 46.8214 -7.590101)
			(xy 46.891246 -7.619578) (xy 46.957563 -7.656313) (xy 47.019599 -7.699888) (xy 47.076652 -7.74981)
			(xy 47.128076 -7.805514) (xy 47.173287 -7.866369) (xy 47.211774 -7.931684) (xy 47.2431 -8.00072)
			(xy 47.26691 -8.072695) (xy 47.282935 -8.146793) (xy 47.290994 -8.222174) (xy 47.291498 -8.26008)
			(xy 48.407577 -8.26008) (xy 48.411612 -8.184376) (xy 48.423671 -8.109531) (xy 48.443617 -8.03639)
			(xy 48.471224 -7.965785) (xy 48.50618 -7.898514) (xy 48.548088 -7.835339) (xy 48.596474 -7.776977)
			(xy 48.65079 -7.724089) (xy 48.710419 -7.677274) (xy 48.774687 -7.637062) (xy 48.842864 -7.60391)
			(xy 48.91418 -7.578192) (xy 48.987825 -7.5602) (xy 49.062965 -7.550138) (xy 49.138749 -7.548119)
			(xy 49.214319 -7.554168) (xy 49.288817 -7.568215) (xy 49.3614 -7.590101) (xy 49.431246 -7.619578)
			(xy 49.497563 -7.656313) (xy 49.559599 -7.699888) (xy 49.616652 -7.74981) (xy 49.668076 -7.805514)
			(xy 49.713287 -7.866369) (xy 49.751774 -7.931684) (xy 49.7831 -8.00072) (xy 49.80691 -8.072695) (xy 49.822935 -8.146793)
			(xy 49.830994 -8.222174) (xy 49.831498 -8.26008) (xy 50.947577 -8.26008) (xy 50.951612 -8.184376)
			(xy 50.963671 -8.109531) (xy 50.983617 -8.03639) (xy 51.011224 -7.965785) (xy 51.04618 -7.898514)
			(xy 51.088088 -7.835339) (xy 51.136474 -7.776977) (xy 51.19079 -7.724089) (xy 51.250419 -7.677274)
			(xy 51.314687 -7.637062) (xy 51.382864 -7.60391) (xy 51.45418 -7.578192) (xy 51.527825 -7.5602) (xy 51.602965 -7.550138)
			(xy 51.678749 -7.548119) (xy 51.754319 -7.554168) (xy 51.828817 -7.568215) (xy 51.9014 -7.590101)
			(xy 51.971246 -7.619578) (xy 52.037563 -7.656313) (xy 52.099599 -7.699888) (xy 52.156652 -7.74981)
			(xy 52.208076 -7.805514) (xy 52.253287 -7.866369) (xy 52.291774 -7.931684) (xy 52.3231 -8.00072)
			(xy 52.34691 -8.072695) (xy 52.362935 -8.146793) (xy 52.370994 -8.222174) (xy 52.371498 -8.26008)
			(xy 53.487577 -8.26008) (xy 53.491612 -8.184376) (xy 53.503671 -8.109531) (xy 53.523617 -8.03639)
			(xy 53.551224 -7.965785) (xy 53.58618 -7.898514) (xy 53.628088 -7.835339) (xy 53.676474 -7.776977)
			(xy 53.73079 -7.724089) (xy 53.790419 -7.677274) (xy 53.854687 -7.637062) (xy 53.922864 -7.60391)
			(xy 53.99418 -7.578192) (xy 54.067825 -7.5602) (xy 54.142965 -7.550138) (xy 54.218749 -7.548119)
			(xy 54.294319 -7.554168) (xy 54.368817 -7.568215) (xy 54.4414 -7.590101) (xy 54.511246 -7.619578)
			(xy 54.577563 -7.656313) (xy 54.639599 -7.699888) (xy 54.696652 -7.74981) (xy 54.748076 -7.805514)
			(xy 54.793287 -7.866369) (xy 54.831774 -7.931684) (xy 54.8631 -8.00072) (xy 54.88691 -8.072695) (xy 54.902935 -8.146793)
			(xy 54.910994 -8.222174) (xy 54.911498 -8.26008) (xy 56.027577 -8.26008) (xy 56.031612 -8.184376)
			(xy 56.043671 -8.109531) (xy 56.063617 -8.03639) (xy 56.091224 -7.965785) (xy 56.12618 -7.898514)
			(xy 56.168088 -7.835339) (xy 56.216474 -7.776977) (xy 56.27079 -7.724089) (xy 56.330419 -7.677274)
			(xy 56.394687 -7.637062) (xy 56.462864 -7.60391) (xy 56.53418 -7.578192) (xy 56.607825 -7.5602) (xy 56.682965 -7.550138)
			(xy 56.758749 -7.548119) (xy 56.834319 -7.554168) (xy 56.908817 -7.568215) (xy 56.9814 -7.590101)
			(xy 57.051246 -7.619578) (xy 57.117563 -7.656313) (xy 57.179599 -7.699888) (xy 57.236652 -7.74981)
			(xy 57.288076 -7.805514) (xy 57.333287 -7.866369) (xy 57.371774 -7.931684) (xy 57.4031 -8.00072)
			(xy 57.42691 -8.072695) (xy 57.442935 -8.146793) (xy 57.450994 -8.222174) (xy 57.451498 -8.26008)
			(xy 58.567577 -8.26008) (xy 58.571612 -8.184376) (xy 58.583671 -8.109531) (xy 58.603617 -8.03639)
			(xy 58.631224 -7.965785) (xy 58.66618 -7.898514) (xy 58.708088 -7.835339) (xy 58.756474 -7.776977)
			(xy 58.81079 -7.724089) (xy 58.870419 -7.677274) (xy 58.934687 -7.637062) (xy 59.002864 -7.60391)
			(xy 59.07418 -7.578192) (xy 59.147825 -7.5602) (xy 59.222965 -7.550138) (xy 59.298749 -7.548119)
			(xy 59.374319 -7.554168) (xy 59.448817 -7.568215) (xy 59.5214 -7.590101) (xy 59.591246 -7.619578)
			(xy 59.657563 -7.656313) (xy 59.719599 -7.699888) (xy 59.776652 -7.74981) (xy 59.828076 -7.805514)
			(xy 59.873287 -7.866369) (xy 59.911774 -7.931684) (xy 59.9431 -8.00072) (xy 59.96691 -8.072695) (xy 59.982935 -8.146793)
			(xy 59.990994 -8.222174) (xy 59.991498 -8.26008) (xy 61.107577 -8.26008) (xy 61.111612 -8.184376)
			(xy 61.123671 -8.109531) (xy 61.143617 -8.03639) (xy 61.171224 -7.965785) (xy 61.20618 -7.898514)
			(xy 61.248088 -7.835339) (xy 61.296474 -7.776977) (xy 61.35079 -7.724089) (xy 61.410419 -7.677274)
			(xy 61.474687 -7.637062) (xy 61.542864 -7.60391) (xy 61.61418 -7.578192) (xy 61.687825 -7.5602) (xy 61.762965 -7.550138)
			(xy 61.838749 -7.548119) (xy 61.914319 -7.554168) (xy 61.988817 -7.568215) (xy 62.0614 -7.590101)
			(xy 62.131246 -7.619578) (xy 62.197563 -7.656313) (xy 62.259599 -7.699888) (xy 62.316652 -7.74981)
			(xy 62.368076 -7.805514) (xy 62.413287 -7.866369) (xy 62.451774 -7.931684) (xy 62.4831 -8.00072)
			(xy 62.50691 -8.072695) (xy 62.522935 -8.146793) (xy 62.530994 -8.222174) (xy 62.531498 -8.26008)
			(xy 62.530994 -8.297986) (xy 62.522935 -8.373367) (xy 62.50691 -8.447465) (xy 62.4831 -8.51944) (xy 62.451774 -8.588476)
			(xy 62.413287 -8.653791) (xy 62.368076 -8.714646) (xy 62.316652 -8.77035) (xy 62.259599 -8.820272)
			(xy 62.197563 -8.863847) (xy 62.131246 -8.900582) (xy 62.0614 -8.930059) (xy 61.988817 -8.951945)
			(xy 61.914319 -8.965992) (xy 61.838749 -8.972041) (xy 61.762965 -8.970022) (xy 61.687825 -8.95996)
			(xy 61.61418 -8.941968) (xy 61.542864 -8.91625) (xy 61.474687 -8.883098) (xy 61.410419 -8.842886)
			(xy 61.35079 -8.796071) (xy 61.296474 -8.743183) (xy 61.248088 -8.684821) (xy 61.20618 -8.621646)
			(xy 61.171224 -8.554375) (xy 61.143617 -8.48377) (xy 61.123671 -8.410629) (xy 61.111612 -8.335784)
			(xy 61.107577 -8.26008) (xy 59.991498 -8.26008) (xy 59.990994 -8.297986) (xy 59.982935 -8.373367)
			(xy 59.96691 -8.447465) (xy 59.9431 -8.51944) (xy 59.911774 -8.588476) (xy 59.873287 -8.653791) (xy 59.828076 -8.714646)
			(xy 59.776652 -8.77035) (xy 59.719599 -8.820272) (xy 59.657563 -8.863847) (xy 59.591246 -8.900582)
			(xy 59.5214 -8.930059) (xy 59.448817 -8.951945) (xy 59.374319 -8.965992) (xy 59.298749 -8.972041)
			(xy 59.222965 -8.970022) (xy 59.147825 -8.95996) (xy 59.07418 -8.941968) (xy 59.002864 -8.91625)
			(xy 58.934687 -8.883098) (xy 58.870419 -8.842886) (xy 58.81079 -8.796071) (xy 58.756474 -8.743183)
			(xy 58.708088 -8.684821) (xy 58.66618 -8.621646) (xy 58.631224 -8.554375) (xy 58.603617 -8.48377)
			(xy 58.583671 -8.410629) (xy 58.571612 -8.335784) (xy 58.567577 -8.26008) (xy 57.451498 -8.26008)
			(xy 57.450994 -8.297986) (xy 57.442935 -8.373367) (xy 57.42691 -8.447465) (xy 57.4031 -8.51944) (xy 57.371774 -8.588476)
			(xy 57.333287 -8.653791) (xy 57.288076 -8.714646) (xy 57.236652 -8.77035) (xy 57.179599 -8.820272)
			(xy 57.117563 -8.863847) (xy 57.051246 -8.900582) (xy 56.9814 -8.930059) (xy 56.908817 -8.951945)
			(xy 56.834319 -8.965992) (xy 56.758749 -8.972041) (xy 56.682965 -8.970022) (xy 56.607825 -8.95996)
			(xy 56.53418 -8.941968) (xy 56.462864 -8.91625) (xy 56.394687 -8.883098) (xy 56.330419 -8.842886)
			(xy 56.27079 -8.796071) (xy 56.216474 -8.743183) (xy 56.168088 -8.684821) (xy 56.12618 -8.621646)
			(xy 56.091224 -8.554375) (xy 56.063617 -8.48377) (xy 56.043671 -8.410629) (xy 56.031612 -8.335784)
			(xy 56.027577 -8.26008) (xy 54.911498 -8.26008) (xy 54.910994 -8.297986) (xy 54.902935 -8.373367)
			(xy 54.88691 -8.447465) (xy 54.8631 -8.51944) (xy 54.831774 -8.588476) (xy 54.793287 -8.653791) (xy 54.748076 -8.714646)
			(xy 54.696652 -8.77035) (xy 54.639599 -8.820272) (xy 54.577563 -8.863847) (xy 54.511246 -8.900582)
			(xy 54.4414 -8.930059) (xy 54.368817 -8.951945) (xy 54.294319 -8.965992) (xy 54.218749 -8.972041)
			(xy 54.142965 -8.970022) (xy 54.067825 -8.95996) (xy 53.99418 -8.941968) (xy 53.922864 -8.91625)
			(xy 53.854687 -8.883098) (xy 53.790419 -8.842886) (xy 53.73079 -8.796071) (xy 53.676474 -8.743183)
			(xy 53.628088 -8.684821) (xy 53.58618 -8.621646) (xy 53.551224 -8.554375) (xy 53.523617 -8.48377)
			(xy 53.503671 -8.410629) (xy 53.491612 -8.335784) (xy 53.487577 -8.26008) (xy 52.371498 -8.26008)
			(xy 52.370994 -8.297986) (xy 52.362935 -8.373367) (xy 52.34691 -8.447465) (xy 52.3231 -8.51944) (xy 52.291774 -8.588476)
			(xy 52.253287 -8.653791) (xy 52.208076 -8.714646) (xy 52.156652 -8.77035) (xy 52.099599 -8.820272)
			(xy 52.037563 -8.863847) (xy 51.971246 -8.900582) (xy 51.9014 -8.930059) (xy 51.828817 -8.951945)
			(xy 51.754319 -8.965992) (xy 51.678749 -8.972041) (xy 51.602965 -8.970022) (xy 51.527825 -8.95996)
			(xy 51.45418 -8.941968) (xy 51.382864 -8.91625) (xy 51.314687 -8.883098) (xy 51.250419 -8.842886)
			(xy 51.19079 -8.796071) (xy 51.136474 -8.743183) (xy 51.088088 -8.684821) (xy 51.04618 -8.621646)
			(xy 51.011224 -8.554375) (xy 50.983617 -8.48377) (xy 50.963671 -8.410629) (xy 50.951612 -8.335784)
			(xy 50.947577 -8.26008) (xy 49.831498 -8.26008) (xy 49.830994 -8.297986) (xy 49.822935 -8.373367)
			(xy 49.80691 -8.447465) (xy 49.7831 -8.51944) (xy 49.751774 -8.588476) (xy 49.713287 -8.653791) (xy 49.668076 -8.714646)
			(xy 49.616652 -8.77035) (xy 49.559599 -8.820272) (xy 49.497563 -8.863847) (xy 49.431246 -8.900582)
			(xy 49.3614 -8.930059) (xy 49.288817 -8.951945) (xy 49.214319 -8.965992) (xy 49.138749 -8.972041)
			(xy 49.062965 -8.970022) (xy 48.987825 -8.95996) (xy 48.91418 -8.941968) (xy 48.842864 -8.91625)
			(xy 48.774687 -8.883098) (xy 48.710419 -8.842886) (xy 48.65079 -8.796071) (xy 48.596474 -8.743183)
			(xy 48.548088 -8.684821) (xy 48.50618 -8.621646) (xy 48.471224 -8.554375) (xy 48.443617 -8.48377)
			(xy 48.423671 -8.410629) (xy 48.411612 -8.335784) (xy 48.407577 -8.26008) (xy 47.291498 -8.26008)
			(xy 47.290994 -8.297986) (xy 47.282935 -8.373367) (xy 47.26691 -8.447465) (xy 47.2431 -8.51944) (xy 47.211774 -8.588476)
			(xy 47.173287 -8.653791) (xy 47.128076 -8.714646) (xy 47.076652 -8.77035) (xy 47.019599 -8.820272)
			(xy 46.957563 -8.863847) (xy 46.891246 -8.900582) (xy 46.8214 -8.930059) (xy 46.748817 -8.951945)
			(xy 46.674319 -8.965992) (xy 46.598749 -8.972041) (xy 46.522965 -8.970022) (xy 46.447825 -8.95996)
			(xy 46.37418 -8.941968) (xy 46.302864 -8.91625) (xy 46.234687 -8.883098) (xy 46.170419 -8.842886)
			(xy 46.11079 -8.796071) (xy 46.056474 -8.743183) (xy 46.008088 -8.684821) (xy 45.96618 -8.621646)
			(xy 45.931224 -8.554375) (xy 45.903617 -8.48377) (xy 45.883671 -8.410629) (xy 45.871612 -8.335784)
			(xy 45.867577 -8.26008) (xy 44.751498 -8.26008) (xy 44.750994 -8.297986) (xy 44.742935 -8.373367)
			(xy 44.72691 -8.447465) (xy 44.7031 -8.51944) (xy 44.671774 -8.588476) (xy 44.633287 -8.653791) (xy 44.588076 -8.714646)
			(xy 44.536652 -8.77035) (xy 44.479599 -8.820272) (xy 44.417563 -8.863847) (xy 44.351246 -8.900582)
			(xy 44.2814 -8.930059) (xy 44.208817 -8.951945) (xy 44.134319 -8.965992) (xy 44.058749 -8.972041)
			(xy 43.982965 -8.970022) (xy 43.907825 -8.95996) (xy 43.83418 -8.941968) (xy 43.762864 -8.91625)
			(xy 43.694687 -8.883098) (xy 43.630419 -8.842886) (xy 43.57079 -8.796071) (xy 43.516474 -8.743183)
			(xy 43.468088 -8.684821) (xy 43.42618 -8.621646) (xy 43.391224 -8.554375) (xy 43.363617 -8.48377)
			(xy 43.343671 -8.410629) (xy 43.331612 -8.335784) (xy 43.327577 -8.26008) (xy 42.500813 -8.26008)
			(xy 42.479042 -8.276857) (xy 42.381609 -8.341665) (xy 42.279905 -8.39954) (xy 42.174422 -8.450202)
			(xy 42.065671 -8.493404) (xy 41.954179 -8.528939) (xy 41.840485 -8.556634) (xy 41.725141 -8.576354)
			(xy 41.608704 -8.588005) (xy 41.491739 -8.59153) (xy 41.374812 -8.586912) (xy 41.258489 -8.574173)
			(xy 41.143334 -8.553375) (xy 41.029905 -8.524618) (xy 40.91875 -8.488042) (xy 40.810407 -8.443825)
			(xy 40.705403 -8.392179) (xy 40.604244 -8.333356) (xy 40.507421 -8.26764) (xy 40.415403 -8.195349)
			(xy 40.328636 -8.116834) (xy 40.247539 -8.032474) (xy 40.172506 -7.942679) (xy 40.103899 -7.847883)
			(xy 40.042051 -7.748544) (xy 39.987262 -7.645145) (xy 39.939796 -7.538186) (xy 39.899884 -7.428185)
			(xy 39.86772 -7.315674) (xy 39.843457 -7.201199) (xy 39.827215 -7.085313) (xy 39.819072 -6.968579)
			(xy 39.818564 -6.91007) (xy 36.454201 -6.91007) (xy 36.4555 -6.914635) (xy 36.471468 -7.000055) (xy 36.479486 -7.086584)
			(xy 36.479988 -7.130034) (xy 36.479486 -7.173484) (xy 36.471468 -7.260013) (xy 36.4555 -7.345433)
			(xy 36.431719 -7.429015) (xy 36.400327 -7.510047) (xy 36.361593 -7.587836) (xy 36.315846 -7.66172)
			(xy 36.263477 -7.731067) (xy 36.204933 -7.795287) (xy 36.140713 -7.853831) (xy 36.071366 -7.9062)
			(xy 35.997482 -7.951947) (xy 35.919693 -7.990681) (xy 35.838661 -8.022073) (xy 35.755079 -8.045854)
			(xy 35.669659 -8.061822) (xy 35.58313 -8.06984) (xy 35.49623 -8.06984) (xy 35.409701 -8.061822) (xy 35.324281 -8.045854)
			(xy 35.240699 -8.022073) (xy 35.159667 -7.990681) (xy 35.081878 -7.951947) (xy 35.007994 -7.9062)
			(xy 34.938647 -7.853831) (xy 34.874427 -7.795287) (xy 34.815883 -7.731067) (xy 34.763514 -7.66172)
			(xy 34.717767 -7.587836) (xy 34.679033 -7.510047) (xy 34.647641 -7.429015) (xy 34.62386 -7.345433)
			(xy 34.607892 -7.260013) (xy 34.599874 -7.173484) (xy 31.399486 -7.173484) (xy 31.391468 -7.260013)
			(xy 31.3755 -7.345433) (xy 31.351719 -7.429015) (xy 31.320327 -7.510047) (xy 31.281593 -7.587836)
			(xy 31.235846 -7.66172) (xy 31.183477 -7.731067) (xy 31.124933 -7.795287) (xy 31.060713 -7.853831)
			(xy 30.991366 -7.9062) (xy 30.917482 -7.951947) (xy 30.839693 -7.990681) (xy 30.758661 -8.022073)
			(xy 30.675079 -8.045854) (xy 30.589659 -8.061822) (xy 30.50313 -8.06984) (xy 30.41623 -8.06984) (xy 30.329701 -8.061822)
			(xy 30.244281 -8.045854) (xy 30.160699 -8.022073) (xy 30.079667 -7.990681) (xy 30.001878 -7.951947)
			(xy 29.927994 -7.9062) (xy 29.858647 -7.853831) (xy 29.794427 -7.795287) (xy 29.735883 -7.731067)
			(xy 29.683514 -7.66172) (xy 29.637767 -7.587836) (xy 29.599033 -7.510047) (xy 29.567641 -7.429015)
			(xy 29.54386 -7.345433) (xy 29.527892 -7.260013) (xy 29.519874 -7.173484) (xy 9.618189 -7.173484)
			(xy 9.649526 -7.296805) (xy 9.673578 -7.424182) (xy 9.689665 -7.552808) (xy 9.697724 -7.682186) (xy 9.698228 -7.747)
			(xy 9.697724 -7.811814) (xy 9.689665 -7.941192) (xy 9.673578 -8.069818) (xy 9.649526 -8.197195) (xy 9.617601 -8.322831)
			(xy 9.577928 -8.446239) (xy 9.530658 -8.566942) (xy 9.475977 -8.684472) (xy 9.414094 -8.798376) (xy 9.345249 -8.908212)
			(xy 9.26971 -9.013555) (xy 9.187767 -9.113998) (xy 9.099738 -9.209153) (xy 9.005964 -9.298651) (xy 8.906807 -9.382146)
			(xy 8.802651 -9.459315) (xy 8.693899 -9.529859) (xy 8.580971 -9.593506) (xy 8.464306 -9.650009) (xy 8.344353 -9.69915)
			(xy 8.221577 -9.740738) (xy 8.096453 -9.774613) (xy 7.969465 -9.800643) (xy 7.841104 -9.818728) (xy 7.711868 -9.828798)
			(xy 7.582255 -9.830814) (xy 7.452768 -9.824768) (xy 7.323907 -9.810684) (xy 7.196171 -9.788615) (xy 7.070054 -9.758648)
			(xy 6.946044 -9.720899) (xy 6.824621 -9.675512) (xy 6.706254 -9.622665) (xy 6.591402 -9.562561) (xy 6.480509 -9.495433)
			(xy 6.374003 -9.421541) (xy 6.272297 -9.34117) (xy 6.175785 -9.254632) (xy 6.08484 -9.16226) (xy 5.999813 -9.064414)
			(xy 5.921033 -8.961471) (xy 5.848806 -8.853829) (xy 5.783411 -8.741905) (xy 5.7251 -8.626132) (xy 5.6741 -8.506958)
			(xy 5.630608 -8.384844) (xy 5.594791 -8.260261) (xy 5.566789 -8.133694) (xy 5.54671 -8.00563) (xy 5.534631 -7.876566)
			(xy 5.5306 -7.747) (xy 1.27 -7.747) (xy 1.27 -28.952635) (xy 4.852911 -28.952635) (xy 4.852911 -28.866909)
			(xy 4.860821 -28.781549) (xy 4.876573 -28.697282) (xy 4.900033 -28.614829) (xy 4.931001 -28.534892)
			(xy 4.969212 -28.458153) (xy 5.014341 -28.385267) (xy 5.066002 -28.316856) (xy 5.123756 -28.253504)
			(xy 5.187108 -28.19575) (xy 5.255519 -28.144089) (xy 5.328405 -28.09896) (xy 5.405144 -28.060749)
			(xy 5.485081 -28.029781) (xy 5.567534 -28.006321) (xy 5.651801 -27.990569) (xy 5.737161 -27.982659)
			(xy 5.822887 -27.982659) (xy 5.908247 -27.990569) (xy 5.992514 -28.006321) (xy 6.074967 -28.029781)
			(xy 6.154904 -28.060749) (xy 6.231643 -28.09896) (xy 6.304529 -28.144089) (xy 6.37294 -28.19575)
			(xy 6.436292 -28.253504) (xy 6.494046 -28.316856) (xy 6.545707 -28.385267) (xy 6.590836 -28.458153)
			(xy 6.629047 -28.534892) (xy 6.660015 -28.614829) (xy 6.683475 -28.697282) (xy 6.699227 -28.781549)
			(xy 6.707137 -28.866909) (xy 6.707632 -28.909772) (xy 6.707137 -28.952635) (xy 6.699227 -29.037995)
			(xy 6.683475 -29.122262) (xy 6.660015 -29.204715) (xy 6.629047 -29.284652) (xy 6.590836 -29.361391)
			(xy 6.545707 -29.434277) (xy 6.494046 -29.502688) (xy 6.436292 -29.56604) (xy 6.37294 -29.623794)
			(xy 6.304529 -29.675455) (xy 6.231643 -29.720584) (xy 6.154904 -29.758795) (xy 6.074967 -29.789763)
			(xy 5.992514 -29.813223) (xy 5.908247 -29.828975) (xy 5.822887 -29.836885) (xy 5.737161 -29.836885)
			(xy 5.651801 -29.828975) (xy 5.567534 -29.813223) (xy 5.485081 -29.789763) (xy 5.405144 -29.758795)
			(xy 5.328405 -29.720584) (xy 5.255519 -29.675455) (xy 5.187108 -29.623794) (xy 5.123756 -29.56604)
			(xy 5.066002 -29.502688) (xy 5.014341 -29.434277) (xy 4.969212 -29.361391) (xy 4.931001 -29.284652)
			(xy 4.900033 -29.204715) (xy 4.876573 -29.122262) (xy 4.860821 -29.037995) (xy 4.852911 -28.952635)
			(xy 1.27 -28.952635) (xy 1.27 -31.952629) (xy 4.852911 -31.952629) (xy 4.852911 -31.866903) (xy 4.860821 -31.781543)
			(xy 4.876573 -31.697276) (xy 4.900033 -31.614823) (xy 4.931001 -31.534886) (xy 4.969212 -31.458147)
			(xy 5.014341 -31.385261) (xy 5.066002 -31.31685) (xy 5.123756 -31.253498) (xy 5.187108 -31.195744)
			(xy 5.255519 -31.144083) (xy 5.328405 -31.098954) (xy 5.405144 -31.060743) (xy 5.485081 -31.029775)
			(xy 5.567534 -31.006315) (xy 5.651801 -30.990563) (xy 5.737161 -30.982653) (xy 5.822887 -30.982653)
			(xy 5.908247 -30.990563) (xy 5.992514 -31.006315) (xy 6.074967 -31.029775) (xy 6.154904 -31.060743)
			(xy 6.231643 -31.098954) (xy 6.304529 -31.144083) (xy 6.37294 -31.195744) (xy 6.436292 -31.253498)
			(xy 6.494046 -31.31685) (xy 6.545707 -31.385261) (xy 6.590836 -31.458147) (xy 6.629047 -31.534886)
			(xy 6.660015 -31.614823) (xy 6.683475 -31.697276) (xy 6.699227 -31.781543) (xy 6.707137 -31.866903)
			(xy 6.707632 -31.909766) (xy 6.707137 -31.952629) (xy 6.699227 -32.037989) (xy 6.683475 -32.122256)
			(xy 6.660015 -32.204709) (xy 6.629047 -32.284646) (xy 6.590836 -32.361385) (xy 6.545707 -32.434271)
			(xy 6.494046 -32.502682) (xy 6.436292 -32.566034) (xy 6.37294 -32.623788) (xy 6.304529 -32.675449)
			(xy 6.231643 -32.720578) (xy 6.154904 -32.758789) (xy 6.074967 -32.789757) (xy 5.992514 -32.813217)
			(xy 5.908247 -32.828969) (xy 5.822887 -32.836879) (xy 5.737161 -32.836879) (xy 5.651801 -32.828969)
			(xy 5.567534 -32.813217) (xy 5.485081 -32.789757) (xy 5.405144 -32.758789) (xy 5.328405 -32.720578)
			(xy 5.255519 -32.675449) (xy 5.187108 -32.623788) (xy 5.123756 -32.566034) (xy 5.066002 -32.502682)
			(xy 5.014341 -32.434271) (xy 4.969212 -32.361385) (xy 4.931001 -32.284646) (xy 4.900033 -32.204709)
			(xy 4.876573 -32.122256) (xy 4.860821 -32.037989) (xy 4.852911 -31.952629) (xy 1.27 -31.952629) (xy 1.27 -34.90976)
			(xy 6.671831 -34.90976) (xy 6.675786 -34.817923) (xy 6.687621 -34.726766) (xy 6.707248 -34.636963)
			(xy 6.734522 -34.549181) (xy 6.769242 -34.464067) (xy 6.81115 -34.382254) (xy 6.859936 -34.304346)
			(xy 6.915239 -34.230921) (xy 6.976649 -34.162521) (xy 7.043711 -34.099654) (xy 7.11593 -34.042784)
			(xy 7.19277 -33.992333) (xy 7.273663 -33.948674) (xy 7.358009 -33.912131) (xy 7.445185 -33.882974)
			(xy 7.534544 -33.86142) (xy 7.625425 -33.847626) (xy 7.717156 -33.841696) (xy 7.809057 -33.843674)
			(xy 7.900448 -33.853545) (xy 7.990652 -33.871235) (xy 8.079001 -33.896615) (xy 8.164841 -33.929495)
			(xy 8.247537 -33.969633) (xy 8.326477 -34.016732) (xy 8.401075 -34.070442) (xy 8.470781 -34.130366)
			(xy 8.535076 -34.19606) (xy 8.593487 -34.267038) (xy 8.645579 -34.342775) (xy 8.690968 -34.42271)
			(xy 8.729318 -34.50625) (xy 8.760343 -34.592778) (xy 8.783816 -34.681653) (xy 8.799562 -34.772217)
			(xy 8.807464 -34.863799) (xy 8.807958 -34.90976) (xy 8.807464 -34.955721) (xy 8.799562 -35.047303)
			(xy 8.783816 -35.137867) (xy 8.760343 -35.226742) (xy 8.729318 -35.31327) (xy 8.690968 -35.39681)
			(xy 8.645579 -35.476745) (xy 8.593487 -35.552482) (xy 8.535076 -35.62346) (xy 8.470781 -35.689154)
			(xy 8.401075 -35.749078) (xy 8.326477 -35.802788) (xy 8.247537 -35.849887) (xy 8.164841 -35.890025)
			(xy 8.079001 -35.922905) (xy 7.990652 -35.948285) (xy 7.900448 -35.965975) (xy 7.809057 -35.975846)
			(xy 7.717156 -35.977824) (xy 7.625425 -35.971894) (xy 7.534544 -35.9581) (xy 7.445185 -35.936546)
			(xy 7.358009 -35.907389) (xy 7.273663 -35.870846) (xy 7.19277 -35.827187) (xy 7.11593 -35.776736)
			(xy 7.043711 -35.719866) (xy 6.976649 -35.656999) (xy 6.915239 -35.588599) (xy 6.859936 -35.515174)
			(xy 6.81115 -35.437266) (xy 6.769242 -35.355453) (xy 6.734522 -35.270339) (xy 6.707248 -35.182557)
			(xy 6.687621 -35.092754) (xy 6.675786 -35.001597) (xy 6.671831 -34.90976) (xy 1.27 -34.90976) (xy 1.27 -42.291)
			(xy 5.5306 -42.291) (xy 5.534631 -42.161434) (xy 5.54671 -42.03237) (xy 5.566789 -41.904306) (xy 5.594791 -41.777739)
			(xy 5.630608 -41.653156) (xy 5.6741 -41.531042) (xy 5.7251 -41.411868) (xy 5.783411 -41.296095) (xy 5.848806 -41.184171)
			(xy 5.921033 -41.076529) (xy 5.999813 -40.973586) (xy 6.08484 -40.87574) (xy 6.175785 -40.783368)
			(xy 6.272297 -40.69683) (xy 6.374003 -40.616459) (xy 6.480509 -40.542567) (xy 6.591402 -40.475439)
			(xy 6.706254 -40.415335) (xy 6.824621 -40.362488) (xy 6.946044 -40.317101) (xy 7.070054 -40.279352)
			(xy 7.196171 -40.249385) (xy 7.323907 -40.227316) (xy 7.452768 -40.213232) (xy 7.582255 -40.207186)
			(xy 7.711868 -40.209202) (xy 7.841104 -40.219272) (xy 7.969465 -40.237357) (xy 8.096453 -40.263387)
			(xy 8.221577 -40.297262) (xy 8.344353 -40.33885) (xy 8.464306 -40.387991) (xy 8.580971 -40.444494)
			(xy 8.693899 -40.508141) (xy 8.802651 -40.578685) (xy 8.906807 -40.655854) (xy 9.005964 -40.739349)
			(xy 9.099738 -40.828847) (xy 9.187767 -40.924002) (xy 9.26971 -41.024445) (xy 9.345249 -41.129788)
			(xy 9.414094 -41.239624) (xy 9.475977 -41.353528) (xy 9.530658 -41.471058) (xy 9.577928 -41.591761)
			(xy 9.617601 -41.715169) (xy 9.649526 -41.840805) (xy 9.673578 -41.968182) (xy 9.689665 -42.096808)
			(xy 9.697724 -42.226186) (xy 9.698228 -42.291) (xy 9.697724 -42.355814) (xy 9.689665 -42.485192)
			(xy 9.673578 -42.613818) (xy 9.649526 -42.741195) (xy 9.617601 -42.866831) (xy 9.577928 -42.990239)
			(xy 9.530658 -43.110942) (xy 9.475977 -43.228472) (xy 9.414094 -43.342376) (xy 9.345249 -43.452212)
			(xy 9.26971 -43.557555) (xy 9.233814 -43.601555) (xy 15.679156 -43.601555) (xy 15.679156 -43.520445)
			(xy 15.687106 -43.439726) (xy 15.702929 -43.360175) (xy 15.726474 -43.282559) (xy 15.757513 -43.207623)
			(xy 15.795748 -43.136091) (xy 15.84081 -43.068651) (xy 15.892265 -43.005952) (xy 15.949618 -42.948599)
			(xy 16.012317 -42.897144) (xy 16.079757 -42.852082) (xy 16.151289 -42.813847) (xy 16.226225 -42.782808)
			(xy 16.303841 -42.759263) (xy 16.383392 -42.74344) (xy 16.464111 -42.73549) (xy 16.545221 -42.73549)
			(xy 16.62594 -42.74344) (xy 16.705491 -42.759263) (xy 16.783107 -42.782808) (xy 16.858043 -42.813847)
			(xy 16.929575 -42.852082) (xy 16.997015 -42.897144) (xy 17.059714 -42.948599) (xy 17.117067 -43.005952)
			(xy 17.168522 -43.068651) (xy 17.213584 -43.136091) (xy 17.251819 -43.207623) (xy 17.282858 -43.282559)
			(xy 17.306403 -43.360175) (xy 17.322226 -43.439726) (xy 17.330176 -43.520445) (xy 17.330674 -43.561)
			(xy 17.330176 -43.601555) (xy 17.322226 -43.682274) (xy 17.306403 -43.761825) (xy 17.282858 -43.839441)
			(xy 17.251819 -43.914377) (xy 17.213584 -43.985909) (xy 17.168522 -44.053349) (xy 17.117067 -44.116048)
			(xy 17.059714 -44.173401) (xy 16.997015 -44.224856) (xy 16.929575 -44.269918) (xy 16.858043 -44.308153)
			(xy 16.783107 -44.339192) (xy 16.705491 -44.362737) (xy 16.62594 -44.37856) (xy 16.545221 -44.38651)
			(xy 16.464111 -44.38651) (xy 16.383392 -44.37856) (xy 16.303841 -44.362737) (xy 16.226225 -44.339192)
			(xy 16.151289 -44.308153) (xy 16.079757 -44.269918) (xy 16.012317 -44.224856) (xy 15.949618 -44.173401)
			(xy 15.892265 -44.116048) (xy 15.84081 -44.053349) (xy 15.795748 -43.985909) (xy 15.757513 -43.914377)
			(xy 15.726474 -43.839441) (xy 15.702929 -43.761825) (xy 15.687106 -43.682274) (xy 15.679156 -43.601555)
			(xy 9.233814 -43.601555) (xy 9.187767 -43.657998) (xy 9.099738 -43.753153) (xy 9.005964 -43.842651)
			(xy 8.906807 -43.926146) (xy 8.802651 -44.003315) (xy 8.693899 -44.073859) (xy 8.580971 -44.137506)
			(xy 8.464306 -44.194009) (xy 8.344353 -44.24315) (xy 8.221577 -44.284738) (xy 8.096453 -44.318613)
			(xy 7.969465 -44.344643) (xy 7.841104 -44.362728) (xy 7.711868 -44.372798) (xy 7.582255 -44.374814)
			(xy 7.452768 -44.368768) (xy 7.323907 -44.354684) (xy 7.196171 -44.332615) (xy 7.070054 -44.302648)
			(xy 6.946044 -44.264899) (xy 6.824621 -44.219512) (xy 6.706254 -44.166665) (xy 6.591402 -44.106561)
			(xy 6.480509 -44.039433) (xy 6.374003 -43.965541) (xy 6.272297 -43.88517) (xy 6.175785 -43.798632)
			(xy 6.08484 -43.70626) (xy 5.999813 -43.608414) (xy 5.921033 -43.505471) (xy 5.848806 -43.397829)
			(xy 5.783411 -43.285905) (xy 5.7251 -43.170132) (xy 5.6741 -43.050958) (xy 5.630608 -42.928844) (xy 5.594791 -42.804261)
			(xy 5.566789 -42.677694) (xy 5.54671 -42.54963) (xy 5.534631 -42.420566) (xy 5.5306 -42.291) (xy 1.27 -42.291)
			(xy 1.27 -44.871555) (xy 13.139156 -44.871555) (xy 13.139156 -44.790445) (xy 13.147106 -44.709726)
			(xy 13.162929 -44.630175) (xy 13.186474 -44.552559) (xy 13.217513 -44.477623) (xy 13.255748 -44.406091)
			(xy 13.30081 -44.338651) (xy 13.352265 -44.275952) (xy 13.409618 -44.218599) (xy 13.472317 -44.167144)
			(xy 13.539757 -44.122082) (xy 13.611289 -44.083847) (xy 13.686225 -44.052808) (xy 13.763841 -44.029263)
			(xy 13.843392 -44.01344) (xy 13.924111 -44.00549) (xy 14.005221 -44.00549) (xy 14.08594 -44.01344)
			(xy 14.165491 -44.029263) (xy 14.243107 -44.052808) (xy 14.318043 -44.083847) (xy 14.389575 -44.122082)
			(xy 14.457015 -44.167144) (xy 14.519714 -44.218599) (xy 14.577067 -44.275952) (xy 14.628522 -44.338651)
			(xy 14.673584 -44.406091) (xy 14.711819 -44.477623) (xy 14.742858 -44.552559) (xy 14.766403 -44.630175)
			(xy 14.782226 -44.709726) (xy 14.790176 -44.790445) (xy 14.790674 -44.831) (xy 14.790176 -44.871555)
			(xy 14.782226 -44.952274) (xy 14.766403 -45.031825) (xy 14.742858 -45.109441) (xy 14.711819 -45.184377)
			(xy 14.673584 -45.255909) (xy 14.628522 -45.323349) (xy 14.577067 -45.386048) (xy 14.519714 -45.443401)
			(xy 14.457015 -45.494856) (xy 14.389575 -45.539918) (xy 14.318043 -45.578153) (xy 14.243107 -45.609192)
			(xy 14.165491 -45.632737) (xy 14.08594 -45.64856) (xy 14.005221 -45.65651) (xy 13.924111 -45.65651)
			(xy 13.843392 -45.64856) (xy 13.763841 -45.632737) (xy 13.686225 -45.609192) (xy 13.611289 -45.578153)
			(xy 13.539757 -45.539918) (xy 13.472317 -45.494856) (xy 13.409618 -45.443401) (xy 13.352265 -45.386048)
			(xy 13.30081 -45.323349) (xy 13.255748 -45.255909) (xy 13.217513 -45.184377) (xy 13.186474 -45.109441)
			(xy 13.162929 -45.031825) (xy 13.147106 -44.952274) (xy 13.139156 -44.871555) (xy 1.27 -44.871555)
			(xy 1.27 -46.141555) (xy 15.679156 -46.141555) (xy 15.679156 -46.060445) (xy 15.687106 -45.979726)
			(xy 15.702929 -45.900175) (xy 15.726474 -45.822559) (xy 15.757513 -45.747623) (xy 15.795748 -45.676091)
			(xy 15.84081 -45.608651) (xy 15.892265 -45.545952) (xy 15.949618 -45.488599) (xy 16.012317 -45.437144)
			(xy 16.079757 -45.392082) (xy 16.151289 -45.353847) (xy 16.226225 -45.322808) (xy 16.303841 -45.299263)
			(xy 16.383392 -45.28344) (xy 16.464111 -45.27549) (xy 16.545221 -45.27549) (xy 16.62594 -45.28344)
			(xy 16.705491 -45.299263) (xy 16.783107 -45.322808) (xy 16.858043 -45.353847) (xy 16.929575 -45.392082)
			(xy 16.997015 -45.437144) (xy 17.059714 -45.488599) (xy 17.117067 -45.545952) (xy 17.168522 -45.608651)
			(xy 17.213584 -45.676091) (xy 17.251819 -45.747623) (xy 17.282858 -45.822559) (xy 17.306403 -45.900175)
			(xy 17.322226 -45.979726) (xy 17.330176 -46.060445) (xy 17.330674 -46.101) (xy 17.330176 -46.141555)
			(xy 17.322226 -46.222274) (xy 17.306403 -46.301825) (xy 17.282858 -46.379441) (xy 17.251819 -46.454377)
			(xy 17.213584 -46.525909) (xy 17.168522 -46.593349) (xy 17.117067 -46.656048) (xy 17.059714 -46.713401)
			(xy 16.997015 -46.764856) (xy 16.929575 -46.809918) (xy 16.858043 -46.848153) (xy 16.783107 -46.879192)
			(xy 16.705491 -46.902737) (xy 16.62594 -46.91856) (xy 16.545221 -46.92651) (xy 16.464111 -46.92651)
			(xy 16.383392 -46.91856) (xy 16.303841 -46.902737) (xy 16.226225 -46.879192) (xy 16.151289 -46.848153)
			(xy 16.079757 -46.809918) (xy 16.012317 -46.764856) (xy 15.949618 -46.713401) (xy 15.892265 -46.656048)
			(xy 15.84081 -46.593349) (xy 15.795748 -46.525909) (xy 15.757513 -46.454377) (xy 15.726474 -46.379441)
			(xy 15.702929 -46.301825) (xy 15.687106 -46.222274) (xy 15.679156 -46.141555) (xy 1.27 -46.141555)
			(xy 1.27 -47.411555) (xy 13.139156 -47.411555) (xy 13.139156 -47.330445) (xy 13.147106 -47.249726)
			(xy 13.162929 -47.170175) (xy 13.186474 -47.092559) (xy 13.217513 -47.017623) (xy 13.255748 -46.946091)
			(xy 13.30081 -46.878651) (xy 13.352265 -46.815952) (xy 13.409618 -46.758599) (xy 13.472317 -46.707144)
			(xy 13.539757 -46.662082) (xy 13.611289 -46.623847) (xy 13.686225 -46.592808) (xy 13.763841 -46.569263)
			(xy 13.843392 -46.55344) (xy 13.924111 -46.54549) (xy 14.005221 -46.54549) (xy 14.08594 -46.55344)
			(xy 14.165491 -46.569263) (xy 14.243107 -46.592808) (xy 14.318043 -46.623847) (xy 14.389575 -46.662082)
			(xy 14.457015 -46.707144) (xy 14.519714 -46.758599) (xy 14.577067 -46.815952) (xy 14.628522 -46.878651)
			(xy 14.673584 -46.946091) (xy 14.711819 -47.017623) (xy 14.742858 -47.092559) (xy 14.766403 -47.170175)
			(xy 14.782226 -47.249726) (xy 14.790176 -47.330445) (xy 14.790674 -47.371) (xy 14.790176 -47.411555)
			(xy 14.782226 -47.492274) (xy 14.766403 -47.571825) (xy 14.742858 -47.649441) (xy 14.711819 -47.724377)
			(xy 14.673584 -47.795909) (xy 14.628522 -47.863349) (xy 14.577067 -47.926048) (xy 14.519714 -47.983401)
			(xy 14.457015 -48.034856) (xy 14.389575 -48.079918) (xy 14.318043 -48.118153) (xy 14.243107 -48.149192)
			(xy 14.165491 -48.172737) (xy 14.08594 -48.18856) (xy 14.005221 -48.19651) (xy 13.924111 -48.19651)
			(xy 13.843392 -48.18856) (xy 13.763841 -48.172737) (xy 13.686225 -48.149192) (xy 13.611289 -48.118153)
			(xy 13.539757 -48.079918) (xy 13.472317 -48.034856) (xy 13.409618 -47.983401) (xy 13.352265 -47.926048)
			(xy 13.30081 -47.863349) (xy 13.255748 -47.795909) (xy 13.217513 -47.724377) (xy 13.186474 -47.649441)
			(xy 13.162929 -47.571825) (xy 13.147106 -47.492274) (xy 13.139156 -47.411555) (xy 1.27 -47.411555)
			(xy 1.27 -48.681555) (xy 15.679156 -48.681555) (xy 15.679156 -48.600445) (xy 15.687106 -48.519726)
			(xy 15.702929 -48.440175) (xy 15.726474 -48.362559) (xy 15.757513 -48.287623) (xy 15.795748 -48.216091)
			(xy 15.84081 -48.148651) (xy 15.892265 -48.085952) (xy 15.949618 -48.028599) (xy 16.012317 -47.977144)
			(xy 16.079757 -47.932082) (xy 16.151289 -47.893847) (xy 16.226225 -47.862808) (xy 16.303841 -47.839263)
			(xy 16.383392 -47.82344) (xy 16.464111 -47.81549) (xy 16.545221 -47.81549) (xy 16.62594 -47.82344)
			(xy 16.705491 -47.839263) (xy 16.783107 -47.862808) (xy 16.858043 -47.893847) (xy 16.929575 -47.932082)
			(xy 16.997015 -47.977144) (xy 17.059714 -48.028599) (xy 17.117067 -48.085952) (xy 17.168522 -48.148651)
			(xy 17.213584 -48.216091) (xy 17.251819 -48.287623) (xy 17.282858 -48.362559) (xy 17.306403 -48.440175)
			(xy 17.322226 -48.519726) (xy 17.330176 -48.600445) (xy 17.330674 -48.641) (xy 17.330176 -48.681555)
			(xy 17.322226 -48.762274) (xy 17.306403 -48.841825) (xy 17.282858 -48.919441) (xy 17.251819 -48.994377)
			(xy 17.213584 -49.065909) (xy 17.168522 -49.133349) (xy 17.117067 -49.196048) (xy 17.059714 -49.253401)
			(xy 16.997015 -49.304856) (xy 16.929575 -49.349918) (xy 16.858043 -49.388153) (xy 16.783107 -49.419192)
			(xy 16.705491 -49.442737) (xy 16.62594 -49.45856) (xy 16.545221 -49.46651) (xy 16.464111 -49.46651)
			(xy 16.383392 -49.45856) (xy 16.303841 -49.442737) (xy 16.226225 -49.419192) (xy 16.151289 -49.388153)
			(xy 16.079757 -49.349918) (xy 16.012317 -49.304856) (xy 15.949618 -49.253401) (xy 15.892265 -49.196048)
			(xy 15.84081 -49.133349) (xy 15.795748 -49.065909) (xy 15.757513 -48.994377) (xy 15.726474 -48.919441)
			(xy 15.702929 -48.841825) (xy 15.687106 -48.762274) (xy 15.679156 -48.681555) (xy 1.27 -48.681555)
			(xy 1.27 -49.951555) (xy 13.139156 -49.951555) (xy 13.139156 -49.870445) (xy 13.147106 -49.789726)
			(xy 13.162929 -49.710175) (xy 13.186474 -49.632559) (xy 13.217513 -49.557623) (xy 13.255748 -49.486091)
			(xy 13.30081 -49.418651) (xy 13.352265 -49.355952) (xy 13.409618 -49.298599) (xy 13.472317 -49.247144)
			(xy 13.539757 -49.202082) (xy 13.611289 -49.163847) (xy 13.686225 -49.132808) (xy 13.763841 -49.109263)
			(xy 13.843392 -49.09344) (xy 13.924111 -49.08549) (xy 14.005221 -49.08549) (xy 14.08594 -49.09344)
			(xy 14.165491 -49.109263) (xy 14.243107 -49.132808) (xy 14.318043 -49.163847) (xy 14.389575 -49.202082)
			(xy 14.457015 -49.247144) (xy 14.519714 -49.298599) (xy 14.577067 -49.355952) (xy 14.628522 -49.418651)
			(xy 14.673584 -49.486091) (xy 14.711819 -49.557623) (xy 14.742858 -49.632559) (xy 14.766403 -49.710175)
			(xy 14.782226 -49.789726) (xy 14.790176 -49.870445) (xy 14.790674 -49.911) (xy 14.790176 -49.951555)
			(xy 14.782226 -50.032274) (xy 14.766403 -50.111825) (xy 14.742858 -50.189441) (xy 14.711819 -50.264377)
			(xy 14.673584 -50.335909) (xy 14.628522 -50.403349) (xy 14.577067 -50.466048) (xy 14.519714 -50.523401)
			(xy 14.457015 -50.574856) (xy 14.389575 -50.619918) (xy 14.318043 -50.658153) (xy 14.243107 -50.689192)
			(xy 14.165491 -50.712737) (xy 14.08594 -50.72856) (xy 14.005221 -50.73651) (xy 13.924111 -50.73651)
			(xy 13.843392 -50.72856) (xy 13.763841 -50.712737) (xy 13.686225 -50.689192) (xy 13.611289 -50.658153)
			(xy 13.539757 -50.619918) (xy 13.472317 -50.574856) (xy 13.409618 -50.523401) (xy 13.352265 -50.466048)
			(xy 13.30081 -50.403349) (xy 13.255748 -50.335909) (xy 13.217513 -50.264377) (xy 13.186474 -50.189441)
			(xy 13.162929 -50.111825) (xy 13.147106 -50.032274) (xy 13.139156 -49.951555) (xy 1.27 -49.951555)
			(xy 1.27 -51.221555) (xy 15.679156 -51.221555) (xy 15.679156 -51.140445) (xy 15.687106 -51.059726)
			(xy 15.702929 -50.980175) (xy 15.726474 -50.902559) (xy 15.757513 -50.827623) (xy 15.795748 -50.756091)
			(xy 15.84081 -50.688651) (xy 15.892265 -50.625952) (xy 15.949618 -50.568599) (xy 16.012317 -50.517144)
			(xy 16.079757 -50.472082) (xy 16.151289 -50.433847) (xy 16.226225 -50.402808) (xy 16.303841 -50.379263)
			(xy 16.383392 -50.36344) (xy 16.464111 -50.35549) (xy 16.545221 -50.35549) (xy 16.62594 -50.36344)
			(xy 16.705491 -50.379263) (xy 16.783107 -50.402808) (xy 16.858043 -50.433847) (xy 16.929575 -50.472082)
			(xy 16.997015 -50.517144) (xy 17.059714 -50.568599) (xy 17.117067 -50.625952) (xy 17.168522 -50.688651)
			(xy 17.213584 -50.756091) (xy 17.251819 -50.827623) (xy 17.282858 -50.902559) (xy 17.306403 -50.980175)
			(xy 17.322226 -51.059726) (xy 17.330176 -51.140445) (xy 17.330674 -51.181) (xy 17.330176 -51.221555)
			(xy 17.322226 -51.302274) (xy 17.306403 -51.381825) (xy 17.282858 -51.459441) (xy 17.251819 -51.534377)
			(xy 17.213584 -51.605909) (xy 17.168522 -51.673349) (xy 17.117067 -51.736048) (xy 17.059714 -51.793401)
			(xy 16.997015 -51.844856) (xy 16.929575 -51.889918) (xy 16.858043 -51.928153) (xy 16.783107 -51.959192)
			(xy 16.705491 -51.982737) (xy 16.62594 -51.99856) (xy 16.545221 -52.00651) (xy 16.464111 -52.00651)
			(xy 16.383392 -51.99856) (xy 16.303841 -51.982737) (xy 16.226225 -51.959192) (xy 16.151289 -51.928153)
			(xy 16.079757 -51.889918) (xy 16.012317 -51.844856) (xy 15.949618 -51.793401) (xy 15.892265 -51.736048)
			(xy 15.84081 -51.673349) (xy 15.795748 -51.605909) (xy 15.757513 -51.534377) (xy 15.726474 -51.459441)
			(xy 15.702929 -51.381825) (xy 15.687106 -51.302274) (xy 15.679156 -51.221555) (xy 1.27 -51.221555)
			(xy 1.27 -53.721) (xy 5.5306 -53.721) (xy 5.534631 -53.591434) (xy 5.54671 -53.46237) (xy 5.566789 -53.334306)
			(xy 5.594791 -53.207739) (xy 5.630608 -53.083156) (xy 5.6741 -52.961042) (xy 5.7251 -52.841868) (xy 5.783411 -52.726095)
			(xy 5.848806 -52.614171) (xy 5.921033 -52.506529) (xy 5.999813 -52.403586) (xy 6.08484 -52.30574)
			(xy 6.175785 -52.213368) (xy 6.272297 -52.12683) (xy 6.374003 -52.046459) (xy 6.480509 -51.972567)
			(xy 6.591402 -51.905439) (xy 6.706254 -51.845335) (xy 6.824621 -51.792488) (xy 6.946044 -51.747101)
			(xy 7.070054 -51.709352) (xy 7.196171 -51.679385) (xy 7.323907 -51.657316) (xy 7.452768 -51.643232)
			(xy 7.582255 -51.637186) (xy 7.711868 -51.639202) (xy 7.841104 -51.649272) (xy 7.969465 -51.667357)
			(xy 8.096453 -51.693387) (xy 8.221577 -51.727262) (xy 8.344353 -51.76885) (xy 8.464306 -51.817991)
			(xy 8.580971 -51.874494) (xy 8.693899 -51.938141) (xy 8.802651 -52.008685) (xy 8.906807 -52.085854)
			(xy 9.005964 -52.169349) (xy 9.099738 -52.258847) (xy 9.187767 -52.354002) (xy 9.26971 -52.454445)
			(xy 9.296321 -52.491555) (xy 13.139156 -52.491555) (xy 13.139156 -52.410445) (xy 13.147106 -52.329726)
			(xy 13.162929 -52.250175) (xy 13.186474 -52.172559) (xy 13.217513 -52.097623) (xy 13.255748 -52.026091)
			(xy 13.30081 -51.958651) (xy 13.352265 -51.895952) (xy 13.409618 -51.838599) (xy 13.472317 -51.787144)
			(xy 13.539757 -51.742082) (xy 13.611289 -51.703847) (xy 13.686225 -51.672808) (xy 13.763841 -51.649263)
			(xy 13.843392 -51.63344) (xy 13.924111 -51.62549) (xy 14.005221 -51.62549) (xy 14.08594 -51.63344)
			(xy 14.165491 -51.649263) (xy 14.243107 -51.672808) (xy 14.318043 -51.703847) (xy 14.389575 -51.742082)
			(xy 14.457015 -51.787144) (xy 14.519714 -51.838599) (xy 14.577067 -51.895952) (xy 14.628522 -51.958651)
			(xy 14.673584 -52.026091) (xy 14.711819 -52.097623) (xy 14.742858 -52.172559) (xy 14.766403 -52.250175)
			(xy 14.782226 -52.329726) (xy 14.790176 -52.410445) (xy 14.790674 -52.451) (xy 14.790176 -52.491555)
			(xy 14.782226 -52.572274) (xy 14.766403 -52.651825) (xy 14.742858 -52.729441) (xy 14.711819 -52.804377)
			(xy 14.673584 -52.875909) (xy 14.628522 -52.943349) (xy 14.577067 -53.006048) (xy 14.519714 -53.063401)
			(xy 14.457015 -53.114856) (xy 14.389575 -53.159918) (xy 14.318043 -53.198153) (xy 14.243107 -53.229192)
			(xy 14.165491 -53.252737) (xy 14.08594 -53.26856) (xy 14.005221 -53.27651) (xy 13.924111 -53.27651)
			(xy 13.843392 -53.26856) (xy 13.763841 -53.252737) (xy 13.686225 -53.229192) (xy 13.611289 -53.198153)
			(xy 13.539757 -53.159918) (xy 13.472317 -53.114856) (xy 13.409618 -53.063401) (xy 13.352265 -53.006048)
			(xy 13.30081 -52.943349) (xy 13.255748 -52.875909) (xy 13.217513 -52.804377) (xy 13.186474 -52.729441)
			(xy 13.162929 -52.651825) (xy 13.147106 -52.572274) (xy 13.139156 -52.491555) (xy 9.296321 -52.491555)
			(xy 9.345249 -52.559788) (xy 9.414094 -52.669624) (xy 9.475977 -52.783528) (xy 9.530658 -52.901058)
			(xy 9.577928 -53.021761) (xy 9.617601 -53.145169) (xy 9.649526 -53.270805) (xy 9.673578 -53.398182)
			(xy 9.689665 -53.526808) (xy 9.697724 -53.656186) (xy 9.698228 -53.721) (xy 9.697724 -53.785814)
			(xy 9.689665 -53.915192) (xy 9.673578 -54.043818) (xy 9.649526 -54.171195) (xy 9.617601 -54.296831)
			(xy 9.577928 -54.420239) (xy 9.530658 -54.540942) (xy 9.475977 -54.658472) (xy 9.414094 -54.772376)
			(xy 9.345249 -54.882212) (xy 9.26971 -54.987555) (xy 9.187767 -55.087998) (xy 9.099738 -55.183153)
			(xy 9.005964 -55.272651) (xy 8.906807 -55.356146) (xy 8.802651 -55.433315) (xy 8.693899 -55.503859)
			(xy 8.580971 -55.567506) (xy 8.464306 -55.624009) (xy 8.344353 -55.67315) (xy 8.221577 -55.714738)
			(xy 8.096453 -55.748613) (xy 7.969465 -55.774643) (xy 7.841104 -55.792728) (xy 7.711868 -55.802798)
			(xy 7.582255 -55.804814) (xy 7.452768 -55.798768) (xy 7.323907 -55.784684) (xy 7.196171 -55.762615)
			(xy 7.070054 -55.732648) (xy 6.946044 -55.694899) (xy 6.824621 -55.649512) (xy 6.706254 -55.596665)
			(xy 6.591402 -55.536561) (xy 6.480509 -55.469433) (xy 6.374003 -55.395541) (xy 6.272297 -55.31517)
			(xy 6.175785 -55.228632) (xy 6.08484 -55.13626) (xy 5.999813 -55.038414) (xy 5.921033 -54.935471)
			(xy 5.848806 -54.827829) (xy 5.783411 -54.715905) (xy 5.7251 -54.600132) (xy 5.6741 -54.480958) (xy 5.630608 -54.358844)
			(xy 5.594791 -54.234261) (xy 5.566789 -54.107694) (xy 5.54671 -53.97963) (xy 5.534631 -53.850566)
			(xy 5.5306 -53.721) (xy 1.27 -53.721) (xy 1.27 -60.833) (xy 5.5306 -60.833) (xy 5.534631 -60.703434)
			(xy 5.54671 -60.57437) (xy 5.566789 -60.446306) (xy 5.594791 -60.319739) (xy 5.630608 -60.195156)
			(xy 5.6741 -60.073042) (xy 5.7251 -59.953868) (xy 5.783411 -59.838095) (xy 5.848806 -59.726171) (xy 5.921033 -59.618529)
			(xy 5.999813 -59.515586) (xy 6.08484 -59.41774) (xy 6.175785 -59.325368) (xy 6.272297 -59.23883)
			(xy 6.374003 -59.158459) (xy 6.480509 -59.084567) (xy 6.591402 -59.017439) (xy 6.706254 -58.957335)
			(xy 6.824621 -58.904488) (xy 6.946044 -58.859101) (xy 7.070054 -58.821352) (xy 7.196171 -58.791385)
			(xy 7.323907 -58.769316) (xy 7.452768 -58.755232) (xy 7.582255 -58.749186) (xy 7.711868 -58.751202)
			(xy 7.841104 -58.761272) (xy 7.969465 -58.779357) (xy 8.096453 -58.805387) (xy 8.221577 -58.839262)
			(xy 8.344353 -58.88085) (xy 8.464306 -58.929991) (xy 8.580971 -58.986494) (xy 8.693899 -59.050141)
			(xy 8.802651 -59.120685) (xy 8.906807 -59.197854) (xy 9.005964 -59.281349) (xy 9.099738 -59.370847)
			(xy 9.187767 -59.466002) (xy 9.26971 -59.566445) (xy 9.345249 -59.671788) (xy 9.414094 -59.781624)
			(xy 9.475977 -59.895528) (xy 9.530658 -60.013058) (xy 9.577928 -60.133761) (xy 9.617601 -60.257169)
			(xy 9.649526 -60.382805) (xy 9.673578 -60.510182) (xy 9.689665 -60.638808) (xy 9.697724 -60.768186)
			(xy 9.698228 -60.833) (xy 9.697724 -60.897814) (xy 9.689665 -61.027192) (xy 9.673578 -61.155818)
			(xy 9.649526 -61.283195) (xy 9.617601 -61.408831) (xy 9.577928 -61.532239) (xy 9.530658 -61.652942)
			(xy 9.475977 -61.770472) (xy 9.414094 -61.884376) (xy 9.345249 -61.994212) (xy 9.26971 -62.099555)
			(xy 9.187767 -62.199998) (xy 9.099738 -62.295153) (xy 9.005964 -62.384651) (xy 8.906807 -62.468146)
			(xy 8.802651 -62.545315) (xy 8.693899 -62.615859) (xy 8.580971 -62.679506) (xy 8.464306 -62.736009)
			(xy 8.344353 -62.78515) (xy 8.221577 -62.826738) (xy 8.096453 -62.860613) (xy 7.969465 -62.886643)
			(xy 7.841104 -62.904728) (xy 7.711868 -62.914798) (xy 7.582255 -62.916814) (xy 7.452768 -62.910768)
			(xy 7.323907 -62.896684) (xy 7.196171 -62.874615) (xy 7.070054 -62.844648) (xy 6.946044 -62.806899)
			(xy 6.824621 -62.761512) (xy 6.706254 -62.708665) (xy 6.591402 -62.648561) (xy 6.480509 -62.581433)
			(xy 6.374003 -62.507541) (xy 6.272297 -62.42717) (xy 6.175785 -62.340632) (xy 6.08484 -62.24826)
			(xy 5.999813 -62.150414) (xy 5.921033 -62.047471) (xy 5.848806 -61.939829) (xy 5.783411 -61.827905)
			(xy 5.7251 -61.712132) (xy 5.6741 -61.592958) (xy 5.630608 -61.470844) (xy 5.594791 -61.346261) (xy 5.566789 -61.219694)
			(xy 5.54671 -61.09163) (xy 5.534631 -60.962566) (xy 5.5306 -60.833) (xy 1.27 -60.833) (xy 1.27 -72.263)
			(xy 5.5306 -72.263) (xy 5.534631 -72.133434) (xy 5.54671 -72.00437) (xy 5.566789 -71.876306) (xy 5.594791 -71.749739)
			(xy 5.630608 -71.625156) (xy 5.6741 -71.503042) (xy 5.7251 -71.383868) (xy 5.783411 -71.268095) (xy 5.848806 -71.156171)
			(xy 5.921033 -71.048529) (xy 5.999813 -70.945586) (xy 6.08484 -70.84774) (xy 6.175785 -70.755368)
			(xy 6.272297 -70.66883) (xy 6.374003 -70.588459) (xy 6.480509 -70.514567) (xy 6.591402 -70.447439)
			(xy 6.706254 -70.387335) (xy 6.824621 -70.334488) (xy 6.946044 -70.289101) (xy 7.070054 -70.251352)
			(xy 7.196171 -70.221385) (xy 7.323907 -70.199316) (xy 7.452768 -70.185232) (xy 7.582255 -70.179186)
			(xy 7.711868 -70.181202) (xy 7.841104 -70.191272) (xy 7.969465 -70.209357) (xy 8.096453 -70.235387)
			(xy 8.221577 -70.269262) (xy 8.344353 -70.31085) (xy 8.464306 -70.359991) (xy 8.580971 -70.416494)
			(xy 8.693899 -70.480141) (xy 8.802651 -70.550685) (xy 8.906807 -70.627854) (xy 9.005964 -70.711349)
			(xy 9.099738 -70.800847) (xy 9.187767 -70.896002) (xy 9.26971 -70.996445) (xy 9.345249 -71.101788)
			(xy 9.414094 -71.211624) (xy 9.475977 -71.325528) (xy 9.530658 -71.443058) (xy 9.577928 -71.563761)
			(xy 9.617601 -71.687169) (xy 9.649526 -71.812805) (xy 9.673578 -71.940182) (xy 9.689665 -72.068808)
			(xy 9.697724 -72.198186) (xy 9.698228 -72.263) (xy 9.697724 -72.327814) (xy 9.689665 -72.457192)
			(xy 9.673578 -72.585818) (xy 9.649526 -72.713195) (xy 9.617601 -72.838831) (xy 9.577928 -72.962239)
			(xy 9.530658 -73.082942) (xy 9.475977 -73.200472) (xy 9.414094 -73.314376) (xy 9.345249 -73.424212)
			(xy 9.26971 -73.529555) (xy 9.187767 -73.629998) (xy 9.099738 -73.725153) (xy 9.005964 -73.814651)
			(xy 8.906807 -73.898146) (xy 8.802651 -73.975315) (xy 8.693899 -74.045859) (xy 8.580971 -74.109506)
			(xy 8.464306 -74.166009) (xy 8.344353 -74.21515) (xy 8.221577 -74.256738) (xy 8.096453 -74.290613)
			(xy 7.969465 -74.316643) (xy 7.841104 -74.334728) (xy 7.711868 -74.344798) (xy 7.582255 -74.346814)
			(xy 7.452768 -74.340768) (xy 7.323907 -74.326684) (xy 7.196171 -74.304615) (xy 7.070054 -74.274648)
			(xy 6.946044 -74.236899) (xy 6.824621 -74.191512) (xy 6.706254 -74.138665) (xy 6.591402 -74.078561)
			(xy 6.480509 -74.011433) (xy 6.374003 -73.937541) (xy 6.272297 -73.85717) (xy 6.175785 -73.770632)
			(xy 6.08484 -73.67826) (xy 5.999813 -73.580414) (xy 5.921033 -73.477471) (xy 5.848806 -73.369829)
			(xy 5.783411 -73.257905) (xy 5.7251 -73.142132) (xy 5.6741 -73.022958) (xy 5.630608 -72.900844) (xy 5.594791 -72.776261)
			(xy 5.566789 -72.649694) (xy 5.54671 -72.52163) (xy 5.534631 -72.392566) (xy 5.5306 -72.263) (xy 1.27 -72.263)
			(xy 1.27 -77.476858) (xy 6.601727 -77.476858) (xy 6.605682 -77.385021) (xy 6.617517 -77.293864) (xy 6.637144 -77.204061)
			(xy 6.664418 -77.116279) (xy 6.699138 -77.031165) (xy 6.741046 -76.949352) (xy 6.789832 -76.871444)
			(xy 6.845135 -76.798019) (xy 6.906545 -76.729619) (xy 6.973607 -76.666752) (xy 7.045826 -76.609882)
			(xy 7.122666 -76.559431) (xy 7.203559 -76.515772) (xy 7.287905 -76.479229) (xy 7.375081 -76.450072)
			(xy 7.46444 -76.428518) (xy 7.555321 -76.414724) (xy 7.647052 -76.408794) (xy 7.738953 -76.410772)
			(xy 7.830344 -76.420643) (xy 7.920548 -76.438333) (xy 8.008897 -76.463713) (xy 8.094737 -76.496593)
			(xy 8.177433 -76.536731) (xy 8.256373 -76.58383) (xy 8.330971 -76.63754) (xy 8.400677 -76.697464)
			(xy 8.464972 -76.763158) (xy 8.523383 -76.834136) (xy 8.575475 -76.909873) (xy 8.620864 -76.989808)
			(xy 8.659214 -77.073348) (xy 8.690239 -77.159876) (xy 8.713712 -77.248751) (xy 8.729458 -77.339315)
			(xy 8.73736 -77.430897) (xy 8.737854 -77.476858) (xy 8.73736 -77.522819) (xy 8.729458 -77.614401)
			(xy 8.713712 -77.704965) (xy 8.690239 -77.79384) (xy 8.659214 -77.880368) (xy 8.620864 -77.963908)
			(xy 8.575475 -78.043843) (xy 8.523383 -78.11958) (xy 8.464972 -78.190558) (xy 8.400677 -78.256252)
			(xy 8.330971 -78.316176) (xy 8.256373 -78.369886) (xy 8.177433 -78.416985) (xy 8.094737 -78.457123)
			(xy 8.008897 -78.490003) (xy 7.920548 -78.515383) (xy 7.830344 -78.533073) (xy 7.738953 -78.542944)
			(xy 7.647052 -78.544922) (xy 7.555321 -78.538992) (xy 7.46444 -78.525198) (xy 7.375081 -78.503644)
			(xy 7.287905 -78.474487) (xy 7.203559 -78.437944) (xy 7.122666 -78.394285) (xy 7.045826 -78.343834)
			(xy 6.973607 -78.286964) (xy 6.906545 -78.224097) (xy 6.845135 -78.155697) (xy 6.789832 -78.082272)
			(xy 6.741046 -78.004364) (xy 6.699138 -77.922551) (xy 6.664418 -77.837437) (xy 6.637144 -77.749655)
			(xy 6.617517 -77.659852) (xy 6.605682 -77.568695) (xy 6.601727 -77.476858) (xy 1.27 -77.476858) (xy 1.27 -80.519715)
			(xy 4.782807 -80.519715) (xy 4.782807 -80.433989) (xy 4.790717 -80.348629) (xy 4.806469 -80.264362)
			(xy 4.829929 -80.181909) (xy 4.860897 -80.101972) (xy 4.899108 -80.025233) (xy 4.944237 -79.952347)
			(xy 4.995898 -79.883936) (xy 5.053652 -79.820584) (xy 5.117004 -79.76283) (xy 5.185415 -79.711169)
			(xy 5.258301 -79.66604) (xy 5.33504 -79.627829) (xy 5.414977 -79.596861) (xy 5.49743 -79.573401)
			(xy 5.581697 -79.557649) (xy 5.667057 -79.549739) (xy 5.752783 -79.549739) (xy 5.838143 -79.557649)
			(xy 5.92241 -79.573401) (xy 6.004863 -79.596861) (xy 6.0848 -79.627829) (xy 6.161539 -79.66604) (xy 6.234425 -79.711169)
			(xy 6.302836 -79.76283) (xy 6.366188 -79.820584) (xy 6.423942 -79.883936) (xy 6.475603 -79.952347)
			(xy 6.520732 -80.025233) (xy 6.558943 -80.101972) (xy 6.589911 -80.181909) (xy 6.613371 -80.264362)
			(xy 6.629123 -80.348629) (xy 6.637033 -80.433989) (xy 6.637528 -80.476852) (xy 6.637033 -80.519715)
			(xy 6.629123 -80.605075) (xy 6.613371 -80.689342) (xy 6.589911 -80.771795) (xy 6.558943 -80.851732)
			(xy 6.520732 -80.928471) (xy 6.475603 -81.001357) (xy 6.423942 -81.069768) (xy 6.366188 -81.13312)
			(xy 6.302836 -81.190874) (xy 6.234425 -81.242535) (xy 6.161539 -81.287664) (xy 6.0848 -81.325875)
			(xy 6.004863 -81.356843) (xy 5.92241 -81.380303) (xy 5.838143 -81.396055) (xy 5.752783 -81.403965)
			(xy 5.667057 -81.403965) (xy 5.581697 -81.396055) (xy 5.49743 -81.380303) (xy 5.414977 -81.356843)
			(xy 5.33504 -81.325875) (xy 5.258301 -81.287664) (xy 5.185415 -81.242535) (xy 5.117004 -81.190874)
			(xy 5.053652 -81.13312) (xy 4.995898 -81.069768) (xy 4.944237 -81.001357) (xy 4.899108 -80.928471)
			(xy 4.860897 -80.851732) (xy 4.829929 -80.771795) (xy 4.806469 -80.689342) (xy 4.790717 -80.605075)
			(xy 4.782807 -80.519715) (xy 1.27 -80.519715) (xy 1.27 -86.519703) (xy 4.782807 -86.519703) (xy 4.782807 -86.433977)
			(xy 4.790717 -86.348617) (xy 4.806469 -86.26435) (xy 4.829929 -86.181897) (xy 4.860897 -86.10196)
			(xy 4.899108 -86.025221) (xy 4.944237 -85.952335) (xy 4.995898 -85.883924) (xy 5.053652 -85.820572)
			(xy 5.117004 -85.762818) (xy 5.185415 -85.711157) (xy 5.258301 -85.666028) (xy 5.33504 -85.627817)
			(xy 5.414977 -85.596849) (xy 5.49743 -85.573389) (xy 5.581697 -85.557637) (xy 5.667057 -85.549727)
			(xy 5.752783 -85.549727) (xy 5.838143 -85.557637) (xy 5.92241 -85.573389) (xy 6.004863 -85.596849)
			(xy 6.0848 -85.627817) (xy 6.161539 -85.666028) (xy 6.234425 -85.711157) (xy 6.302836 -85.762818)
			(xy 6.366188 -85.820572) (xy 6.423942 -85.883924) (xy 6.475603 -85.952335) (xy 6.520732 -86.025221)
			(xy 6.558943 -86.10196) (xy 6.589911 -86.181897) (xy 6.613371 -86.26435) (xy 6.629123 -86.348617)
			(xy 6.637033 -86.433977) (xy 6.637528 -86.47684) (xy 6.637033 -86.519703) (xy 6.629123 -86.605063)
			(xy 6.613371 -86.68933) (xy 6.589911 -86.771783) (xy 6.558943 -86.85172) (xy 6.520732 -86.928459)
			(xy 6.475603 -87.001345) (xy 6.423942 -87.069756) (xy 6.366188 -87.133108) (xy 6.302836 -87.190862)
			(xy 6.234425 -87.242523) (xy 6.161539 -87.287652) (xy 6.0848 -87.325863) (xy 6.004863 -87.356831)
			(xy 5.92241 -87.380291) (xy 5.838143 -87.396043) (xy 5.752783 -87.403953) (xy 5.667057 -87.403953)
			(xy 5.581697 -87.396043) (xy 5.49743 -87.380291) (xy 5.414977 -87.356831) (xy 5.33504 -87.325863)
			(xy 5.258301 -87.287652) (xy 5.185415 -87.242523) (xy 5.117004 -87.190862) (xy 5.053652 -87.133108)
			(xy 4.995898 -87.069756) (xy 4.944237 -87.001345) (xy 4.899108 -86.928459) (xy 4.860897 -86.85172)
			(xy 4.829929 -86.771783) (xy 4.806469 -86.68933) (xy 4.790717 -86.605063) (xy 4.782807 -86.519703)
			(xy 1.27 -86.519703) (xy 1.27 -89.476834) (xy 6.601727 -89.476834) (xy 6.605682 -89.384997) (xy 6.617517 -89.29384)
			(xy 6.637144 -89.204037) (xy 6.664418 -89.116255) (xy 6.699138 -89.031141) (xy 6.741046 -88.949328)
			(xy 6.789832 -88.87142) (xy 6.845135 -88.797995) (xy 6.906545 -88.729595) (xy 6.973607 -88.666728)
			(xy 7.045826 -88.609858) (xy 7.122666 -88.559407) (xy 7.203559 -88.515748) (xy 7.287905 -88.479205)
			(xy 7.375081 -88.450048) (xy 7.46444 -88.428494) (xy 7.555321 -88.4147) (xy 7.647052 -88.40877) (xy 7.738953 -88.410748)
			(xy 7.830344 -88.420619) (xy 7.920548 -88.438309) (xy 8.008897 -88.463689) (xy 8.094737 -88.496569)
			(xy 8.177433 -88.536707) (xy 8.256373 -88.583806) (xy 8.330971 -88.637516) (xy 8.400677 -88.69744)
			(xy 8.464972 -88.763134) (xy 8.523383 -88.834112) (xy 8.575475 -88.909849) (xy 8.620864 -88.989784)
			(xy 8.659214 -89.073324) (xy 8.690239 -89.159852) (xy 8.713712 -89.248727) (xy 8.729458 -89.339291)
			(xy 8.73736 -89.430873) (xy 8.737854 -89.476834) (xy 8.73736 -89.522795) (xy 8.729458 -89.614377)
			(xy 8.713712 -89.704941) (xy 8.690239 -89.793816) (xy 8.659214 -89.880344) (xy 8.620864 -89.963884)
			(xy 8.575475 -90.043819) (xy 8.523383 -90.119556) (xy 8.464972 -90.190534) (xy 8.400677 -90.256228)
			(xy 8.330971 -90.316152) (xy 8.256373 -90.369862) (xy 8.177433 -90.416961) (xy 8.094737 -90.457099)
			(xy 8.008897 -90.489979) (xy 7.920548 -90.515359) (xy 7.830344 -90.533049) (xy 7.738953 -90.54292)
			(xy 7.647052 -90.544898) (xy 7.555321 -90.538968) (xy 7.46444 -90.525174) (xy 7.375081 -90.50362)
			(xy 7.287905 -90.474463) (xy 7.203559 -90.43792) (xy 7.122666 -90.394261) (xy 7.045826 -90.34381)
			(xy 6.973607 -90.28694) (xy 6.906545 -90.224073) (xy 6.845135 -90.155673) (xy 6.789832 -90.082248)
			(xy 6.741046 -90.00434) (xy 6.699138 -89.922527) (xy 6.664418 -89.837413) (xy 6.637144 -89.749631)
			(xy 6.617517 -89.659828) (xy 6.605682 -89.568671) (xy 6.601727 -89.476834) (xy 1.27 -89.476834) (xy 1.27 -95.377)
			(xy 5.5306 -95.377) (xy 5.534631 -95.247434) (xy 5.54671 -95.11837) (xy 5.566789 -94.990306) (xy 5.594791 -94.863739)
			(xy 5.630608 -94.739156) (xy 5.6741 -94.617042) (xy 5.7251 -94.497868) (xy 5.783411 -94.382095) (xy 5.848806 -94.270171)
			(xy 5.921033 -94.162529) (xy 5.999813 -94.059586) (xy 6.08484 -93.96174) (xy 6.175785 -93.869368)
			(xy 6.272297 -93.78283) (xy 6.374003 -93.702459) (xy 6.480509 -93.628567) (xy 6.591402 -93.561439)
			(xy 6.706254 -93.501335) (xy 6.824621 -93.448488) (xy 6.946044 -93.403101) (xy 7.070054 -93.365352)
			(xy 7.196171 -93.335385) (xy 7.323907 -93.313316) (xy 7.452768 -93.299232) (xy 7.582255 -93.293186)
			(xy 7.711868 -93.295202) (xy 7.841104 -93.305272) (xy 7.969465 -93.323357) (xy 8.096453 -93.349387)
			(xy 8.221577 -93.383262) (xy 8.344353 -93.42485) (xy 8.464306 -93.473991) (xy 8.580971 -93.530494)
			(xy 8.693899 -93.594141) (xy 8.802651 -93.664685) (xy 8.906807 -93.741854) (xy 9.005964 -93.825349)
			(xy 9.099738 -93.914847) (xy 9.187767 -94.010002) (xy 9.26971 -94.110445) (xy 9.345249 -94.215788)
			(xy 9.414094 -94.325624) (xy 9.475977 -94.439528) (xy 9.530658 -94.557058) (xy 9.577928 -94.677761)
			(xy 9.617601 -94.801169) (xy 9.649526 -94.926805) (xy 9.673578 -95.054182) (xy 9.689665 -95.182808)
			(xy 9.697724 -95.312186) (xy 9.698228 -95.377) (xy 9.697724 -95.441814) (xy 9.689665 -95.571192)
			(xy 9.673578 -95.699818) (xy 9.649526 -95.827195) (xy 9.617601 -95.952831) (xy 9.577928 -96.076239)
			(xy 9.530658 -96.196942) (xy 9.475977 -96.314472) (xy 9.414094 -96.428376) (xy 9.345249 -96.538212)
			(xy 9.26971 -96.643555) (xy 9.187767 -96.743998) (xy 9.099738 -96.839153) (xy 9.005964 -96.928651)
			(xy 8.906807 -97.012146) (xy 8.802651 -97.089315) (xy 8.693899 -97.159859) (xy 8.580971 -97.223506)
			(xy 8.464306 -97.280009) (xy 8.344353 -97.32915) (xy 8.221577 -97.370738) (xy 8.096453 -97.404613)
			(xy 7.969465 -97.430643) (xy 7.841104 -97.448728) (xy 7.711868 -97.458798) (xy 7.582255 -97.460814)
			(xy 7.452768 -97.454768) (xy 7.323907 -97.440684) (xy 7.196171 -97.418615) (xy 7.070054 -97.388648)
			(xy 6.946044 -97.350899) (xy 6.824621 -97.305512) (xy 6.706254 -97.252665) (xy 6.591402 -97.192561)
			(xy 6.480509 -97.125433) (xy 6.374003 -97.051541) (xy 6.272297 -96.97117) (xy 6.175785 -96.884632)
			(xy 6.08484 -96.79226) (xy 5.999813 -96.694414) (xy 5.921033 -96.591471) (xy 5.848806 -96.483829)
			(xy 5.783411 -96.371905) (xy 5.7251 -96.256132) (xy 5.6741 -96.136958) (xy 5.630608 -96.014844) (xy 5.594791 -95.890261)
			(xy 5.566789 -95.763694) (xy 5.54671 -95.63563) (xy 5.534631 -95.506566) (xy 5.5306 -95.377) (xy 1.27 -95.377)
			(xy 1.27 -106.807) (xy 5.5306 -106.807) (xy 5.534631 -106.677434) (xy 5.54671 -106.54837) (xy 5.566789 -106.420306)
			(xy 5.594791 -106.293739) (xy 5.630608 -106.169156) (xy 5.6741 -106.047042) (xy 5.7251 -105.927868)
			(xy 5.783411 -105.812095) (xy 5.848806 -105.700171) (xy 5.921033 -105.592529) (xy 5.999813 -105.489586)
			(xy 6.08484 -105.39174) (xy 6.175785 -105.299368) (xy 6.272297 -105.21283) (xy 6.374003 -105.132459)
			(xy 6.480509 -105.058567) (xy 6.591402 -104.991439) (xy 6.706254 -104.931335) (xy 6.824621 -104.878488)
			(xy 6.946044 -104.833101) (xy 7.070054 -104.795352) (xy 7.196171 -104.765385) (xy 7.323907 -104.743316)
			(xy 7.452768 -104.729232) (xy 7.582255 -104.723186) (xy 7.711868 -104.725202) (xy 7.841104 -104.735272)
			(xy 7.969465 -104.753357) (xy 8.096453 -104.779387) (xy 8.221577 -104.813262) (xy 8.344353 -104.85485)
			(xy 8.464306 -104.903991) (xy 8.580971 -104.960494) (xy 8.693899 -105.024141) (xy 8.802651 -105.094685)
			(xy 8.906807 -105.171854) (xy 9.005964 -105.255349) (xy 9.099738 -105.344847) (xy 9.187767 -105.440002)
			(xy 9.26971 -105.540445) (xy 9.345249 -105.645788) (xy 9.414094 -105.755624) (xy 9.475977 -105.869528)
			(xy 9.530658 -105.987058) (xy 9.577928 -106.107761) (xy 9.617601 -106.231169) (xy 9.649526 -106.356805)
			(xy 9.673578 -106.484182) (xy 9.689665 -106.612808) (xy 9.697724 -106.742186) (xy 9.698228 -106.807)
			(xy 9.697724 -106.871814) (xy 9.689665 -107.001192) (xy 9.673578 -107.129818) (xy 9.649526 -107.257195)
			(xy 9.617601 -107.382831) (xy 9.577928 -107.506239) (xy 9.530658 -107.626942) (xy 9.475977 -107.744472)
			(xy 9.414094 -107.858376) (xy 9.345249 -107.968212) (xy 9.26971 -108.073555) (xy 9.187767 -108.173998)
			(xy 9.099738 -108.269153) (xy 9.005964 -108.358651) (xy 8.906807 -108.442146) (xy 8.802651 -108.519315)
			(xy 8.693899 -108.589859) (xy 8.580971 -108.653506) (xy 8.464306 -108.710009) (xy 8.344353 -108.75915)
			(xy 8.221577 -108.800738) (xy 8.096453 -108.834613) (xy 7.969465 -108.860643) (xy 7.841104 -108.878728)
			(xy 7.711868 -108.888798) (xy 7.582255 -108.890814) (xy 7.452768 -108.884768) (xy 7.323907 -108.870684)
			(xy 7.196171 -108.848615) (xy 7.070054 -108.818648) (xy 6.946044 -108.780899) (xy 6.824621 -108.735512)
			(xy 6.706254 -108.682665) (xy 6.591402 -108.622561) (xy 6.480509 -108.555433) (xy 6.374003 -108.481541)
			(xy 6.272297 -108.40117) (xy 6.175785 -108.314632) (xy 6.08484 -108.22226) (xy 5.999813 -108.124414)
			(xy 5.921033 -108.021471) (xy 5.848806 -107.913829) (xy 5.783411 -107.801905) (xy 5.7251 -107.686132)
			(xy 5.6741 -107.566958) (xy 5.630608 -107.444844) (xy 5.594791 -107.320261) (xy 5.566789 -107.193694)
			(xy 5.54671 -107.06563) (xy 5.534631 -106.936566) (xy 5.5306 -106.807) (xy 1.27 -106.807) (xy 1.27 -125.974094)
			(xy 3.031996 -125.974094) (xy 3.036067 -125.918472) (xy 3.048193 -125.864035) (xy 3.068116 -125.811944)
			(xy 3.095412 -125.763309) (xy 3.129498 -125.719166) (xy 3.169647 -125.680457) (xy 3.215005 -125.648006)
			(xy 3.264605 -125.622505) (xy 3.317389 -125.604498) (xy 3.372232 -125.594368) (xy 3.427966 -125.592331)
			(xy 3.483403 -125.598431) (xy 3.53736 -125.612537) (xy 3.588689 -125.634349) (xy 3.636295 -125.663403)
			(xy 3.679163 -125.699078) (xy 3.71638 -125.740615) (xy 3.747153 -125.787128) (xy 3.770825 -125.837625)
			(xy 3.786893 -125.891032) (xy 3.795013 -125.946208) (xy 3.795522 -125.974094) (xy 3.795013 -126.00198)
			(xy 3.786893 -126.057156) (xy 3.770825 -126.110563) (xy 3.747153 -126.16106) (xy 3.71638 -126.207573)
			(xy 3.679163 -126.24911) (xy 3.636295 -126.284785) (xy 3.588689 -126.313839) (xy 3.53736 -126.335651)
			(xy 3.483403 -126.349757) (xy 3.427966 -126.355857) (xy 3.372232 -126.35382) (xy 3.317389 -126.34369)
			(xy 3.264605 -126.325683) (xy 3.215005 -126.300182) (xy 3.169647 -126.267731) (xy 3.129498 -126.229022)
			(xy 3.095412 -126.184879) (xy 3.068116 -126.136244) (xy 3.048193 -126.084153) (xy 3.036067 -126.029716)
			(xy 3.031996 -125.974094) (xy 1.27 -125.974094) (xy 1.27 -128.57438) (xy 10.22629 -128.57438) (xy 10.22629 -128.471588)
			(xy 10.234355 -128.369114) (xy 10.250435 -128.267589) (xy 10.274431 -128.167638) (xy 10.306196 -128.069878)
			(xy 10.345532 -127.974911) (xy 10.392198 -127.883324) (xy 10.445906 -127.79568) (xy 10.506325 -127.71252)
			(xy 10.573083 -127.634357) (xy 10.645767 -127.561673) (xy 10.72393 -127.494915) (xy 10.80709 -127.434496)
			(xy 10.894734 -127.380788) (xy 10.986321 -127.334122) (xy 11.081288 -127.294786) (xy 11.179048 -127.263021)
			(xy 11.278999 -127.239025) (xy 11.380524 -127.222945) (xy 11.482998 -127.21488) (xy 11.58579 -127.21488)
			(xy 11.688264 -127.222945) (xy 11.789789 -127.239025) (xy 11.88974 -127.263021) (xy 11.9875 -127.294786)
			(xy 12.082467 -127.334122) (xy 12.174054 -127.380788) (xy 12.261698 -127.434496) (xy 12.344858 -127.494915)
			(xy 12.423021 -127.561673) (xy 12.495705 -127.634357) (xy 12.562463 -127.71252) (xy 12.622882 -127.79568)
			(xy 12.67659 -127.883324) (xy 12.723256 -127.974911) (xy 12.762592 -128.069878) (xy 12.794357 -128.167638)
			(xy 12.818353 -128.267589) (xy 12.834433 -128.369114) (xy 12.842498 -128.471588) (xy 12.843002 -128.522984)
			(xy 12.842498 -128.57438) (xy 12.834433 -128.676854) (xy 12.818353 -128.778379) (xy 12.794357 -128.87833)
			(xy 12.762592 -128.97609) (xy 12.723256 -129.071057) (xy 12.67659 -129.162644) (xy 12.622882 -129.250288)
			(xy 12.562463 -129.333448) (xy 12.495705 -129.411611) (xy 12.423021 -129.484295) (xy 12.344858 -129.551053)
			(xy 12.261698 -129.611472) (xy 12.174054 -129.66518) (xy 12.082467 -129.711846) (xy 11.9875 -129.751182)
			(xy 11.88974 -129.782947) (xy 11.789789 -129.806943) (xy 11.688264 -129.823023) (xy 11.58579 -129.831088)
			(xy 11.482998 -129.831088) (xy 11.380524 -129.823023) (xy 11.278999 -129.806943) (xy 11.179048 -129.782947)
			(xy 11.081288 -129.751182) (xy 10.986321 -129.711846) (xy 10.894734 -129.66518) (xy 10.80709 -129.611472)
			(xy 10.72393 -129.551053) (xy 10.645767 -129.484295) (xy 10.573083 -129.411611) (xy 10.506325 -129.333448)
			(xy 10.445906 -129.250288) (xy 10.392198 -129.162644) (xy 10.345532 -129.071057) (xy 10.306196 -128.97609)
			(xy 10.274431 -128.87833) (xy 10.250435 -128.778379) (xy 10.234355 -128.676854) (xy 10.22629 -128.57438)
			(xy 1.27 -128.57438) (xy 1.27 -130.137971) (xy 2.787139 -130.137971) (xy 2.787139 -130.058105) (xy 2.795219 -129.97865)
			(xy 2.811296 -129.90042) (xy 2.835205 -129.824218) (xy 2.8667 -129.750825) (xy 2.905459 -129.680995)
			(xy 2.951083 -129.615445) (xy 3.003105 -129.554846) (xy 3.06099 -129.499822) (xy 3.124146 -129.450936)
			(xy 3.191923 -129.40869) (xy 3.263626 -129.373518) (xy 3.33852 -129.345781) (xy 3.415835 -129.325762)
			(xy 3.494779 -129.313669) (xy 3.574542 -129.309624) (xy 3.654305 -129.313669) (xy 3.733249 -129.325762)
			(xy 3.810564 -129.345781) (xy 3.885458 -129.373518) (xy 3.957161 -129.40869) (xy 4.024938 -129.450936)
			(xy 4.088094 -129.499822) (xy 4.145979 -129.554846) (xy 4.198001 -129.615445) (xy 4.243625 -129.680995)
			(xy 4.282384 -129.750825) (xy 4.313879 -129.824218) (xy 4.337788 -129.90042) (xy 4.353865 -129.97865)
			(xy 4.361945 -130.058105) (xy 4.36245 -130.098038) (xy 4.361945 -130.137971) (xy 4.353865 -130.217426)
			(xy 4.337788 -130.295656) (xy 4.313879 -130.371858) (xy 4.282384 -130.445251) (xy 4.243625 -130.515081)
			(xy 4.198001 -130.580631) (xy 4.145979 -130.64123) (xy 4.088094 -130.696254) (xy 4.024938 -130.74514)
			(xy 4.023449 -130.746068) (xy 5.677649 -130.746068) (xy 5.677649 -130.619932) (xy 5.685569 -130.494044)
			(xy 5.701379 -130.368902) (xy 5.725014 -130.244999) (xy 5.756383 -130.122826) (xy 5.795361 -130.002863)
			(xy 5.841795 -129.885584) (xy 5.895502 -129.771452) (xy 5.956269 -129.660917) (xy 6.023856 -129.554417)
			(xy 6.097997 -129.45237) (xy 6.1784 -129.35518) (xy 6.264746 -129.26323) (xy 6.356696 -129.176884)
			(xy 6.453886 -129.096481) (xy 6.555933 -129.02234) (xy 6.662433 -128.954753) (xy 6.772968 -128.893986)
			(xy 6.8871 -128.840279) (xy 7.004379 -128.793845) (xy 7.124342 -128.754867) (xy 7.246515 -128.723498)
			(xy 7.370418 -128.699863) (xy 7.49556 -128.684053) (xy 7.621448 -128.676133) (xy 7.747584 -128.676133)
			(xy 7.873472 -128.684053) (xy 7.998614 -128.699863) (xy 8.122517 -128.723498) (xy 8.24469 -128.754867)
			(xy 8.364653 -128.793845) (xy 8.481932 -128.840279) (xy 8.596064 -128.893986) (xy 8.706599 -128.954753)
			(xy 8.813099 -129.02234) (xy 8.915146 -129.096481) (xy 9.012336 -129.176884) (xy 9.104286 -129.26323)
			(xy 9.190632 -129.35518) (xy 9.271035 -129.45237) (xy 9.345176 -129.554417) (xy 9.412763 -129.660917)
			(xy 9.47353 -129.771452) (xy 9.527237 -129.885584) (xy 9.573671 -130.002863) (xy 9.612649 -130.122826)
			(xy 9.644018 -130.244999) (xy 9.667653 -130.368902) (xy 9.683463 -130.494044) (xy 9.691383 -130.619932)
			(xy 9.691878 -130.683) (xy 9.691383 -130.746068) (xy 9.683463 -130.871956) (xy 9.667653 -130.997098)
			(xy 9.644018 -131.121001) (xy 9.612649 -131.243174) (xy 9.573671 -131.363137) (xy 9.527237 -131.480416)
			(xy 9.47353 -131.594548) (xy 9.412763 -131.705083) (xy 9.345176 -131.811583) (xy 9.271035 -131.91363)
			(xy 9.205429 -131.992933) (xy 15.787113 -131.992933) (xy 15.787113 -131.913067) (xy 15.795193 -131.833612)
			(xy 15.81127 -131.755382) (xy 15.835179 -131.67918) (xy 15.866674 -131.605787) (xy 15.905433 -131.535957)
			(xy 15.951057 -131.470407) (xy 16.003079 -131.409808) (xy 16.060964 -131.354784) (xy 16.12412 -131.305898)
			(xy 16.191897 -131.263652) (xy 16.2636 -131.22848) (xy 16.338494 -131.200743) (xy 16.415809 -131.180724)
			(xy 16.494753 -131.168631) (xy 16.574516 -131.164586) (xy 16.654279 -131.168631) (xy 16.733223 -131.180724)
			(xy 16.810538 -131.200743) (xy 16.885432 -131.22848) (xy 16.957135 -131.263652) (xy 17.024912 -131.305898)
			(xy 17.088068 -131.354784) (xy 17.145953 -131.409808) (xy 17.197975 -131.470407) (xy 17.243599 -131.535957)
			(xy 17.282358 -131.605787) (xy 17.313853 -131.67918) (xy 17.337762 -131.755382) (xy 17.353839 -131.833612)
			(xy 17.361919 -131.913067) (xy 17.362424 -131.953) (xy 17.361919 -131.992933) (xy 17.353839 -132.072388)
			(xy 17.337762 -132.150618) (xy 17.313853 -132.22682) (xy 17.282358 -132.300213) (xy 17.243599 -132.370043)
			(xy 17.197975 -132.435593) (xy 17.145953 -132.496192) (xy 17.088068 -132.551216) (xy 17.024912 -132.600102)
			(xy 16.957135 -132.642348) (xy 16.885432 -132.67752) (xy 16.810538 -132.705257) (xy 16.733223 -132.725276)
			(xy 16.654279 -132.737369) (xy 16.574516 -132.741415) (xy 16.494753 -132.737369) (xy 16.415809 -132.725276)
			(xy 16.338494 -132.705257) (xy 16.2636 -132.67752) (xy 16.191897 -132.642348) (xy 16.12412 -132.600102)
			(xy 16.060964 -132.551216) (xy 16.003079 -132.496192) (xy 15.951057 -132.435593) (xy 15.905433 -132.370043)
			(xy 15.866674 -132.300213) (xy 15.835179 -132.22682) (xy 15.81127 -132.150618) (xy 15.795193 -132.072388)
			(xy 15.787113 -131.992933) (xy 9.205429 -131.992933) (xy 9.190632 -132.01082) (xy 9.104286 -132.10277)
			(xy 9.012336 -132.189116) (xy 8.915146 -132.269519) (xy 8.813099 -132.34366) (xy 8.706599 -132.411247)
			(xy 8.596064 -132.472014) (xy 8.481932 -132.525721) (xy 8.364653 -132.572155) (xy 8.24469 -132.611133)
			(xy 8.122517 -132.642502) (xy 7.998614 -132.666137) (xy 7.873472 -132.681947) (xy 7.747584 -132.689867)
			(xy 7.621448 -132.689867) (xy 7.49556 -132.681947) (xy 7.370418 -132.666137) (xy 7.246515 -132.642502)
			(xy 7.124342 -132.611133) (xy 7.004379 -132.572155) (xy 6.8871 -132.525721) (xy 6.772968 -132.472014)
			(xy 6.662433 -132.411247) (xy 6.555933 -132.34366) (xy 6.453886 -132.269519) (xy 6.356696 -132.189116)
			(xy 6.264746 -132.10277) (xy 6.1784 -132.01082) (xy 6.097997 -131.91363) (xy 6.023856 -131.811583)
			(xy 5.956269 -131.705083) (xy 5.895502 -131.594548) (xy 5.841795 -131.480416) (xy 5.795361 -131.363137)
			(xy 5.756383 -131.243174) (xy 5.725014 -131.121001) (xy 5.701379 -130.997098) (xy 5.685569 -130.871956)
			(xy 5.677649 -130.746068) (xy 4.023449 -130.746068) (xy 3.957161 -130.787386) (xy 3.885458 -130.822558)
			(xy 3.810564 -130.850295) (xy 3.733249 -130.870314) (xy 3.654305 -130.882407) (xy 3.574542 -130.886453)
			(xy 3.494779 -130.882407) (xy 3.415835 -130.870314) (xy 3.33852 -130.850295) (xy 3.263626 -130.822558)
			(xy 3.191923 -130.787386) (xy 3.124146 -130.74514) (xy 3.06099 -130.696254) (xy 3.003105 -130.64123)
			(xy 2.951083 -130.580631) (xy 2.905459 -130.515081) (xy 2.8667 -130.445251) (xy 2.835205 -130.371858)
			(xy 2.811296 -130.295656) (xy 2.795219 -130.217426) (xy 2.787139 -130.137971) (xy 1.27 -130.137971)
			(xy 1.27 -132.627933) (xy 2.787139 -132.627933) (xy 2.787139 -132.548067) (xy 2.795219 -132.468612)
			(xy 2.811296 -132.390382) (xy 2.835205 -132.31418) (xy 2.8667 -132.240787) (xy 2.905459 -132.170957)
			(xy 2.951083 -132.105407) (xy 3.003105 -132.044808) (xy 3.06099 -131.989784) (xy 3.124146 -131.940898)
			(xy 3.191923 -131.898652) (xy 3.263626 -131.86348) (xy 3.33852 -131.835743) (xy 3.415835 -131.815724)
			(xy 3.494779 -131.803631) (xy 3.574542 -131.799586) (xy 3.654305 -131.803631) (xy 3.733249 -131.815724)
			(xy 3.810564 -131.835743) (xy 3.885458 -131.86348) (xy 3.957161 -131.898652) (xy 4.024938 -131.940898)
			(xy 4.088094 -131.989784) (xy 4.145979 -132.044808) (xy 4.198001 -132.105407) (xy 4.243625 -132.170957)
			(xy 4.282384 -132.240787) (xy 4.313879 -132.31418) (xy 4.337788 -132.390382) (xy 4.353865 -132.468612)
			(xy 4.361945 -132.548067) (xy 4.36245 -132.588) (xy 4.361945 -132.627933) (xy 4.353865 -132.707388)
			(xy 4.337788 -132.785618) (xy 4.313879 -132.86182) (xy 4.282384 -132.935213) (xy 4.243625 -133.005043)
			(xy 4.198001 -133.070593) (xy 4.145979 -133.131192) (xy 4.088094 -133.186216) (xy 4.024938 -133.235102)
			(xy 3.980288 -133.262933) (xy 13.247113 -133.262933) (xy 13.247113 -133.183067) (xy 13.255193 -133.103612)
			(xy 13.27127 -133.025382) (xy 13.295179 -132.94918) (xy 13.326674 -132.875787) (xy 13.365433 -132.805957)
			(xy 13.411057 -132.740407) (xy 13.463079 -132.679808) (xy 13.520964 -132.624784) (xy 13.58412 -132.575898)
			(xy 13.651897 -132.533652) (xy 13.7236 -132.49848) (xy 13.798494 -132.470743) (xy 13.875809 -132.450724)
			(xy 13.954753 -132.438631) (xy 14.034516 -132.434586) (xy 14.114279 -132.438631) (xy 14.193223 -132.450724)
			(xy 14.270538 -132.470743) (xy 14.345432 -132.49848) (xy 14.417135 -132.533652) (xy 14.484912 -132.575898)
			(xy 14.548068 -132.624784) (xy 14.605953 -132.679808) (xy 14.657975 -132.740407) (xy 14.703599 -132.805957)
			(xy 14.742358 -132.875787) (xy 14.773853 -132.94918) (xy 14.797762 -133.025382) (xy 14.813839 -133.103612)
			(xy 14.821919 -133.183067) (xy 14.822424 -133.223) (xy 14.821919 -133.262933) (xy 14.813839 -133.342388)
			(xy 14.797762 -133.420618) (xy 14.773853 -133.49682) (xy 14.742358 -133.570213) (xy 14.703599 -133.640043)
			(xy 14.657975 -133.705593) (xy 14.605953 -133.766192) (xy 14.548068 -133.821216) (xy 14.484912 -133.870102)
			(xy 14.417135 -133.912348) (xy 14.345432 -133.94752) (xy 14.270538 -133.975257) (xy 14.193223 -133.995276)
			(xy 14.114279 -134.007369) (xy 14.034516 -134.011415) (xy 13.954753 -134.007369) (xy 13.875809 -133.995276)
			(xy 13.798494 -133.975257) (xy 13.7236 -133.94752) (xy 13.651897 -133.912348) (xy 13.58412 -133.870102)
			(xy 13.520964 -133.821216) (xy 13.463079 -133.766192) (xy 13.411057 -133.705593) (xy 13.365433 -133.640043)
			(xy 13.326674 -133.570213) (xy 13.295179 -133.49682) (xy 13.27127 -133.420618) (xy 13.255193 -133.342388)
			(xy 13.247113 -133.262933) (xy 3.980288 -133.262933) (xy 3.957161 -133.277348) (xy 3.885458 -133.31252)
			(xy 3.810564 -133.340257) (xy 3.733249 -133.360276) (xy 3.654305 -133.372369) (xy 3.574542 -133.376415)
			(xy 3.494779 -133.372369) (xy 3.415835 -133.360276) (xy 3.33852 -133.340257) (xy 3.263626 -133.31252)
			(xy 3.191923 -133.277348) (xy 3.124146 -133.235102) (xy 3.06099 -133.186216) (xy 3.003105 -133.131192)
			(xy 2.951083 -133.070593) (xy 2.905459 -133.005043) (xy 2.8667 -132.935213) (xy 2.835205 -132.86182)
			(xy 2.811296 -132.785618) (xy 2.795219 -132.707388) (xy 2.787139 -132.627933) (xy 1.27 -132.627933)
			(xy 1.27 -134.532933) (xy 15.787113 -134.532933) (xy 15.787113 -134.453067) (xy 15.795193 -134.373612)
			(xy 15.81127 -134.295382) (xy 15.835179 -134.21918) (xy 15.866674 -134.145787) (xy 15.905433 -134.075957)
			(xy 15.951057 -134.010407) (xy 16.003079 -133.949808) (xy 16.060964 -133.894784) (xy 16.12412 -133.845898)
			(xy 16.191897 -133.803652) (xy 16.2636 -133.76848) (xy 16.338494 -133.740743) (xy 16.415809 -133.720724)
			(xy 16.494753 -133.708631) (xy 16.574516 -133.704586) (xy 16.654279 -133.708631) (xy 16.733223 -133.720724)
			(xy 16.810538 -133.740743) (xy 16.885432 -133.76848) (xy 16.957135 -133.803652) (xy 17.024912 -133.845898)
			(xy 17.088068 -133.894784) (xy 17.145953 -133.949808) (xy 17.197975 -134.010407) (xy 17.243599 -134.075957)
			(xy 17.282358 -134.145787) (xy 17.313853 -134.21918) (xy 17.337762 -134.295382) (xy 17.353839 -134.373612)
			(xy 17.361919 -134.453067) (xy 17.362424 -134.493) (xy 17.361919 -134.532933) (xy 17.353839 -134.612388)
			(xy 17.337762 -134.690618) (xy 17.313853 -134.76682) (xy 17.282358 -134.840213) (xy 17.243599 -134.910043)
			(xy 17.197975 -134.975593) (xy 17.145953 -135.036192) (xy 17.088068 -135.091216) (xy 17.024912 -135.140102)
			(xy 16.957135 -135.182348) (xy 16.885432 -135.21752) (xy 16.810538 -135.245257) (xy 16.733223 -135.265276)
			(xy 16.654279 -135.277369) (xy 16.574516 -135.281415) (xy 16.494753 -135.277369) (xy 16.415809 -135.265276)
			(xy 16.338494 -135.245257) (xy 16.2636 -135.21752) (xy 16.191897 -135.182348) (xy 16.12412 -135.140102)
			(xy 16.060964 -135.091216) (xy 16.003079 -135.036192) (xy 15.951057 -134.975593) (xy 15.905433 -134.910043)
			(xy 15.866674 -134.840213) (xy 15.835179 -134.76682) (xy 15.81127 -134.690618) (xy 15.795193 -134.612388)
			(xy 15.787113 -134.532933) (xy 1.27 -134.532933) (xy 1.27 -135.802933) (xy 13.247113 -135.802933)
			(xy 13.247113 -135.723067) (xy 13.255193 -135.643612) (xy 13.27127 -135.565382) (xy 13.295179 -135.48918)
			(xy 13.326674 -135.415787) (xy 13.365433 -135.345957) (xy 13.411057 -135.280407) (xy 13.463079 -135.219808)
			(xy 13.520964 -135.164784) (xy 13.58412 -135.115898) (xy 13.651897 -135.073652) (xy 13.7236 -135.03848)
			(xy 13.798494 -135.010743) (xy 13.875809 -134.990724) (xy 13.954753 -134.978631) (xy 14.034516 -134.974586)
			(xy 14.114279 -134.978631) (xy 14.193223 -134.990724) (xy 14.270538 -135.010743) (xy 14.345432 -135.03848)
			(xy 14.417135 -135.073652) (xy 14.484912 -135.115898) (xy 14.548068 -135.164784) (xy 14.605953 -135.219808)
			(xy 14.657975 -135.280407) (xy 14.703599 -135.345957) (xy 14.742358 -135.415787) (xy 14.773853 -135.48918)
			(xy 14.797762 -135.565382) (xy 14.813839 -135.643612) (xy 14.821919 -135.723067) (xy 14.822424 -135.763)
			(xy 14.821919 -135.802933) (xy 14.813839 -135.882388) (xy 14.797762 -135.960618) (xy 14.773853 -136.03682)
			(xy 14.742358 -136.110213) (xy 14.703599 -136.180043) (xy 14.657975 -136.245593) (xy 14.605953 -136.306192)
			(xy 14.548068 -136.361216) (xy 14.484912 -136.410102) (xy 14.417135 -136.452348) (xy 14.345432 -136.48752)
			(xy 14.270538 -136.515257) (xy 14.193223 -136.535276) (xy 14.114279 -136.547369) (xy 14.034516 -136.551415)
			(xy 13.954753 -136.547369) (xy 13.875809 -136.535276) (xy 13.798494 -136.515257) (xy 13.7236 -136.48752)
			(xy 13.651897 -136.452348) (xy 13.58412 -136.410102) (xy 13.520964 -136.361216) (xy 13.463079 -136.306192)
			(xy 13.411057 -136.245593) (xy 13.365433 -136.180043) (xy 13.326674 -136.110213) (xy 13.295179 -136.03682)
			(xy 13.27127 -135.960618) (xy 13.255193 -135.882388) (xy 13.247113 -135.802933) (xy 1.27 -135.802933)
			(xy 1.27 -137.072933) (xy 15.787113 -137.072933) (xy 15.787113 -136.993067) (xy 15.795193 -136.913612)
			(xy 15.81127 -136.835382) (xy 15.835179 -136.75918) (xy 15.866674 -136.685787) (xy 15.905433 -136.615957)
			(xy 15.951057 -136.550407) (xy 16.003079 -136.489808) (xy 16.060964 -136.434784) (xy 16.12412 -136.385898)
			(xy 16.191897 -136.343652) (xy 16.2636 -136.30848) (xy 16.338494 -136.280743) (xy 16.415809 -136.260724)
			(xy 16.494753 -136.248631) (xy 16.574516 -136.244586) (xy 16.654279 -136.248631) (xy 16.733223 -136.260724)
			(xy 16.810538 -136.280743) (xy 16.885432 -136.30848) (xy 16.957135 -136.343652) (xy 17.024912 -136.385898)
			(xy 17.088068 -136.434784) (xy 17.145953 -136.489808) (xy 17.197975 -136.550407) (xy 17.243599 -136.615957)
			(xy 17.282358 -136.685787) (xy 17.313853 -136.75918) (xy 17.337762 -136.835382) (xy 17.353839 -136.913612)
			(xy 17.361919 -136.993067) (xy 17.362424 -137.033) (xy 17.361919 -137.072933) (xy 17.353839 -137.152388)
			(xy 17.337762 -137.230618) (xy 17.313853 -137.30682) (xy 17.282358 -137.380213) (xy 17.243599 -137.450043)
			(xy 17.197975 -137.515593) (xy 17.145953 -137.576192) (xy 17.088068 -137.631216) (xy 17.024912 -137.680102)
			(xy 16.957135 -137.722348) (xy 16.885432 -137.75752) (xy 16.810538 -137.785257) (xy 16.733223 -137.805276)
			(xy 16.654279 -137.817369) (xy 16.574516 -137.821415) (xy 16.494753 -137.817369) (xy 16.415809 -137.805276)
			(xy 16.338494 -137.785257) (xy 16.2636 -137.75752) (xy 16.191897 -137.722348) (xy 16.12412 -137.680102)
			(xy 16.060964 -137.631216) (xy 16.003079 -137.576192) (xy 15.951057 -137.515593) (xy 15.905433 -137.450043)
			(xy 15.866674 -137.380213) (xy 15.835179 -137.30682) (xy 15.81127 -137.230618) (xy 15.795193 -137.152388)
			(xy 15.787113 -137.072933) (xy 1.27 -137.072933) (xy 1.27 -138.342933) (xy 13.247113 -138.342933)
			(xy 13.247113 -138.263067) (xy 13.255193 -138.183612) (xy 13.27127 -138.105382) (xy 13.295179 -138.02918)
			(xy 13.326674 -137.955787) (xy 13.365433 -137.885957) (xy 13.411057 -137.820407) (xy 13.463079 -137.759808)
			(xy 13.520964 -137.704784) (xy 13.58412 -137.655898) (xy 13.651897 -137.613652) (xy 13.7236 -137.57848)
			(xy 13.798494 -137.550743) (xy 13.875809 -137.530724) (xy 13.954753 -137.518631) (xy 14.034516 -137.514586)
			(xy 14.114279 -137.518631) (xy 14.193223 -137.530724) (xy 14.270538 -137.550743) (xy 14.345432 -137.57848)
			(xy 14.417135 -137.613652) (xy 14.484912 -137.655898) (xy 14.548068 -137.704784) (xy 14.605953 -137.759808)
			(xy 14.657975 -137.820407) (xy 14.703599 -137.885957) (xy 14.742358 -137.955787) (xy 14.773853 -138.02918)
			(xy 14.797762 -138.105382) (xy 14.813839 -138.183612) (xy 14.821919 -138.263067) (xy 14.822424 -138.303)
			(xy 14.821919 -138.342933) (xy 14.813839 -138.422388) (xy 14.797762 -138.500618) (xy 14.773853 -138.57682)
			(xy 14.742358 -138.650213) (xy 14.703599 -138.720043) (xy 14.657975 -138.785593) (xy 14.605953 -138.846192)
			(xy 14.548068 -138.901216) (xy 14.484912 -138.950102) (xy 14.417135 -138.992348) (xy 14.345432 -139.02752)
			(xy 14.270538 -139.055257) (xy 14.193223 -139.075276) (xy 14.114279 -139.087369) (xy 14.034516 -139.091415)
			(xy 13.954753 -139.087369) (xy 13.875809 -139.075276) (xy 13.798494 -139.055257) (xy 13.7236 -139.02752)
			(xy 13.651897 -138.992348) (xy 13.58412 -138.950102) (xy 13.520964 -138.901216) (xy 13.463079 -138.846192)
			(xy 13.411057 -138.785593) (xy 13.365433 -138.720043) (xy 13.326674 -138.650213) (xy 13.295179 -138.57682)
			(xy 13.27127 -138.500618) (xy 13.255193 -138.422388) (xy 13.247113 -138.342933) (xy 1.27 -138.342933)
			(xy 1.27 -140.247933) (xy 2.787139 -140.247933) (xy 2.787139 -140.168067) (xy 2.795219 -140.088612)
			(xy 2.811296 -140.010382) (xy 2.835205 -139.93418) (xy 2.8667 -139.860787) (xy 2.905459 -139.790957)
			(xy 2.951083 -139.725407) (xy 3.003105 -139.664808) (xy 3.06099 -139.609784) (xy 3.124146 -139.560898)
			(xy 3.191923 -139.518652) (xy 3.263626 -139.48348) (xy 3.33852 -139.455743) (xy 3.415835 -139.435724)
			(xy 3.494779 -139.423631) (xy 3.574542 -139.419586) (xy 3.654305 -139.423631) (xy 3.733249 -139.435724)
			(xy 3.810564 -139.455743) (xy 3.885458 -139.48348) (xy 3.957161 -139.518652) (xy 4.024938 -139.560898)
			(xy 4.088094 -139.609784) (xy 4.091407 -139.612933) (xy 15.787113 -139.612933) (xy 15.787113 -139.533067)
			(xy 15.795193 -139.453612) (xy 15.81127 -139.375382) (xy 15.835179 -139.29918) (xy 15.866674 -139.225787)
			(xy 15.905433 -139.155957) (xy 15.951057 -139.090407) (xy 16.003079 -139.029808) (xy 16.060964 -138.974784)
			(xy 16.12412 -138.925898) (xy 16.191897 -138.883652) (xy 16.2636 -138.84848) (xy 16.338494 -138.820743)
			(xy 16.415809 -138.800724) (xy 16.494753 -138.788631) (xy 16.574516 -138.784586) (xy 16.654279 -138.788631)
			(xy 16.733223 -138.800724) (xy 16.810538 -138.820743) (xy 16.885432 -138.84848) (xy 16.957135 -138.883652)
			(xy 17.024912 -138.925898) (xy 17.088068 -138.974784) (xy 17.145953 -139.029808) (xy 17.197975 -139.090407)
			(xy 17.243599 -139.155957) (xy 17.282358 -139.225787) (xy 17.313853 -139.29918) (xy 17.337762 -139.375382)
			(xy 17.353839 -139.453612) (xy 17.361919 -139.533067) (xy 17.362424 -139.573) (xy 17.361919 -139.612933)
			(xy 17.353839 -139.692388) (xy 17.337762 -139.770618) (xy 17.313853 -139.84682) (xy 17.282358 -139.920213)
			(xy 17.243599 -139.990043) (xy 17.197975 -140.055593) (xy 17.145953 -140.116192) (xy 17.088068 -140.171216)
			(xy 17.024912 -140.220102) (xy 16.957135 -140.262348) (xy 16.885432 -140.29752) (xy 16.810538 -140.325257)
			(xy 16.733223 -140.345276) (xy 16.654279 -140.357369) (xy 16.574516 -140.361415) (xy 16.494753 -140.357369)
			(xy 16.415809 -140.345276) (xy 16.338494 -140.325257) (xy 16.2636 -140.29752) (xy 16.191897 -140.262348)
			(xy 16.12412 -140.220102) (xy 16.060964 -140.171216) (xy 16.003079 -140.116192) (xy 15.951057 -140.055593)
			(xy 15.905433 -139.990043) (xy 15.866674 -139.920213) (xy 15.835179 -139.84682) (xy 15.81127 -139.770618)
			(xy 15.795193 -139.692388) (xy 15.787113 -139.612933) (xy 4.091407 -139.612933) (xy 4.145979 -139.664808)
			(xy 4.198001 -139.725407) (xy 4.243625 -139.790957) (xy 4.282384 -139.860787) (xy 4.313879 -139.93418)
			(xy 4.337788 -140.010382) (xy 4.353865 -140.088612) (xy 4.361945 -140.168067) (xy 4.36245 -140.208)
			(xy 4.361945 -140.247933) (xy 4.353865 -140.327388) (xy 4.337788 -140.405618) (xy 4.313879 -140.48182)
			(xy 4.282384 -140.555213) (xy 4.243625 -140.625043) (xy 4.198001 -140.690593) (xy 4.145979 -140.751192)
			(xy 4.088094 -140.806216) (xy 4.024938 -140.855102) (xy 3.957161 -140.897348) (xy 3.885458 -140.93252)
			(xy 3.810564 -140.960257) (xy 3.733249 -140.980276) (xy 3.654305 -140.992369) (xy 3.574542 -140.996415)
			(xy 3.494779 -140.992369) (xy 3.415835 -140.980276) (xy 3.33852 -140.960257) (xy 3.263626 -140.93252)
			(xy 3.191923 -140.897348) (xy 3.124146 -140.855102) (xy 3.06099 -140.806216) (xy 3.003105 -140.751192)
			(xy 2.951083 -140.690593) (xy 2.905459 -140.625043) (xy 2.8667 -140.555213) (xy 2.835205 -140.48182)
			(xy 2.811296 -140.405618) (xy 2.795219 -140.327388) (xy 2.787139 -140.247933) (xy 1.27 -140.247933)
			(xy 1.27 -142.737895) (xy 2.787139 -142.737895) (xy 2.787139 -142.658029) (xy 2.795219 -142.578574)
			(xy 2.811296 -142.500344) (xy 2.835205 -142.424142) (xy 2.8667 -142.350749) (xy 2.905459 -142.280919)
			(xy 2.951083 -142.215369) (xy 3.003105 -142.15477) (xy 3.06099 -142.099746) (xy 3.124146 -142.05086)
			(xy 3.191923 -142.008614) (xy 3.263626 -141.973442) (xy 3.33852 -141.945705) (xy 3.415835 -141.925686)
			(xy 3.494779 -141.913593) (xy 3.574542 -141.909548) (xy 3.654305 -141.913593) (xy 3.733249 -141.925686)
			(xy 3.810564 -141.945705) (xy 3.885458 -141.973442) (xy 3.957161 -142.008614) (xy 4.024938 -142.05086)
			(xy 4.088094 -142.099746) (xy 4.145979 -142.15477) (xy 4.164263 -142.176068) (xy 5.677649 -142.176068)
			(xy 5.677649 -142.049932) (xy 5.685569 -141.924044) (xy 5.701379 -141.798902) (xy 5.725014 -141.674999)
			(xy 5.756383 -141.552826) (xy 5.795361 -141.432863) (xy 5.841795 -141.315584) (xy 5.895502 -141.201452)
			(xy 5.956269 -141.090917) (xy 6.023856 -140.984417) (xy 6.097997 -140.88237) (xy 6.1784 -140.78518)
			(xy 6.264746 -140.69323) (xy 6.356696 -140.606884) (xy 6.453886 -140.526481) (xy 6.555933 -140.45234)
			(xy 6.662433 -140.384753) (xy 6.772968 -140.323986) (xy 6.8871 -140.270279) (xy 7.004379 -140.223845)
			(xy 7.124342 -140.184867) (xy 7.246515 -140.153498) (xy 7.370418 -140.129863) (xy 7.49556 -140.114053)
			(xy 7.621448 -140.106133) (xy 7.747584 -140.106133) (xy 7.873472 -140.114053) (xy 7.998614 -140.129863)
			(xy 8.122517 -140.153498) (xy 8.24469 -140.184867) (xy 8.364653 -140.223845) (xy 8.481932 -140.270279)
			(xy 8.596064 -140.323986) (xy 8.706599 -140.384753) (xy 8.813099 -140.45234) (xy 8.915146 -140.526481)
			(xy 9.012336 -140.606884) (xy 9.104286 -140.69323) (xy 9.190632 -140.78518) (xy 9.271035 -140.88237)
			(xy 9.271444 -140.882933) (xy 13.247113 -140.882933) (xy 13.247113 -140.803067) (xy 13.255193 -140.723612)
			(xy 13.27127 -140.645382) (xy 13.295179 -140.56918) (xy 13.326674 -140.495787) (xy 13.365433 -140.425957)
			(xy 13.411057 -140.360407) (xy 13.463079 -140.299808) (xy 13.520964 -140.244784) (xy 13.58412 -140.195898)
			(xy 13.651897 -140.153652) (xy 13.7236 -140.11848) (xy 13.798494 -140.090743) (xy 13.875809 -140.070724)
			(xy 13.954753 -140.058631) (xy 14.034516 -140.054586) (xy 14.114279 -140.058631) (xy 14.193223 -140.070724)
			(xy 14.270538 -140.090743) (xy 14.345432 -140.11848) (xy 14.417135 -140.153652) (xy 14.484912 -140.195898)
			(xy 14.548068 -140.244784) (xy 14.605953 -140.299808) (xy 14.657975 -140.360407) (xy 14.703599 -140.425957)
			(xy 14.742358 -140.495787) (xy 14.773853 -140.56918) (xy 14.797762 -140.645382) (xy 14.813839 -140.723612)
			(xy 14.821919 -140.803067) (xy 14.822424 -140.843) (xy 14.821919 -140.882933) (xy 14.813839 -140.962388)
			(xy 14.797762 -141.040618) (xy 14.773853 -141.11682) (xy 14.742358 -141.190213) (xy 14.703599 -141.260043)
			(xy 14.657975 -141.325593) (xy 14.605953 -141.386192) (xy 14.548068 -141.441216) (xy 14.484912 -141.490102)
			(xy 14.417135 -141.532348) (xy 14.345432 -141.56752) (xy 14.270538 -141.595257) (xy 14.193223 -141.615276)
			(xy 14.114279 -141.627369) (xy 14.034516 -141.631415) (xy 13.954753 -141.627369) (xy 13.875809 -141.615276)
			(xy 13.798494 -141.595257) (xy 13.7236 -141.56752) (xy 13.651897 -141.532348) (xy 13.58412 -141.490102)
			(xy 13.520964 -141.441216) (xy 13.463079 -141.386192) (xy 13.411057 -141.325593) (xy 13.365433 -141.260043)
			(xy 13.326674 -141.190213) (xy 13.295179 -141.11682) (xy 13.27127 -141.040618) (xy 13.255193 -140.962388)
			(xy 13.247113 -140.882933) (xy 9.271444 -140.882933) (xy 9.345176 -140.984417) (xy 9.412763 -141.090917)
			(xy 9.47353 -141.201452) (xy 9.527237 -141.315584) (xy 9.573671 -141.432863) (xy 9.612649 -141.552826)
			(xy 9.644018 -141.674999) (xy 9.667653 -141.798902) (xy 9.683463 -141.924044) (xy 9.691383 -142.049932)
			(xy 9.691878 -142.113) (xy 9.691383 -142.176068) (xy 9.683463 -142.301956) (xy 9.667653 -142.427098)
			(xy 9.644018 -142.551001) (xy 9.612649 -142.673174) (xy 9.573671 -142.793137) (xy 9.527237 -142.910416)
			(xy 9.47353 -143.024548) (xy 9.412763 -143.135083) (xy 9.345176 -143.241583) (xy 9.271035 -143.34363)
			(xy 9.190632 -143.44082) (xy 9.104286 -143.53277) (xy 9.012336 -143.619116) (xy 8.915146 -143.699519)
			(xy 8.813099 -143.77366) (xy 8.706599 -143.841247) (xy 8.596064 -143.902014) (xy 8.481932 -143.955721)
			(xy 8.364653 -144.002155) (xy 8.24469 -144.041133) (xy 8.122517 -144.072502) (xy 7.998614 -144.096137)
			(xy 7.873472 -144.111947) (xy 7.747584 -144.119867) (xy 7.621448 -144.119867) (xy 7.49556 -144.111947)
			(xy 7.370418 -144.096137) (xy 7.246515 -144.072502) (xy 7.124342 -144.041133) (xy 7.004379 -144.002155)
			(xy 6.8871 -143.955721) (xy 6.772968 -143.902014) (xy 6.662433 -143.841247) (xy 6.555933 -143.77366)
			(xy 6.453886 -143.699519) (xy 6.356696 -143.619116) (xy 6.264746 -143.53277) (xy 6.1784 -143.44082)
			(xy 6.097997 -143.34363) (xy 6.023856 -143.241583) (xy 5.956269 -143.135083) (xy 5.895502 -143.024548)
			(xy 5.841795 -142.910416) (xy 5.795361 -142.793137) (xy 5.756383 -142.673174) (xy 5.725014 -142.551001)
			(xy 5.701379 -142.427098) (xy 5.685569 -142.301956) (xy 5.677649 -142.176068) (xy 4.164263 -142.176068)
			(xy 4.198001 -142.215369) (xy 4.243625 -142.280919) (xy 4.282384 -142.350749) (xy 4.313879 -142.424142)
			(xy 4.337788 -142.500344) (xy 4.353865 -142.578574) (xy 4.361945 -142.658029) (xy 4.36245 -142.697962)
			(xy 4.361945 -142.737895) (xy 4.353865 -142.81735) (xy 4.337788 -142.89558) (xy 4.313879 -142.971782)
			(xy 4.282384 -143.045175) (xy 4.243625 -143.115005) (xy 4.198001 -143.180555) (xy 4.145979 -143.241154)
			(xy 4.088094 -143.296178) (xy 4.024938 -143.345064) (xy 3.957161 -143.38731) (xy 3.885458 -143.422482)
			(xy 3.810564 -143.450219) (xy 3.733249 -143.470238) (xy 3.654305 -143.482331) (xy 3.574542 -143.486377)
			(xy 3.494779 -143.482331) (xy 3.415835 -143.470238) (xy 3.33852 -143.450219) (xy 3.263626 -143.422482)
			(xy 3.191923 -143.38731) (xy 3.124146 -143.345064) (xy 3.06099 -143.296178) (xy 3.003105 -143.241154)
			(xy 2.951083 -143.180555) (xy 2.905459 -143.115005) (xy 2.8667 -143.045175) (xy 2.835205 -142.971782)
			(xy 2.811296 -142.89558) (xy 2.795219 -142.81735) (xy 2.787139 -142.737895) (xy 1.27 -142.737895)
			(xy 1.27 -144.324412) (xy 10.22629 -144.324412) (xy 10.22629 -144.22162) (xy 10.234355 -144.119146)
			(xy 10.250435 -144.017621) (xy 10.274431 -143.91767) (xy 10.306196 -143.81991) (xy 10.345532 -143.724943)
			(xy 10.392198 -143.633356) (xy 10.445906 -143.545712) (xy 10.506325 -143.462552) (xy 10.573083 -143.384389)
			(xy 10.645767 -143.311705) (xy 10.72393 -143.244947) (xy 10.80709 -143.184528) (xy 10.894734 -143.13082)
			(xy 10.986321 -143.084154) (xy 11.081288 -143.044818) (xy 11.179048 -143.013053) (xy 11.278999 -142.989057)
			(xy 11.380524 -142.972977) (xy 11.482998 -142.964912) (xy 11.58579 -142.964912) (xy 11.688264 -142.972977)
			(xy 11.789789 -142.989057) (xy 11.88974 -143.013053) (xy 11.9875 -143.044818) (xy 12.082467 -143.084154)
			(xy 12.174054 -143.13082) (xy 12.261698 -143.184528) (xy 12.344858 -143.244947) (xy 12.423021 -143.311705)
			(xy 12.495705 -143.384389) (xy 12.562463 -143.462552) (xy 12.622882 -143.545712) (xy 12.67659 -143.633356)
			(xy 12.723256 -143.724943) (xy 12.762592 -143.81991) (xy 12.794357 -143.91767) (xy 12.818353 -144.017621)
			(xy 12.834433 -144.119146) (xy 12.842498 -144.22162) (xy 12.843002 -144.273016) (xy 12.842498 -144.324412)
			(xy 12.834433 -144.426886) (xy 12.818353 -144.528411) (xy 12.794357 -144.628362) (xy 12.762592 -144.726122)
			(xy 12.723256 -144.821089) (xy 12.67659 -144.912676) (xy 12.622882 -145.00032) (xy 12.562463 -145.08348)
			(xy 12.495705 -145.161643) (xy 12.423021 -145.234327) (xy 12.344858 -145.301085) (xy 12.261698 -145.361504)
			(xy 12.174054 -145.415212) (xy 12.082467 -145.461878) (xy 11.9875 -145.501214) (xy 11.88974 -145.532979)
			(xy 11.789789 -145.556975) (xy 11.688264 -145.573055) (xy 11.58579 -145.58112) (xy 11.482998 -145.58112)
			(xy 11.380524 -145.573055) (xy 11.278999 -145.556975) (xy 11.179048 -145.532979) (xy 11.081288 -145.501214)
			(xy 10.986321 -145.461878) (xy 10.894734 -145.415212) (xy 10.80709 -145.361504) (xy 10.72393 -145.301085)
			(xy 10.645767 -145.234327) (xy 10.573083 -145.161643) (xy 10.506325 -145.08348) (xy 10.445906 -145.00032)
			(xy 10.392198 -144.912676) (xy 10.345532 -144.821089) (xy 10.306196 -144.726122) (xy 10.274431 -144.628362)
			(xy 10.250435 -144.528411) (xy 10.234355 -144.426886) (xy 10.22629 -144.324412) (xy 1.27 -144.324412)
			(xy 1.27 -147.027392) (xy 2.390138 -147.027392) (xy 2.394209 -146.97177) (xy 2.406335 -146.917333)
			(xy 2.426258 -146.865242) (xy 2.453554 -146.816607) (xy 2.48764 -146.772464) (xy 2.527789 -146.733755)
			(xy 2.573147 -146.701304) (xy 2.622747 -146.675803) (xy 2.675531 -146.657796) (xy 2.730374 -146.647666)
			(xy 2.786108 -146.645629) (xy 2.841545 -146.651729) (xy 2.895502 -146.665835) (xy 2.946831 -146.687647)
			(xy 2.994437 -146.716701) (xy 3.037305 -146.752376) (xy 3.074522 -146.793913) (xy 3.105295 -146.840426)
			(xy 3.128967 -146.890923) (xy 3.145035 -146.94433) (xy 3.153155 -146.999506) (xy 3.153664 -147.027392)
			(xy 3.153659 -147.027646) (xy 3.677918 -147.027646) (xy 3.681989 -146.972024) (xy 3.694115 -146.917587)
			(xy 3.714038 -146.865496) (xy 3.741334 -146.816861) (xy 3.77542 -146.772718) (xy 3.815569 -146.734009)
			(xy 3.860927 -146.701558) (xy 3.910527 -146.676057) (xy 3.963311 -146.65805) (xy 4.018154 -146.64792)
			(xy 4.073888 -146.645883) (xy 4.129325 -146.651983) (xy 4.183282 -146.666089) (xy 4.234611 -146.687901)
			(xy 4.282217 -146.716955) (xy 4.325085 -146.75263) (xy 4.362302 -146.794167) (xy 4.393075 -146.84068)
			(xy 4.416747 -146.891177) (xy 4.432815 -146.944584) (xy 4.440935 -146.99976) (xy 4.441444 -147.027646)
			(xy 4.440935 -147.055532) (xy 4.432815 -147.110708) (xy 4.416747 -147.164115) (xy 4.393075 -147.214612)
			(xy 4.362302 -147.261125) (xy 4.325085 -147.302662) (xy 4.282217 -147.338337) (xy 4.234611 -147.367391)
			(xy 4.183282 -147.389203) (xy 4.129325 -147.403309) (xy 4.073888 -147.409409) (xy 4.018154 -147.407372)
			(xy 3.963311 -147.397242) (xy 3.910527 -147.379235) (xy 3.860927 -147.353734) (xy 3.815569 -147.321283)
			(xy 3.77542 -147.282574) (xy 3.741334 -147.238431) (xy 3.714038 -147.189796) (xy 3.694115 -147.137705)
			(xy 3.681989 -147.083268) (xy 3.677918 -147.027646) (xy 3.153659 -147.027646) (xy 3.153155 -147.055278)
			(xy 3.145035 -147.110454) (xy 3.128967 -147.163861) (xy 3.105295 -147.214358) (xy 3.074522 -147.260871)
			(xy 3.037305 -147.302408) (xy 2.994437 -147.338083) (xy 2.946831 -147.367137) (xy 2.895502 -147.388949)
			(xy 2.841545 -147.403055) (xy 2.786108 -147.409155) (xy 2.730374 -147.407118) (xy 2.675531 -147.396988)
			(xy 2.622747 -147.378981) (xy 2.573147 -147.35348) (xy 2.527789 -147.321029) (xy 2.48764 -147.28232)
			(xy 2.453554 -147.238177) (xy 2.426258 -147.189542) (xy 2.406335 -147.137451) (xy 2.394209 -147.083014)
			(xy 2.390138 -147.027392) (xy 1.27 -147.027392) (xy 1.27 -169.167048) (xy 15.337534 -169.167048)
			(xy 15.341605 -169.111426) (xy 15.353731 -169.056989) (xy 15.373654 -169.004898) (xy 15.40095 -168.956263)
			(xy 15.435036 -168.91212) (xy 15.475185 -168.873411) (xy 15.520543 -168.84096) (xy 15.570143 -168.815459)
			(xy 15.622927 -168.797452) (xy 15.67777 -168.787322) (xy 15.733504 -168.785285) (xy 15.788941 -168.791385)
			(xy 15.842898 -168.805491) (xy 15.894227 -168.827303) (xy 15.941833 -168.856357) (xy 15.984701 -168.892032)
			(xy 16.021918 -168.933569) (xy 16.052691 -168.980082) (xy 16.076363 -169.030579) (xy 16.092431 -169.083986)
			(xy 16.100551 -169.139162) (xy 16.10106 -169.167048) (xy 16.100551 -169.194934) (xy 16.092431 -169.25011)
			(xy 16.076363 -169.303517) (xy 16.052691 -169.354014) (xy 16.021918 -169.400527) (xy 15.984701 -169.442064)
			(xy 15.941833 -169.477739) (xy 15.894227 -169.506793) (xy 15.842898 -169.528605) (xy 15.788941 -169.542711)
			(xy 15.733504 -169.548811) (xy 15.67777 -169.546774) (xy 15.622927 -169.536644) (xy 15.570143 -169.518637)
			(xy 15.520543 -169.493136) (xy 15.475185 -169.460685) (xy 15.435036 -169.421976) (xy 15.40095 -169.377833)
			(xy 15.373654 -169.329198) (xy 15.353731 -169.277107) (xy 15.341605 -169.22267) (xy 15.337534 -169.167048)
			(xy 1.27 -169.167048) (xy 1.27 -170.372532) (xy 14.663926 -170.372532) (xy 14.667997 -170.31691)
			(xy 14.680123 -170.262473) (xy 14.700046 -170.210382) (xy 14.727342 -170.161747) (xy 14.761428 -170.117604)
			(xy 14.801577 -170.078895) (xy 14.846935 -170.046444) (xy 14.896535 -170.020943) (xy 14.949319 -170.002936)
			(xy 15.004162 -169.992806) (xy 15.059896 -169.990769) (xy 15.115333 -169.996869) (xy 15.16929 -170.010975)
			(xy 15.220619 -170.032787) (xy 15.268225 -170.061841) (xy 15.311093 -170.097516) (xy 15.34831 -170.139053)
			(xy 15.379083 -170.185566) (xy 15.402755 -170.236063) (xy 15.418823 -170.28947) (xy 15.426943 -170.344646)
			(xy 15.427452 -170.372532) (xy 15.426943 -170.400418) (xy 15.418823 -170.455594) (xy 15.402755 -170.509001)
			(xy 15.379083 -170.559498) (xy 15.34831 -170.606011) (xy 15.311093 -170.647548) (xy 15.268225 -170.683223)
			(xy 15.220619 -170.712277) (xy 15.16929 -170.734089) (xy 15.115333 -170.748195) (xy 15.059896 -170.754295)
			(xy 15.004162 -170.752258) (xy 14.949319 -170.742128) (xy 14.896535 -170.724121) (xy 14.846935 -170.69862)
			(xy 14.801577 -170.666169) (xy 14.761428 -170.62746) (xy 14.727342 -170.583317) (xy 14.700046 -170.534682)
			(xy 14.680123 -170.482591) (xy 14.667997 -170.428154) (xy 14.663926 -170.372532) (xy 1.27 -170.372532)
			(xy 1.27 -171.533058) (xy 14.127478 -171.533058) (xy 14.131549 -171.477436) (xy 14.143675 -171.422999)
			(xy 14.163598 -171.370908) (xy 14.190894 -171.322273) (xy 14.22498 -171.27813) (xy 14.265129 -171.239421)
			(xy 14.310487 -171.20697) (xy 14.360087 -171.181469) (xy 14.412871 -171.163462) (xy 14.467714 -171.153332)
			(xy 14.523448 -171.151295) (xy 14.578885 -171.157395) (xy 14.632842 -171.171501) (xy 14.684171 -171.193313)
			(xy 14.731777 -171.222367) (xy 14.774645 -171.258042) (xy 14.811862 -171.299579) (xy 14.842635 -171.346092)
			(xy 14.866307 -171.396589) (xy 14.882375 -171.449996) (xy 14.890495 -171.505172) (xy 14.891004 -171.533058)
			(xy 14.890495 -171.560944) (xy 14.882375 -171.61612) (xy 14.866307 -171.669527) (xy 14.842635 -171.720024)
			(xy 14.811862 -171.766537) (xy 14.774645 -171.808074) (xy 14.731777 -171.843749) (xy 14.684171 -171.872803)
			(xy 14.632842 -171.894615) (xy 14.578885 -171.908721) (xy 14.523448 -171.914821) (xy 14.467714 -171.912784)
			(xy 14.412871 -171.902654) (xy 14.360087 -171.884647) (xy 14.310487 -171.859146) (xy 14.265129 -171.826695)
			(xy 14.22498 -171.787986) (xy 14.190894 -171.743843) (xy 14.163598 -171.695208) (xy 14.143675 -171.643117)
			(xy 14.131549 -171.58868) (xy 14.127478 -171.533058) (xy 1.27 -171.533058) (xy 1.27 -176.870614)
			(xy 3.864362 -176.870614) (xy 3.868375 -176.7672) (xy 3.88039 -176.664407) (xy 3.900334 -176.562855)
			(xy 3.928088 -176.463153) (xy 3.963484 -176.365903) (xy 4.00631 -176.271687) (xy 4.056309 -176.181074)
			(xy 4.113179 -176.094607) (xy 4.176578 -176.012808) (xy 4.246126 -175.936167) (xy 4.321403 -175.865146)
			(xy 4.401958 -175.800173) (xy 4.487305 -175.741637) (xy 4.576932 -175.689891) (xy 4.6703 -175.645245)
			(xy 4.766846 -175.60797) (xy 4.86599 -175.578288) (xy 4.967137 -175.556378) (xy 5.069677 -175.542372)
			(xy 5.172994 -175.536355) (xy 5.276467 -175.538362) (xy 5.379473 -175.548381) (xy 5.481393 -175.566352)
			(xy 5.581614 -175.592167) (xy 5.679533 -175.625671) (xy 5.774561 -175.666663) (xy 5.866127 -175.714894)
			(xy 5.95368 -175.770077) (xy 6.036694 -175.831878) (xy 6.114668 -175.899927) (xy 6.187135 -175.973813)
			(xy 6.253659 -176.053092) (xy 6.313839 -176.137289) (xy 6.367313 -176.225895) (xy 6.41376 -176.318379)
			(xy 6.452901 -176.414185) (xy 6.4845 -176.512735) (xy 6.508367 -176.613438) (xy 6.524359 -176.715687)
			(xy 6.532378 -176.818868) (xy 6.53288 -176.870614) (xy 6.532378 -176.92236) (xy 6.524359 -177.025541)
			(xy 6.508367 -177.12779) (xy 6.4845 -177.228493) (xy 6.452901 -177.327043) (xy 6.41376 -177.422849)
			(xy 6.367313 -177.515333) (xy 6.313839 -177.603939) (xy 6.253659 -177.688136) (xy 6.187135 -177.767415)
			(xy 6.114668 -177.841301) (xy 6.036694 -177.90935) (xy 5.95368 -177.971151) (xy 5.866127 -178.026334)
			(xy 5.774561 -178.074565) (xy 5.679533 -178.115557) (xy 5.581614 -178.149061) (xy 5.481393 -178.174876)
			(xy 5.379473 -178.192847) (xy 5.276467 -178.202866) (xy 5.172994 -178.204873) (xy 5.069677 -178.198856)
			(xy 4.967137 -178.18485) (xy 4.86599 -178.16294) (xy 4.766846 -178.133258) (xy 4.6703 -178.095983)
			(xy 4.576932 -178.051337) (xy 4.487305 -177.999591) (xy 4.401958 -177.941055) (xy 4.321403 -177.876082)
			(xy 4.246126 -177.805061) (xy 4.176578 -177.72842) (xy 4.113179 -177.646621) (xy 4.056309 -177.560154)
			(xy 4.00631 -177.469541) (xy 3.963484 -177.375325) (xy 3.928088 -177.278075) (xy 3.900334 -177.178373)
			(xy 3.88039 -177.076821) (xy 3.868375 -176.974028) (xy 3.864362 -176.870614) (xy 1.27 -176.870614)
			(xy 1.27 -179.706117) (xy 3.31393 -179.706117) (xy 3.31393 -179.634795) (xy 3.321916 -179.563921)
			(xy 3.337786 -179.494386) (xy 3.361343 -179.427066) (xy 3.392288 -179.362807) (xy 3.430234 -179.302416)
			(xy 3.474703 -179.246654) (xy 3.525136 -179.196221) (xy 3.580898 -179.151752) (xy 3.641289 -179.113806)
			(xy 3.705548 -179.082861) (xy 3.772868 -179.059304) (xy 3.842403 -179.043434) (xy 3.913277 -179.035448)
			(xy 3.984599 -179.035448) (xy 4.055473 -179.043434) (xy 4.125008 -179.059304) (xy 4.192328 -179.082861)
			(xy 4.256587 -179.113806) (xy 4.316978 -179.151752) (xy 4.37274 -179.196221) (xy 4.423173 -179.246654)
			(xy 4.467642 -179.302416) (xy 4.505588 -179.362807) (xy 4.536533 -179.427066) (xy 4.56009 -179.494386)
			(xy 4.57596 -179.563921) (xy 4.583946 -179.634795) (xy 4.584446 -179.670456) (xy 4.583946 -179.706117)
			(xy 4.57596 -179.776991) (xy 4.56009 -179.846526) (xy 4.536533 -179.913846) (xy 4.505588 -179.978105)
			(xy 4.467642 -180.038496) (xy 4.423173 -180.094258) (xy 4.37274 -180.144691) (xy 4.316978 -180.18916)
			(xy 4.256587 -180.227106) (xy 4.192328 -180.258051) (xy 4.125008 -180.281608) (xy 4.055473 -180.297478)
			(xy 3.984599 -180.305464) (xy 3.913277 -180.305464) (xy 3.842403 -180.297478) (xy 3.772868 -180.281608)
			(xy 3.705548 -180.258051) (xy 3.641289 -180.227106) (xy 3.580898 -180.18916) (xy 3.525136 -180.144691)
			(xy 3.474703 -180.094258) (xy 3.430234 -180.038496) (xy 3.392288 -179.978105) (xy 3.361343 -179.913846)
			(xy 3.337786 -179.846526) (xy 3.321916 -179.776991) (xy 3.31393 -179.706117) (xy 1.27 -179.706117)
			(xy 1.27 -181.888892) (xy 1.27042 -181.910637) (xy 1.277777 -181.9535) (xy 1.292327 -181.994484)
			(xy 1.313645 -182.032391) (xy 1.341108 -182.066113) (xy 1.373913 -182.094665) (xy 1.411101 -182.117212)
			(xy 1.451587 -182.133096) (xy 1.494186 -182.141852) (xy 1.537654 -182.143224) (xy 1.580721 -182.137173)
			(xy 1.622128 -182.123875) (xy 1.641602 -182.11419) (xy 1.673056 -182.097383) (xy 1.73895 -182.070098)
			(xy 1.807484 -182.050363) (xy 1.877796 -182.038424) (xy 1.949004 -182.034433) (xy 2.02021 -182.038438)
			(xy 2.09052 -182.050391) (xy 2.15905 -182.07014) (xy 2.224939 -182.097438) (xy 2.287356 -182.13194)
			(xy 2.345519 -182.173214) (xy 2.398695 -182.22074) (xy 2.446215 -182.273921) (xy 2.487483 -182.332088)
			(xy 2.52198 -182.394509) (xy 2.549271 -182.4604) (xy 2.569013 -182.528932) (xy 2.580959 -182.599243)
			(xy 2.584957 -182.67045) (xy 2.580959 -182.741657) (xy 2.569013 -182.811968) (xy 2.549271 -182.8805)
			(xy 2.52198 -182.946391) (xy 2.487483 -183.008812) (xy 2.446215 -183.066979) (xy 2.398695 -183.12016)
			(xy 2.345519 -183.167686) (xy 2.287356 -183.20896) (xy 2.224939 -183.243462) (xy 2.15905 -183.27076)
			(xy 2.09052 -183.290509) (xy 2.02021 -183.302462) (xy 1.949004 -183.306467) (xy 1.877796 -183.302476)
			(xy 1.807484 -183.290537) (xy 1.73895 -183.270802) (xy 1.673056 -183.243517) (xy 1.641602 -183.22671)
			(xy 1.622127 -183.217038) (xy 1.580725 -183.203758) (xy 1.537666 -183.197722) (xy 1.494208 -183.199105)
			(xy 1.45162 -183.207867) (xy 1.411146 -183.223751) (xy 1.373967 -183.246295) (xy 1.341169 -183.274839)
			(xy 1.31371 -183.308551) (xy 1.292391 -183.346446) (xy 1.277835 -183.387417) (xy 1.270468 -183.430268)
			(xy 1.27 -183.452008) (xy 1.27 -183.706109) (xy 3.31393 -183.706109) (xy 3.31393 -183.634787) (xy 3.321916 -183.563913)
			(xy 3.337786 -183.494378) (xy 3.361343 -183.427058) (xy 3.392288 -183.362799) (xy 3.430234 -183.302408)
			(xy 3.474703 -183.246646) (xy 3.525136 -183.196213) (xy 3.580898 -183.151744) (xy 3.641289 -183.113798)
			(xy 3.705548 -183.082853) (xy 3.772868 -183.059296) (xy 3.842403 -183.043426) (xy 3.913277 -183.03544)
			(xy 3.984599 -183.03544) (xy 4.055473 -183.043426) (xy 4.125008 -183.059296) (xy 4.192328 -183.082853)
			(xy 4.256587 -183.113798) (xy 4.316978 -183.151744) (xy 4.37274 -183.196213) (xy 4.423173 -183.246646)
			(xy 4.467642 -183.302408) (xy 4.505588 -183.362799) (xy 4.536533 -183.427058) (xy 4.56009 -183.494378)
			(xy 4.57596 -183.563913) (xy 4.583946 -183.634787) (xy 4.584446 -183.670448) (xy 4.583946 -183.706109)
			(xy 5.813798 -183.706109) (xy 5.813798 -183.634787) (xy 5.821784 -183.563913) (xy 5.837654 -183.494378)
			(xy 5.861211 -183.427058) (xy 5.892156 -183.362799) (xy 5.930102 -183.302408) (xy 5.974571 -183.246646)
			(xy 6.025004 -183.196213) (xy 6.080766 -183.151744) (xy 6.141157 -183.113798) (xy 6.205416 -183.082853)
			(xy 6.272736 -183.059296) (xy 6.342271 -183.043426) (xy 6.413145 -183.03544) (xy 6.484467 -183.03544)
			(xy 6.555341 -183.043426) (xy 6.624876 -183.059296) (xy 6.692196 -183.082853) (xy 6.756455 -183.113798)
			(xy 6.816846 -183.151744) (xy 6.872608 -183.196213) (xy 6.923041 -183.246646) (xy 6.96751 -183.302408)
			(xy 7.005456 -183.362799) (xy 7.036401 -183.427058) (xy 7.059958 -183.494378) (xy 7.075828 -183.563913)
			(xy 7.083814 -183.634787) (xy 7.084314 -183.670448) (xy 7.083814 -183.706109) (xy 7.075828 -183.776983)
			(xy 7.059958 -183.846518) (xy 7.036401 -183.913838) (xy 7.005456 -183.978097) (xy 6.96751 -184.038488)
			(xy 6.923041 -184.09425) (xy 6.872608 -184.144683) (xy 6.816846 -184.189152) (xy 6.756455 -184.227098)
			(xy 6.692196 -184.258043) (xy 6.624876 -184.2816) (xy 6.555341 -184.29747) (xy 6.484467 -184.305456)
			(xy 6.413145 -184.305456) (xy 6.342271 -184.29747) (xy 6.272736 -184.2816) (xy 6.205416 -184.258043)
			(xy 6.141157 -184.227098) (xy 6.080766 -184.189152) (xy 6.025004 -184.144683) (xy 5.974571 -184.09425)
			(xy 5.930102 -184.038488) (xy 5.892156 -183.978097) (xy 5.861211 -183.913838) (xy 5.837654 -183.846518)
			(xy 5.821784 -183.776983) (xy 5.813798 -183.706109) (xy 4.583946 -183.706109) (xy 4.57596 -183.776983)
			(xy 4.56009 -183.846518) (xy 4.536533 -183.913838) (xy 4.505588 -183.978097) (xy 4.467642 -184.038488)
			(xy 4.423173 -184.09425) (xy 4.37274 -184.144683) (xy 4.316978 -184.189152) (xy 4.256587 -184.227098)
			(xy 4.192328 -184.258043) (xy 4.125008 -184.2816) (xy 4.055473 -184.29747) (xy 3.984599 -184.305456)
			(xy 3.913277 -184.305456) (xy 3.842403 -184.29747) (xy 3.772868 -184.2816) (xy 3.705548 -184.258043)
			(xy 3.641289 -184.227098) (xy 3.580898 -184.189152) (xy 3.525136 -184.144683) (xy 3.474703 -184.09425)
			(xy 3.430234 -184.038488) (xy 3.392288 -183.978097) (xy 3.361343 -183.913838) (xy 3.337786 -183.846518)
			(xy 3.321916 -183.776983) (xy 3.31393 -183.706109) (xy 1.27 -183.706109) (xy 1.27 -183.888888) (xy 1.27042 -183.910634)
			(xy 1.277777 -183.953497) (xy 1.292326 -183.994482) (xy 1.313644 -184.032389) (xy 1.341107 -184.066112)
			(xy 1.373912 -184.094664) (xy 1.411101 -184.117211) (xy 1.451587 -184.133095) (xy 1.494186 -184.141852)
			(xy 1.537655 -184.143224) (xy 1.580722 -184.137173) (xy 1.62213 -184.123875) (xy 1.641602 -184.114186)
			(xy 1.673056 -184.097378) (xy 1.73895 -184.070094) (xy 1.807484 -184.050358) (xy 1.877797 -184.038419)
			(xy 1.949004 -184.034428) (xy 2.020211 -184.038433) (xy 2.090522 -184.050386) (xy 2.159052 -184.070135)
			(xy 2.22494 -184.097432) (xy 2.287358 -184.131935) (xy 2.345521 -184.173209) (xy 2.398697 -184.220735)
			(xy 2.446218 -184.273916) (xy 2.487486 -184.332083) (xy 2.521983 -184.394504) (xy 2.549274 -184.460395)
			(xy 2.569016 -184.528927) (xy 2.580962 -184.599239) (xy 2.58496 -184.670446) (xy 2.582958 -184.706107)
			(xy 7.813794 -184.706107) (xy 7.813794 -184.634785) (xy 7.82178 -184.563911) (xy 7.83765 -184.494376)
			(xy 7.861207 -184.427056) (xy 7.892152 -184.362797) (xy 7.930098 -184.302406) (xy 7.974567 -184.246644)
			(xy 8.025 -184.196211) (xy 8.080762 -184.151742) (xy 8.141153 -184.113796) (xy 8.205412 -184.082851)
			(xy 8.272732 -184.059294) (xy 8.342267 -184.043424) (xy 8.413141 -184.035438) (xy 8.484463 -184.035438)
			(xy 8.555337 -184.043424) (xy 8.624872 -184.059294) (xy 8.692192 -184.082851) (xy 8.756451 -184.113796)
			(xy 8.816842 -184.151742) (xy 8.872604 -184.196211) (xy 8.923037 -184.246644) (xy 8.967506 -184.302406)
			(xy 9.005452 -184.362797) (xy 9.036397 -184.427056) (xy 9.059954 -184.494376) (xy 9.075824 -184.563911)
			(xy 9.08381 -184.634785) (xy 9.08431 -184.670446) (xy 9.08381 -184.706107) (xy 9.075824 -184.776981)
			(xy 9.059954 -184.846516) (xy 9.036397 -184.913836) (xy 9.005452 -184.978095) (xy 8.967506 -185.038486)
			(xy 8.923037 -185.094248) (xy 8.872604 -185.144681) (xy 8.816842 -185.18915) (xy 8.756451 -185.227096)
			(xy 8.692192 -185.258041) (xy 8.624872 -185.281598) (xy 8.555337 -185.297468) (xy 8.484463 -185.305454)
			(xy 8.413141 -185.305454) (xy 8.342267 -185.297468) (xy 8.272732 -185.281598) (xy 8.205412 -185.258041)
			(xy 8.141153 -185.227096) (xy 8.080762 -185.18915) (xy 8.025 -185.144681) (xy 7.974567 -185.094248)
			(xy 7.930098 -185.038486) (xy 7.892152 -184.978095) (xy 7.861207 -184.913836) (xy 7.83765 -184.846516)
			(xy 7.82178 -184.776981) (xy 7.813794 -184.706107) (xy 2.582958 -184.706107) (xy 2.580962 -184.741653)
			(xy 2.569016 -184.811965) (xy 2.549274 -184.880497) (xy 2.521983 -184.946388) (xy 2.487486 -185.008809)
			(xy 2.446218 -185.066976) (xy 2.398697 -185.120157) (xy 2.345521 -185.167683) (xy 2.287358 -185.208957)
			(xy 2.22494 -185.24346) (xy 2.159052 -185.270757) (xy 2.090522 -185.290506) (xy 2.020211 -185.302459)
			(xy 1.949004 -185.306464) (xy 1.877797 -185.302473) (xy 1.807484 -185.290534) (xy 1.73895 -185.270798)
			(xy 1.673056 -185.243514) (xy 1.641602 -185.226706) (xy 1.622127 -185.217034) (xy 1.580725 -185.203755)
			(xy 1.537666 -185.197719) (xy 1.494208 -185.199101) (xy 1.45162 -185.207863) (xy 1.411145 -185.223748)
			(xy 1.373966 -185.246291) (xy 1.341168 -185.274835) (xy 1.313708 -185.308547) (xy 1.292389 -185.346442)
			(xy 1.277833 -185.387413) (xy 1.270464 -185.430264) (xy 1.27 -185.452004) (xy 1.27 -185.706105) (xy 3.31393 -185.706105)
			(xy 3.31393 -185.634783) (xy 3.321916 -185.563909) (xy 3.337786 -185.494374) (xy 3.361343 -185.427054)
			(xy 3.392288 -185.362795) (xy 3.430234 -185.302404) (xy 3.474703 -185.246642) (xy 3.525136 -185.196209)
			(xy 3.580898 -185.15174) (xy 3.641289 -185.113794) (xy 3.705548 -185.082849) (xy 3.772868 -185.059292)
			(xy 3.842403 -185.043422) (xy 3.913277 -185.035436) (xy 3.984599 -185.035436) (xy 4.055473 -185.043422)
			(xy 4.125008 -185.059292) (xy 4.192328 -185.082849) (xy 4.256587 -185.113794) (xy 4.316978 -185.15174)
			(xy 4.37274 -185.196209) (xy 4.423173 -185.246642) (xy 4.467642 -185.302404) (xy 4.505588 -185.362795)
			(xy 4.536533 -185.427054) (xy 4.56009 -185.494374) (xy 4.57596 -185.563909) (xy 4.583946 -185.634783)
			(xy 4.584446 -185.670444) (xy 4.583946 -185.706105) (xy 5.813798 -185.706105) (xy 5.813798 -185.634783)
			(xy 5.821784 -185.563909) (xy 5.837654 -185.494374) (xy 5.861211 -185.427054) (xy 5.892156 -185.362795)
			(xy 5.930102 -185.302404) (xy 5.974571 -185.246642) (xy 6.025004 -185.196209) (xy 6.080766 -185.15174)
			(xy 6.141157 -185.113794) (xy 6.205416 -185.082849) (xy 6.272736 -185.059292) (xy 6.342271 -185.043422)
			(xy 6.413145 -185.035436) (xy 6.484467 -185.035436) (xy 6.555341 -185.043422) (xy 6.624876 -185.059292)
			(xy 6.692196 -185.082849) (xy 6.756455 -185.113794) (xy 6.816846 -185.15174) (xy 6.872608 -185.196209)
			(xy 6.923041 -185.246642) (xy 6.96751 -185.302404) (xy 7.005456 -185.362795) (xy 7.036401 -185.427054)
			(xy 7.059958 -185.494374) (xy 7.075828 -185.563909) (xy 7.083814 -185.634783) (xy 7.084314 -185.670444)
			(xy 7.083814 -185.706105) (xy 7.075828 -185.776979) (xy 7.059958 -185.846514) (xy 7.036401 -185.913834)
			(xy 7.005456 -185.978093) (xy 6.96751 -186.038484) (xy 6.923041 -186.094246) (xy 6.872608 -186.144679)
			(xy 6.816846 -186.189148) (xy 6.756455 -186.227094) (xy 6.692196 -186.258039) (xy 6.624876 -186.281596)
			(xy 6.555341 -186.297466) (xy 6.484467 -186.305452) (xy 6.413145 -186.305452) (xy 6.342271 -186.297466)
			(xy 6.272736 -186.281596) (xy 6.205416 -186.258039) (xy 6.141157 -186.227094) (xy 6.080766 -186.189148)
			(xy 6.025004 -186.144679) (xy 5.974571 -186.094246) (xy 5.930102 -186.038484) (xy 5.892156 -185.978093)
			(xy 5.861211 -185.913834) (xy 5.837654 -185.846514) (xy 5.821784 -185.776979) (xy 5.813798 -185.706105)
			(xy 4.583946 -185.706105) (xy 4.57596 -185.776979) (xy 4.56009 -185.846514) (xy 4.536533 -185.913834)
			(xy 4.505588 -185.978093) (xy 4.467642 -186.038484) (xy 4.423173 -186.094246) (xy 4.37274 -186.144679)
			(xy 4.316978 -186.189148) (xy 4.256587 -186.227094) (xy 4.192328 -186.258039) (xy 4.125008 -186.281596)
			(xy 4.055473 -186.297466) (xy 3.984599 -186.305452) (xy 3.913277 -186.305452) (xy 3.842403 -186.297466)
			(xy 3.772868 -186.281596) (xy 3.705548 -186.258039) (xy 3.641289 -186.227094) (xy 3.580898 -186.189148)
			(xy 3.525136 -186.144679) (xy 3.474703 -186.094246) (xy 3.430234 -186.038484) (xy 3.392288 -185.978093)
			(xy 3.361343 -185.913834) (xy 3.337786 -185.846514) (xy 3.321916 -185.776979) (xy 3.31393 -185.706105)
			(xy 1.27 -185.706105) (xy 1.27 -185.888884) (xy 1.27042 -185.91063) (xy 1.277776 -185.953494) (xy 1.292325 -185.994479)
			(xy 1.313643 -186.032387) (xy 1.341105 -186.06611) (xy 1.373911 -186.094663) (xy 1.4111 -186.117211)
			(xy 1.451586 -186.133095) (xy 1.494186 -186.141852) (xy 1.537656 -186.143224) (xy 1.580723 -186.137173)
			(xy 1.622131 -186.123874) (xy 1.641602 -186.114182) (xy 1.673056 -186.097375) (xy 1.738949 -186.07009)
			(xy 1.807483 -186.050355) (xy 1.877796 -186.038416) (xy 1.949003 -186.034424) (xy 2.020209 -186.03843)
			(xy 2.090519 -186.050382) (xy 2.159049 -186.070132) (xy 2.224937 -186.097429) (xy 2.287355 -186.131931)
			(xy 2.345517 -186.173205) (xy 2.398693 -186.220731) (xy 2.446214 -186.273911) (xy 2.487481 -186.332078)
			(xy 2.521978 -186.394499) (xy 2.549269 -186.460389) (xy 2.569011 -186.528921) (xy 2.580957 -186.599232)
			(xy 2.584956 -186.670439) (xy 2.582953 -186.706103) (xy 7.813794 -186.706103) (xy 7.813794 -186.634781)
			(xy 7.82178 -186.563907) (xy 7.83765 -186.494372) (xy 7.861207 -186.427052) (xy 7.892152 -186.362793)
			(xy 7.930098 -186.302402) (xy 7.974567 -186.24664) (xy 8.025 -186.196207) (xy 8.080762 -186.151738)
			(xy 8.141153 -186.113792) (xy 8.205412 -186.082847) (xy 8.272732 -186.05929) (xy 8.342267 -186.04342)
			(xy 8.413141 -186.035434) (xy 8.484463 -186.035434) (xy 8.555337 -186.04342) (xy 8.624872 -186.05929)
			(xy 8.692192 -186.082847) (xy 8.756451 -186.113792) (xy 8.816842 -186.151738) (xy 8.872604 -186.196207)
			(xy 8.923037 -186.24664) (xy 8.967506 -186.302402) (xy 9.005452 -186.362793) (xy 9.036397 -186.427052)
			(xy 9.059954 -186.494372) (xy 9.075824 -186.563907) (xy 9.08381 -186.634781) (xy 9.08431 -186.670442)
			(xy 9.08381 -186.706103) (xy 9.075824 -186.776977) (xy 9.059954 -186.846512) (xy 9.036397 -186.913832)
			(xy 9.005452 -186.978091) (xy 8.967506 -187.038482) (xy 8.923037 -187.094244) (xy 8.872604 -187.144677)
			(xy 8.816842 -187.189146) (xy 8.756451 -187.227092) (xy 8.692192 -187.258037) (xy 8.624872 -187.281594)
			(xy 8.555337 -187.297464) (xy 8.484463 -187.30545) (xy 8.413141 -187.30545) (xy 8.342267 -187.297464)
			(xy 8.272732 -187.281594) (xy 8.205412 -187.258037) (xy 8.141153 -187.227092) (xy 8.080762 -187.189146)
			(xy 8.025 -187.144677) (xy 7.974567 -187.094244) (xy 7.930098 -187.038482) (xy 7.892152 -186.978091)
			(xy 7.861207 -186.913832) (xy 7.83765 -186.846512) (xy 7.82178 -186.776977) (xy 7.813794 -186.706103)
			(xy 2.582953 -186.706103) (xy 2.580957 -186.741646) (xy 2.569012 -186.811957) (xy 2.549269 -186.880489)
			(xy 2.521979 -186.94638) (xy 2.487483 -187.008801) (xy 2.446215 -187.066967) (xy 2.398694 -187.120148)
			(xy 2.345519 -187.167674) (xy 2.287356 -187.208948) (xy 2.224939 -187.24345) (xy 2.159051 -187.270748)
			(xy 2.090521 -187.290497) (xy 2.020211 -187.30245) (xy 1.949005 -187.306456) (xy 1.877798 -187.302464)
			(xy 1.807485 -187.290526) (xy 1.738951 -187.27079) (xy 1.673058 -187.243506) (xy 1.641602 -187.226702)
			(xy 1.622127 -187.21703) (xy 1.580724 -187.203751) (xy 1.537665 -187.197715) (xy 1.494207 -187.199098)
			(xy 1.451619 -187.20786) (xy 1.411144 -187.223744) (xy 1.373965 -187.246287) (xy 1.341166 -187.274832)
			(xy 1.313706 -187.308543) (xy 1.292387 -187.346438) (xy 1.27783 -187.387409) (xy 1.270461 -187.43026)
			(xy 1.27 -187.452) (xy 1.27 -187.706101) (xy 3.31393 -187.706101) (xy 3.31393 -187.634779) (xy 3.321916 -187.563905)
			(xy 3.337786 -187.49437) (xy 3.361343 -187.42705) (xy 3.392288 -187.362791) (xy 3.430234 -187.3024)
			(xy 3.474703 -187.246638) (xy 3.525136 -187.196205) (xy 3.580898 -187.151736) (xy 3.641289 -187.11379)
			(xy 3.705548 -187.082845) (xy 3.772868 -187.059288) (xy 3.842403 -187.043418) (xy 3.913277 -187.035432)
			(xy 3.984599 -187.035432) (xy 4.055473 -187.043418) (xy 4.125008 -187.059288) (xy 4.192328 -187.082845)
			(xy 4.256587 -187.11379) (xy 4.316978 -187.151736) (xy 4.37274 -187.196205) (xy 4.423173 -187.246638)
			(xy 4.467642 -187.3024) (xy 4.505588 -187.362791) (xy 4.536533 -187.42705) (xy 4.56009 -187.49437)
			(xy 4.57596 -187.563905) (xy 4.583946 -187.634779) (xy 4.584446 -187.67044) (xy 4.583946 -187.706101)
			(xy 5.813798 -187.706101) (xy 5.813798 -187.634779) (xy 5.821784 -187.563905) (xy 5.837654 -187.49437)
			(xy 5.861211 -187.42705) (xy 5.892156 -187.362791) (xy 5.930102 -187.3024) (xy 5.974571 -187.246638)
			(xy 6.025004 -187.196205) (xy 6.080766 -187.151736) (xy 6.141157 -187.11379) (xy 6.205416 -187.082845)
			(xy 6.272736 -187.059288) (xy 6.342271 -187.043418) (xy 6.413145 -187.035432) (xy 6.484467 -187.035432)
			(xy 6.555341 -187.043418) (xy 6.624876 -187.059288) (xy 6.692196 -187.082845) (xy 6.756455 -187.11379)
			(xy 6.816846 -187.151736) (xy 6.872608 -187.196205) (xy 6.923041 -187.246638) (xy 6.96751 -187.3024)
			(xy 7.005456 -187.362791) (xy 7.036401 -187.42705) (xy 7.059958 -187.49437) (xy 7.075828 -187.563905)
			(xy 7.083814 -187.634779) (xy 7.084314 -187.67044) (xy 7.083814 -187.706101) (xy 7.075828 -187.776975)
			(xy 7.059958 -187.84651) (xy 7.036401 -187.91383) (xy 7.005456 -187.978089) (xy 6.96751 -188.03848)
			(xy 6.923041 -188.094242) (xy 6.872608 -188.144675) (xy 6.816846 -188.189144) (xy 6.756455 -188.22709)
			(xy 6.692196 -188.258035) (xy 6.624876 -188.281592) (xy 6.555341 -188.297462) (xy 6.484467 -188.305448)
			(xy 6.413145 -188.305448) (xy 6.342271 -188.297462) (xy 6.272736 -188.281592) (xy 6.205416 -188.258035)
			(xy 6.141157 -188.22709) (xy 6.080766 -188.189144) (xy 6.025004 -188.144675) (xy 5.974571 -188.094242)
			(xy 5.930102 -188.03848) (xy 5.892156 -187.978089) (xy 5.861211 -187.91383) (xy 5.837654 -187.84651)
			(xy 5.821784 -187.776975) (xy 5.813798 -187.706101) (xy 4.583946 -187.706101) (xy 4.57596 -187.776975)
			(xy 4.56009 -187.84651) (xy 4.536533 -187.91383) (xy 4.505588 -187.978089) (xy 4.467642 -188.03848)
			(xy 4.423173 -188.094242) (xy 4.37274 -188.144675) (xy 4.316978 -188.189144) (xy 4.256587 -188.22709)
			(xy 4.192328 -188.258035) (xy 4.125008 -188.281592) (xy 4.055473 -188.297462) (xy 3.984599 -188.305448)
			(xy 3.913277 -188.305448) (xy 3.842403 -188.297462) (xy 3.772868 -188.281592) (xy 3.705548 -188.258035)
			(xy 3.641289 -188.22709) (xy 3.580898 -188.189144) (xy 3.525136 -188.144675) (xy 3.474703 -188.094242)
			(xy 3.430234 -188.03848) (xy 3.392288 -187.978089) (xy 3.361343 -187.91383) (xy 3.337786 -187.84651)
			(xy 3.321916 -187.776975) (xy 3.31393 -187.706101) (xy 1.27 -187.706101) (xy 1.27 -187.88888) (xy 1.27042 -187.910626)
			(xy 1.277777 -187.953489) (xy 1.292327 -187.994473) (xy 1.313645 -188.03238) (xy 1.341107 -188.066102)
			(xy 1.373912 -188.094654) (xy 1.411101 -188.117202) (xy 1.451587 -188.133085) (xy 1.494186 -188.141842)
			(xy 1.537655 -188.143214) (xy 1.580722 -188.137163) (xy 1.622129 -188.123865) (xy 1.641602 -188.114178)
			(xy 1.673056 -188.097371) (xy 1.73895 -188.070086) (xy 1.807484 -188.050351) (xy 1.877797 -188.038412)
			(xy 1.949005 -188.034421) (xy 2.020211 -188.038427) (xy 2.090522 -188.050379) (xy 2.159052 -188.070129)
			(xy 2.22494 -188.097427) (xy 2.287358 -188.131929) (xy 2.345521 -188.173203) (xy 2.398697 -188.22073)
			(xy 2.446217 -188.273911) (xy 2.487485 -188.332077) (xy 2.521982 -188.394499) (xy 2.549273 -188.46039)
			(xy 2.569015 -188.528922) (xy 2.580961 -188.599234) (xy 2.584959 -188.670441) (xy 2.58096 -188.741648)
			(xy 2.569015 -188.81196) (xy 2.549272 -188.880492) (xy 2.521981 -188.946383) (xy 2.487484 -189.008804)
			(xy 2.446216 -189.066971) (xy 2.398695 -189.120152) (xy 2.345519 -189.167678) (xy 2.287356 -189.208952)
			(xy 2.224938 -189.243454) (xy 2.15905 -189.270752) (xy 2.09052 -189.290501) (xy 2.020209 -189.302454)
			(xy 1.949003 -189.306459) (xy 1.877795 -189.302468) (xy 1.807482 -189.290529) (xy 1.738948 -189.270793)
			(xy 1.673054 -189.243509) (xy 1.641602 -189.226698) (xy 1.622127 -189.217026) (xy 1.580724 -189.203747)
			(xy 1.537665 -189.197711) (xy 1.494207 -189.199094) (xy 1.451618 -189.207856) (xy 1.411143 -189.223741)
			(xy 1.373964 -189.246284) (xy 1.341165 -189.274828) (xy 1.313705 -189.308539) (xy 1.292385 -189.346434)
			(xy 1.277827 -189.387404) (xy 1.270458 -189.430256) (xy 1.27 -189.451996) (xy 1.27 -189.706097) (xy 3.31393 -189.706097)
			(xy 3.31393 -189.634775) (xy 3.321916 -189.563901) (xy 3.337786 -189.494366) (xy 3.361343 -189.427046)
			(xy 3.392288 -189.362787) (xy 3.430234 -189.302396) (xy 3.474703 -189.246634) (xy 3.525136 -189.196201)
			(xy 3.580898 -189.151732) (xy 3.641289 -189.113786) (xy 3.705548 -189.082841) (xy 3.772868 -189.059284)
			(xy 3.842403 -189.043414) (xy 3.913277 -189.035428) (xy 3.984599 -189.035428) (xy 4.055473 -189.043414)
			(xy 4.125008 -189.059284) (xy 4.192328 -189.082841) (xy 4.256587 -189.113786) (xy 4.316978 -189.151732)
			(xy 4.37274 -189.196201) (xy 4.423173 -189.246634) (xy 4.467642 -189.302396) (xy 4.505588 -189.362787)
			(xy 4.536533 -189.427046) (xy 4.56009 -189.494366) (xy 4.57596 -189.563901) (xy 4.583946 -189.634775)
			(xy 4.584446 -189.670436) (xy 4.583946 -189.706097) (xy 4.57596 -189.776971) (xy 4.56009 -189.846506)
			(xy 4.536533 -189.913826) (xy 4.505588 -189.978085) (xy 4.467642 -190.038476) (xy 4.423173 -190.094238)
			(xy 4.37274 -190.144671) (xy 4.316978 -190.18914) (xy 4.256587 -190.227086) (xy 4.192328 -190.258031)
			(xy 4.125008 -190.281588) (xy 4.055473 -190.297458) (xy 3.984599 -190.305444) (xy 3.913277 -190.305444)
			(xy 3.842403 -190.297458) (xy 3.772868 -190.281588) (xy 3.705548 -190.258031) (xy 3.641289 -190.227086)
			(xy 3.580898 -190.18914) (xy 3.525136 -190.144671) (xy 3.474703 -190.094238) (xy 3.430234 -190.038476)
			(xy 3.392288 -189.978085) (xy 3.361343 -189.913826) (xy 3.337786 -189.846506) (xy 3.321916 -189.776971)
			(xy 3.31393 -189.706097) (xy 1.27 -189.706097) (xy 1.27 -189.888876) (xy 1.27042 -189.910622) (xy 1.277776 -189.953486)
			(xy 1.292326 -189.99447) (xy 1.313643 -190.032378) (xy 1.341106 -190.066101) (xy 1.373911 -190.094653)
			(xy 1.4111 -190.117201) (xy 1.451586 -190.133085) (xy 1.494186 -190.141842) (xy 1.537655 -190.143214)
			(xy 1.580723 -190.137163) (xy 1.62213 -190.123864) (xy 1.641602 -190.114174) (xy 1.673056 -190.097366)
			(xy 1.73895 -190.070082) (xy 1.807484 -190.050346) (xy 1.877797 -190.038407) (xy 1.949004 -190.034416)
			(xy 2.020211 -190.038421) (xy 2.090522 -190.050374) (xy 2.159052 -190.070123) (xy 2.22494 -190.09742)
			(xy 2.287358 -190.131923) (xy 2.345521 -190.173197) (xy 2.398697 -190.220723) (xy 2.446218 -190.273904)
			(xy 2.487486 -190.332071) (xy 2.521983 -190.394492) (xy 2.549274 -190.460383) (xy 2.569016 -190.528915)
			(xy 2.580962 -190.599227) (xy 2.58496 -190.670434) (xy 2.580962 -190.741641) (xy 2.569016 -190.811953)
			(xy 2.549274 -190.880485) (xy 2.521983 -190.946376) (xy 2.487486 -191.008797) (xy 2.446218 -191.066964)
			(xy 2.398697 -191.120145) (xy 2.345521 -191.167671) (xy 2.287358 -191.208945) (xy 2.22494 -191.243448)
			(xy 2.159052 -191.270745) (xy 2.090522 -191.290494) (xy 2.020211 -191.302447) (xy 1.949004 -191.306452)
			(xy 1.877797 -191.302461) (xy 1.807484 -191.290522) (xy 1.73895 -191.270786) (xy 1.673056 -191.243502)
			(xy 1.641602 -191.226694) (xy 1.622127 -191.217022) (xy 1.580724 -191.203744) (xy 1.537664 -191.197708)
			(xy 1.494206 -191.199091) (xy 1.451618 -191.207853) (xy 1.411143 -191.223737) (xy 1.373963 -191.24628)
			(xy 1.341164 -191.274824) (xy 1.313703 -191.308535) (xy 1.292383 -191.34643) (xy 1.277825 -191.3874)
			(xy 1.270455 -191.430252) (xy 1.27 -191.451992) (xy 1.27 -191.888872) (xy 1.27042 -191.910617) (xy 1.277777 -191.95348)
			(xy 1.292327 -191.994464) (xy 1.313645 -192.032371) (xy 1.341108 -192.066093) (xy 1.373913 -192.094645)
			(xy 1.411101 -192.117192) (xy 1.451587 -192.133076) (xy 1.494186 -192.141832) (xy 1.537654 -192.143204)
			(xy 1.580721 -192.137153) (xy 1.622128 -192.123855) (xy 1.641602 -192.11417) (xy 1.647444 -192.110868)
			(xy 1.677879 -192.094986) (xy 1.741471 -192.069118) (xy 1.807483 -192.050262) (xy 1.875144 -192.038635)
			(xy 1.943664 -192.034376) (xy 2.012244 -192.037532) (xy 2.080083 -192.048067) (xy 2.14639 -192.065859)
			(xy 2.178558 -192.077848) (xy 2.211379 -192.091072) (xy 2.274124 -192.123789) (xy 2.332845 -192.163275)
			(xy 2.386815 -192.209041) (xy 2.435366 -192.26052) (xy 2.477897 -192.317075) (xy 2.513881 -192.378005)
			(xy 2.528824 -192.41008) (xy 2.53882 -192.431089) (xy 2.565268 -192.469361) (xy 2.598239 -192.50218)
			(xy 2.636631 -192.528452) (xy 2.679164 -192.547299) (xy 2.724415 -192.558091) (xy 2.770875 -192.560468)
			(xy 2.794 -192.557908) (xy 3.221228 -192.13068) (xy 3.263138 -192.13068) (xy 3.279782 -192.130132)
			(xy 3.311934 -192.121508) (xy 3.340758 -192.104856) (xy 3.364292 -192.081312) (xy 3.38093 -192.05248)
			(xy 3.38954 -192.020324) (xy 3.390138 -192.00368) (xy 3.390138 -191.97447) (xy 3.377438 -191.948054)
			(xy 3.363086 -191.917532) (xy 3.340181 -191.85409) (xy 3.324135 -191.788576) (xy 3.31513 -191.721729)
			(xy 3.313266 -191.654305) (xy 3.315462 -191.620648) (xy 3.317441 -191.597719) (xy 3.324306 -191.552208)
			(xy 3.329178 -191.529716) (xy 3.33121 -191.52108) (xy 3.337476 -191.49616) (xy 3.3535 -191.447333)
			(xy 3.363214 -191.423544) (xy 3.377518 -191.390887) (xy 3.412385 -191.328697) (xy 3.453994 -191.2708)
			(xy 3.501821 -191.217924) (xy 3.555265 -191.170732) (xy 3.613655 -191.129819) (xy 3.676258 -191.095698)
			(xy 3.742286 -191.068797) (xy 3.810909 -191.049456) (xy 3.881267 -191.037916) (xy 3.952474 -191.034324)
			(xy 4.023635 -191.038723) (xy 4.093857 -191.051059) (xy 4.162257 -191.071177) (xy 4.227976 -191.098824)
			(xy 4.290188 -191.133652) (xy 4.348111 -191.175225) (xy 4.374896 -191.198754) (xy 4.391327 -191.211924)
			(xy 4.427636 -191.233246) (xy 4.466958 -191.248305) (xy 4.508221 -191.256689) (xy 4.550302 -191.258169)
			(xy 4.571238 -191.255904) (xy 5.75437 -190.072772) (xy 5.790438 -190.072772) (xy 5.864606 -189.998604)
			(xy 5.864606 -189.921642) (xy 5.85597 -189.899544) (xy 5.842 -189.859158) (xy 5.840476 -189.854332)
			(xy 5.830645 -189.82016) (xy 5.817763 -189.750228) (xy 5.812768 -189.679295) (xy 5.815721 -189.608248)
			(xy 5.826587 -189.537974) (xy 5.845229 -189.469353) (xy 5.871415 -189.403241) (xy 5.904817 -189.340465)
			(xy 5.945017 -189.281811) (xy 5.991513 -189.22801) (xy 6.043724 -189.179735) (xy 6.100998 -189.13759)
			(xy 6.162618 -189.102102) (xy 6.227814 -189.073714) (xy 6.295772 -189.05278) (xy 6.365641 -189.039564)
			(xy 6.43655 -189.034229) (xy 6.50761 -189.036842) (xy 6.577935 -189.047371) (xy 6.646645 -189.065685)
			(xy 6.712881 -189.091554) (xy 6.775816 -189.124654) (xy 6.834663 -189.164573) (xy 6.888686 -189.210811)
			(xy 6.93721 -189.262791) (xy 6.979628 -189.319862) (xy 7.015411 -189.381311) (xy 7.030212 -189.413642)
			(xy 7.040905 -189.433078) (xy 7.067947 -189.468236) (xy 7.10068 -189.498169) (xy 7.138111 -189.521967)
			(xy 7.179104 -189.538909) (xy 7.222414 -189.548481) (xy 7.266728 -189.550392) (xy 7.288784 -189.548008)
			(xy 7.676134 -189.160404) (xy 7.777988 -189.160404) (xy 7.794644 -189.159911) (xy 7.826822 -189.151292)
			(xy 7.855672 -189.134638) (xy 7.879228 -189.111084) (xy 7.895886 -189.082236) (xy 7.904509 -189.05006)
			(xy 7.904988 -189.033404) (xy 7.904988 -189.001146) (xy 7.889748 -188.972952) (xy 7.872577 -188.940136)
			(xy 7.845136 -188.871341) (xy 7.825886 -188.799821) (xy 7.815088 -188.726546) (xy 7.81289 -188.652513)
			(xy 7.81558 -188.615574) (xy 7.819176 -188.579804) (xy 7.83342 -188.509337) (xy 7.855525 -188.440926)
			(xy 7.885208 -188.375447) (xy 7.92209 -188.313735) (xy 7.965699 -188.25658) (xy 8.01548 -188.20471)
			(xy 8.070796 -188.158788) (xy 8.13094 -188.119402) (xy 8.195144 -188.087054) (xy 8.262589 -188.062158)
			(xy 8.332412 -188.04503) (xy 8.403722 -188.035891) (xy 8.439658 -188.03493) (xy 8.475703 -188.034914)
			(xy 8.547434 -188.042037) (xy 8.617899 -188.057227) (xy 8.686193 -188.080291) (xy 8.751441 -188.110931)
			(xy 8.812803 -188.148755) (xy 8.869494 -188.193277) (xy 8.920785 -188.243926) (xy 8.966018 -188.300051)
			(xy 9.004612 -188.360933) (xy 9.036072 -188.425789) (xy 9.059994 -188.493787) (xy 9.076071 -188.564055)
			(xy 9.0805 -188.599826) (xy 9.0805 -188.60008) (xy 9.080754 -188.603128) (xy 9.083314 -188.618645)
			(xy 9.095003 -188.64783) (xy 9.113479 -188.673267) (xy 9.137619 -188.693409) (xy 9.165953 -188.70703)
			(xy 9.19676 -188.713304) (xy 9.228165 -188.711847) (xy 9.258259 -188.702748) (xy 9.285211 -188.686562)
			(xy 9.296654 -188.675772) (xy 9.353296 -188.61913) (xy 9.353296 -177.893472) (xy 13.927328 -173.31944)
			(xy 13.929831 -173.296647) (xy 13.927564 -173.250854) (xy 13.917128 -173.206208) (xy 13.898862 -173.164155)
			(xy 13.873356 -173.126055) (xy 13.841436 -173.093143) (xy 13.804135 -173.066482) (xy 13.76266 -173.046937)
			(xy 13.740638 -173.040548) (xy 13.71409 -173.032986) (xy 13.663344 -173.011267) (xy 13.616256 -172.982464)
			(xy 13.57381 -172.947176) (xy 13.53689 -172.906142) (xy 13.506267 -172.860216) (xy 13.482581 -172.810358)
			(xy 13.466325 -172.757607) (xy 13.457839 -172.703064) (xy 13.457299 -172.647868) (xy 13.464717 -172.59317)
			(xy 13.479938 -172.540112) (xy 13.502645 -172.4898) (xy 13.532364 -172.443284) (xy 13.568475 -172.401536)
			(xy 13.610223 -172.365425) (xy 13.656738 -172.335706) (xy 13.70705 -172.312999) (xy 13.760109 -172.297777)
			(xy 13.814807 -172.290359) (xy 13.870003 -172.290898) (xy 13.924546 -172.299385) (xy 13.977296 -172.31564)
			(xy 14.027155 -172.339327) (xy 14.073081 -172.369949) (xy 14.114115 -172.406869) (xy 14.149403 -172.449315)
			(xy 14.178207 -172.496403) (xy 14.199926 -172.547149) (xy 14.20749 -172.573696) (xy 14.213825 -172.595747)
			(xy 14.233319 -172.637273) (xy 14.259957 -172.67462) (xy 14.292872 -172.706573) (xy 14.330994 -172.732092)
			(xy 14.37308 -172.750346) (xy 14.417761 -172.760741) (xy 14.463582 -172.762938) (xy 14.486382 -172.760386)
			(xy 18.926556 -168.320212) (xy 18.926556 -132.235448) (xy 8.225536 -121.534428) (xy 8.225536 -114.51717)
			(xy 11.624564 -111.117888) (xy 11.624564 -107.523534) (xy 10.400284 -106.299254) (xy 10.400284 -90.894916)
			(xy 13.523976 -87.771224) (xy 13.523976 -76.271628) (xy 10.443972 -73.191624) (xy 10.443972 -60.931298)
			(xy 17.596866 -53.778658) (xy 17.608215 -53.766509) (xy 17.624806 -53.737713) (xy 17.633405 -53.705612)
			(xy 17.63395 -53.688996) (xy 17.63395 -42.129202) (xy 8.788908 -33.28416) (xy 8.788908 -26.76906)
			(xy 8.774624 -26.751313) (xy 8.74087 -26.720727) (xy 8.702206 -26.696646) (xy 8.659868 -26.679841)
			(xy 8.615214 -26.670851) (xy 8.569672 -26.669963) (xy 8.524701 -26.677206) (xy 8.481741 -26.692347)
			(xy 8.442167 -26.714902) (xy 8.424418 -26.729182) (xy 8.388372 -26.758625) (xy 8.312005 -26.81184)
			(xy 8.231295 -26.858204) (xy 8.146855 -26.897365) (xy 8.059326 -26.929026) (xy 7.969373 -26.952945)
			(xy 7.877679 -26.968942) (xy 7.78494 -26.976895) (xy 7.691861 -26.976744) (xy 7.599149 -26.968488)
			(xy 7.507507 -26.952193) (xy 7.417633 -26.92798) (xy 7.330207 -26.896034) (xy 7.245895 -26.856598)
			(xy 7.165337 -26.809971) (xy 7.089144 -26.756507) (xy 7.017896 -26.696612) (xy 6.952132 -26.630742)
			(xy 6.892354 -26.559396) (xy 6.839014 -26.483116) (xy 6.792518 -26.402482) (xy 6.75322 -26.318106)
			(xy 6.721416 -26.230629) (xy 6.69735 -26.140714) (xy 6.681203 -26.049047) (xy 6.673099 -25.956321)
			(xy 6.673099 -25.863242) (xy 6.681203 -25.770516) (xy 6.697349 -25.678848) (xy 6.721415 -25.588934)
			(xy 6.753219 -25.501457) (xy 6.792517 -25.41708) (xy 6.839013 -25.336446) (xy 6.892352 -25.260166)
			(xy 6.952131 -25.18882) (xy 7.017894 -25.122949) (xy 7.089142 -25.063055) (xy 7.165335 -25.009591)
			(xy 7.245893 -24.962963) (xy 7.330205 -24.923527) (xy 7.41763 -24.891581) (xy 7.507505 -24.867368)
			(xy 7.599146 -24.851072) (xy 7.691859 -24.842817) (xy 7.784938 -24.842665) (xy 7.877676 -24.850617)
			(xy 7.969371 -24.866614) (xy 8.059324 -24.890533) (xy 8.146853 -24.922194) (xy 8.231293 -24.961355)
			(xy 8.312003 -25.007719) (xy 8.38837 -25.060934) (xy 8.424418 -25.090374) (xy 8.442209 -25.104588)
			(xy 8.481782 -25.127108) (xy 8.524732 -25.142224) (xy 8.569687 -25.149453) (xy 8.61521 -25.148565)
			(xy 8.659849 -25.139588) (xy 8.702177 -25.122809) (xy 8.740842 -25.098764) (xy 8.77461 -25.068219)
			(xy 8.788908 -25.050496) (xy 8.788908 -21.268944) (xy 8.999728 -21.058124) (xy 9.011192 -21.045993)
			(xy 9.027908 -21.017115) (xy 9.036563 -20.984889) (xy 9.036565 -20.951522) (xy 9.027913 -20.919296)
			(xy 9.011199 -20.890416) (xy 8.999728 -20.878292) (xy 8.966708 -20.845272) (xy 8.87349 -20.837906)
			(xy 8.835644 -20.865338) (xy 8.78204 -20.903471) (xy 8.670783 -20.973689) (xy 8.555317 -21.036748)
			(xy 8.436101 -21.092394) (xy 8.313612 -21.140408) (xy 8.188338 -21.180596) (xy 8.060777 -21.212799)
			(xy 7.931438 -21.23689) (xy 7.800837 -21.252771) (xy 7.669494 -21.260379) (xy 7.537933 -21.259684)
			(xy 7.406678 -21.25069) (xy 7.276251 -21.233431) (xy 7.147174 -21.207976) (xy 7.019961 -21.174428)
			(xy 6.895117 -21.132919) (xy 6.773142 -21.083615) (xy 6.654521 -21.026712) (xy 6.539727 -20.962439)
			(xy 6.429217 -20.891049) (xy 6.323432 -20.812829) (xy 6.272784 -20.77085) (xy 6.224579 -20.729641)
			(xy 6.132699 -20.642204) (xy 6.046309 -20.549339) (xy 5.965731 -20.451389) (xy 5.891263 -20.348718)
			(xy 5.82318 -20.241705) (xy 5.761735 -20.130748) (xy 5.707156 -20.016257) (xy 5.659645 -19.898657)
			(xy 5.619378 -19.778384) (xy 5.602478 -19.717258) (xy 5.586295 -19.65511) (xy 5.560697 -19.52925)
			(xy 5.542899 -19.402052) (xy 5.532972 -19.273999) (xy 5.530951 -19.145578) (xy 5.536845 -19.017276)
			(xy 5.550632 -18.889581) (xy 5.572258 -18.762978) (xy 5.601643 -18.637947) (xy 5.638673 -18.514964)
			(xy 5.68321 -18.394496) (xy 5.735082 -18.277) (xy 5.794094 -18.162923) (xy 5.860022 -18.052697) (xy 5.932614 -17.946742)
			(xy 6.011595 -17.84546) (xy 6.096665 -17.749236) (xy 6.187502 -17.658435) (xy 6.283759 -17.573402)
			(xy 6.385072 -17.49446) (xy 6.491055 -17.421909) (xy 6.601306 -17.356025) (xy 6.715407 -17.297057)
			(xy 6.832923 -17.24523) (xy 6.953408 -17.200741) (xy 7.076406 -17.163758) (xy 7.201448 -17.134422)
			(xy 7.328059 -17.112845) (xy 7.45576 -17.099108) (xy 7.584064 -17.093264) (xy 7.712484 -17.095335)
			(xy 7.840533 -17.105312) (xy 7.967724 -17.123159) (xy 8.093574 -17.148807) (xy 8.217605 -17.182158)
			(xy 8.339346 -17.223087) (xy 8.458335 -17.271438) (xy 8.574119 -17.327026) (xy 8.686259 -17.389642)
			(xy 8.794329 -17.459046) (xy 8.897918 -17.534976) (xy 8.996633 -17.617143) (xy 9.090099 -17.705235)
			(xy 9.177961 -17.798917) (xy 9.259885 -17.897834) (xy 9.33556 -18.00161) (xy 9.404699 -18.10985)
			(xy 9.467038 -18.222144) (xy 9.522342 -18.338064) (xy 9.5704 -18.457171) (xy 9.611029 -18.579013)
			(xy 9.644076 -18.703126) (xy 9.669414 -18.829038) (xy 9.686948 -18.956273) (xy 9.696611 -19.084346)
			(xy 9.697974 -19.148552) (xy 9.698748 -19.170526) (xy 9.706921 -19.213725) (xy 9.72241 -19.254872)
			(xy 9.74475 -19.292738) (xy 9.773276 -19.326193) (xy 9.807135 -19.354238) (xy 9.845316 -19.376036)
			(xy 9.88668 -19.390935) (xy 9.929991 -19.398491) (xy 9.951974 -19.398996) (xy 10.243312 -19.398996)
			(xy 10.854436 -18.787872) (xy 10.854436 -13.797534) (xy 13.512546 -11.139678) (xy 13.51491 -11.118784)
			(xy 13.513513 -11.076761) (xy 13.505216 -11.035541) (xy 13.490247 -10.996249) (xy 13.469013 -10.959958)
			(xy 13.442094 -10.927658) (xy 13.42644 -10.913618) (xy 13.406846 -10.896498) (xy 13.369609 -10.860147)
			(xy 13.352018 -10.840974) (xy 13.320378 -10.804971) (xy 13.26474 -10.726922) (xy 13.24102 -10.685272)
			(xy 13.222139 -10.649991) (xy 13.190512 -10.576481) (xy 13.166143 -10.500257) (xy 13.149261 -10.422033)
			(xy 13.140023 -10.342543) (xy 13.138517 -10.262533) (xy 13.144756 -10.182751) (xy 13.158682 -10.103947)
			(xy 13.180165 -10.02686) (xy 13.209002 -9.952211) (xy 13.244924 -9.880702) (xy 13.287594 -9.813002)
			(xy 13.336611 -9.749746) (xy 13.391517 -9.691528) (xy 13.451795 -9.638893) (xy 13.516882 -9.592334)
			(xy 13.586167 -9.552289) (xy 13.659 -9.519133) (xy 13.734698 -9.493176) (xy 13.812552 -9.474662)
			(xy 13.891831 -9.463765) (xy 13.971793 -9.460586) (xy 14.051687 -9.465156) (xy 14.130765 -9.477432)
			(xy 14.169644 -9.4869) (xy 14.209573 -9.49765) (xy 14.28723 -9.526076) (xy 14.361657 -9.562121) (xy 14.432108 -9.605425)
			(xy 14.497879 -9.655553) (xy 14.55831 -9.712004) (xy 14.612796 -9.774211) (xy 14.660793 -9.841553)
			(xy 14.701818 -9.913355) (xy 14.735462 -9.988898) (xy 14.761386 -10.067425) (xy 14.770862 -10.107676)
			(xy 14.780514 -10.15111) (xy 14.85011 -10.20699) (xy 14.895068 -10.20699) (xy 14.911725 -10.206499)
			(xy 14.943905 -10.197883) (xy 14.972758 -10.18123) (xy 14.996317 -10.157676) (xy 15.012975 -10.128826)
			(xy 15.021596 -10.096647) (xy 15.022068 -10.07999) (xy 15.022068 -10.050272) (xy 15.388082 -9.684004)
			(xy 15.610078 -9.462008) (xy 15.682722 -9.388602) (xy 15.692526 -9.378155) (xy 15.707614 -9.353806)
			(xy 15.71689 -9.326705) (xy 15.719886 -9.298217) (xy 15.718536 -9.283954) (xy 15.715742 -9.26211)
			(xy 15.712694 -9.252204) (xy 15.70155 -9.21296) (xy 15.686139 -9.132843) (xy 15.678701 -9.051596)
			(xy 15.67931 -8.970013) (xy 15.687958 -8.888887) (xy 15.704562 -8.809008) (xy 15.728959 -8.731156)
			(xy 15.760913 -8.656088) (xy 15.800112 -8.584536) (xy 15.846174 -8.517197) (xy 15.89865 -8.454726)
			(xy 15.957029 -8.397734) (xy 16.020742 -8.346774) (xy 16.089169 -8.302344) (xy 16.161642 -8.264876)
			(xy 16.237456 -8.234735) (xy 16.315873 -8.212215) (xy 16.396127 -8.197536) (xy 16.477438 -8.19084)
			(xy 16.559012 -8.192192) (xy 16.640056 -8.20158) (xy 16.71978 -8.218912) (xy 16.797407 -8.244019)
			(xy 16.87218 -8.276656) (xy 16.908018 -8.296148) (xy 16.943819 -8.316749) (xy 16.983756 -8.344662)
			(xy 24.3619 -8.344662) (xy 24.365971 -8.28904) (xy 24.378097 -8.234603) (xy 24.39802 -8.182512) (xy 24.425316 -8.133877)
			(xy 24.459402 -8.089734) (xy 24.499551 -8.051025) (xy 24.544909 -8.018574) (xy 24.594509 -7.993073)
			(xy 24.647293 -7.975066) (xy 24.702136 -7.964936) (xy 24.75787 -7.962899) (xy 24.813307 -7.968999)
			(xy 24.867264 -7.983105) (xy 24.918593 -8.004917) (xy 24.966199 -8.033971) (xy 25.009067 -8.069646)
			(xy 25.046284 -8.111183) (xy 25.077057 -8.157696) (xy 25.100729 -8.208193) (xy 25.116797 -8.2616)
			(xy 25.124917 -8.316776) (xy 25.125426 -8.344662) (xy 25.124917 -8.372548) (xy 25.116797 -8.427724)
			(xy 25.100729 -8.481131) (xy 25.077057 -8.531628) (xy 25.046284 -8.578141) (xy 25.009067 -8.619678)
			(xy 24.966199 -8.655353) (xy 24.918593 -8.684407) (xy 24.867264 -8.706219) (xy 24.813307 -8.720325)
			(xy 24.75787 -8.726425) (xy 24.702136 -8.724388) (xy 24.647293 -8.714258) (xy 24.594509 -8.696251)
			(xy 24.544909 -8.67075) (xy 24.499551 -8.638299) (xy 24.459402 -8.59959) (xy 24.425316 -8.555447)
			(xy 24.39802 -8.506812) (xy 24.378097 -8.454721) (xy 24.365971 -8.400284) (xy 24.3619 -8.344662)
			(xy 16.983756 -8.344662) (xy 17.011525 -8.364071) (xy 17.07417 -8.417913) (xy 17.131128 -8.47774)
			(xy 17.181831 -8.542953) (xy 17.225771 -8.6129) (xy 17.262511 -8.686884) (xy 17.291683 -8.764166)
			(xy 17.304056 -8.810498) (xy 26.80538 -8.810498) (xy 26.809451 -8.754876) (xy 26.821577 -8.700439)
			(xy 26.8415 -8.648348) (xy 26.868796 -8.599713) (xy 26.902882 -8.55557) (xy 26.943031 -8.516861)
			(xy 26.988389 -8.48441) (xy 27.037989 -8.458909) (xy 27.090773 -8.440902) (xy 27.145616 -8.430772)
			(xy 27.20135 -8.428735) (xy 27.256787 -8.434835) (xy 27.310744 -8.448941) (xy 27.362073 -8.470753)
			(xy 27.409679 -8.499807) (xy 27.452547 -8.535482) (xy 27.489764 -8.577019) (xy 27.520537 -8.623532)
			(xy 27.544209 -8.674029) (xy 27.560277 -8.727436) (xy 27.568397 -8.782612) (xy 27.568906 -8.810498)
			(xy 27.568397 -8.838384) (xy 27.560277 -8.89356) (xy 27.544209 -8.946967) (xy 27.520537 -8.997464)
			(xy 27.489764 -9.043977) (xy 27.452547 -9.085514) (xy 27.409679 -9.121189) (xy 27.362073 -9.150243)
			(xy 27.310744 -9.172055) (xy 27.256787 -9.186161) (xy 27.20135 -9.192261) (xy 27.145616 -9.190224)
			(xy 27.090773 -9.180094) (xy 27.037989 -9.162087) (xy 26.988389 -9.136586) (xy 26.943031 -9.104135)
			(xy 26.902882 -9.065426) (xy 26.868796 -9.021283) (xy 26.8415 -8.972648) (xy 26.821577 -8.920557)
			(xy 26.809451 -8.86612) (xy 26.80538 -8.810498) (xy 17.304056 -8.810498) (xy 17.312995 -8.843973)
			(xy 17.326236 -8.925509) (xy 17.331273 -9.00796) (xy 17.328055 -9.090501) (xy 17.316614 -9.172309)
			(xy 17.297066 -9.252567) (xy 17.269605 -9.330473) (xy 17.234505 -9.405249) (xy 17.192117 -9.476148)
			(xy 17.16753 -9.509252) (xy 24.3619 -9.509252) (xy 24.365971 -9.45363) (xy 24.378097 -9.399193) (xy 24.39802 -9.347102)
			(xy 24.425316 -9.298467) (xy 24.459402 -9.254324) (xy 24.499551 -9.215615) (xy 24.544909 -9.183164)
			(xy 24.594509 -9.157663) (xy 24.647293 -9.139656) (xy 24.702136 -9.129526) (xy 24.75787 -9.127489)
			(xy 24.813307 -9.133589) (xy 24.867264 -9.147695) (xy 24.918593 -9.169507) (xy 24.966199 -9.198561)
			(xy 25.009067 -9.234236) (xy 25.046284 -9.275773) (xy 25.077057 -9.322286) (xy 25.100729 -9.372783)
			(xy 25.116797 -9.42619) (xy 25.124917 -9.481366) (xy 25.125426 -9.509252) (xy 25.124917 -9.537138)
			(xy 25.116797 -9.592314) (xy 25.100729 -9.645721) (xy 25.077057 -9.696218) (xy 25.046284 -9.742731)
			(xy 25.009067 -9.784268) (xy 24.966199 -9.819943) (xy 24.918593 -9.848997) (xy 24.867264 -9.870809)
			(xy 24.830784 -9.880346) (xy 27.07081 -9.880346) (xy 27.074881 -9.824724) (xy 27.087007 -9.770287)
			(xy 27.10693 -9.718196) (xy 27.134226 -9.669561) (xy 27.168312 -9.625418) (xy 27.208461 -9.586709)
			(xy 27.253819 -9.554258) (xy 27.303419 -9.528757) (xy 27.356203 -9.51075) (xy 27.411046 -9.50062)
			(xy 27.46678 -9.498583) (xy 27.522217 -9.504683) (xy 27.576174 -9.518789) (xy 27.627503 -9.540601)
			(xy 27.675109 -9.569655) (xy 27.717977 -9.60533) (xy 27.755194 -9.646867) (xy 27.785967 -9.69338)
			(xy 27.795391 -9.713484) (xy 29.519874 -9.713484) (xy 29.519874 -9.626584) (xy 29.527892 -9.540055)
			(xy 29.54386 -9.454635) (xy 29.567641 -9.371053) (xy 29.599033 -9.290021) (xy 29.637767 -9.212232)
			(xy 29.683514 -9.138348) (xy 29.735883 -9.069001) (xy 29.794427 -9.004781) (xy 29.858647 -8.946237)
			(xy 29.927994 -8.893868) (xy 30.001878 -8.848121) (xy 30.079667 -8.809387) (xy 30.160699 -8.777995)
			(xy 30.244281 -8.754214) (xy 30.329701 -8.738246) (xy 30.41623 -8.730228) (xy 30.50313 -8.730228)
			(xy 30.589659 -8.738246) (xy 30.675079 -8.754214) (xy 30.758661 -8.777995) (xy 30.839693 -8.809387)
			(xy 30.917482 -8.848121) (xy 30.991366 -8.893868) (xy 31.060713 -8.946237) (xy 31.124933 -9.004781)
			(xy 31.183477 -9.069001) (xy 31.235846 -9.138348) (xy 31.281593 -9.212232) (xy 31.320327 -9.290021)
			(xy 31.351719 -9.371053) (xy 31.3755 -9.454635) (xy 31.391468 -9.540055) (xy 31.399486 -9.626584)
			(xy 31.399988 -9.670034) (xy 31.399486 -9.713484) (xy 34.599874 -9.713484) (xy 34.599874 -9.626584)
			(xy 34.607892 -9.540055) (xy 34.62386 -9.454635) (xy 34.647641 -9.371053) (xy 34.679033 -9.290021)
			(xy 34.717767 -9.212232) (xy 34.763514 -9.138348) (xy 34.815883 -9.069001) (xy 34.874427 -9.004781)
			(xy 34.938647 -8.946237) (xy 35.007994 -8.893868) (xy 35.081878 -8.848121) (xy 35.159667 -8.809387)
			(xy 35.240699 -8.777995) (xy 35.324281 -8.754214) (xy 35.409701 -8.738246) (xy 35.49623 -8.730228)
			(xy 35.58313 -8.730228) (xy 35.669659 -8.738246) (xy 35.755079 -8.754214) (xy 35.838661 -8.777995)
			(xy 35.919693 -8.809387) (xy 35.997482 -8.848121) (xy 36.071366 -8.893868) (xy 36.140713 -8.946237)
			(xy 36.204933 -9.004781) (xy 36.263477 -9.069001) (xy 36.315846 -9.138348) (xy 36.361593 -9.212232)
			(xy 36.400327 -9.290021) (xy 36.431719 -9.371053) (xy 36.4555 -9.454635) (xy 36.471468 -9.540055)
			(xy 36.479486 -9.626584) (xy 36.479988 -9.670034) (xy 36.479486 -9.713484) (xy 36.471468 -9.800013)
			(xy 36.4555 -9.885433) (xy 36.431719 -9.969015) (xy 36.400327 -10.050047) (xy 36.361593 -10.127836)
			(xy 36.315846 -10.20172) (xy 36.263477 -10.271067) (xy 36.204933 -10.335287) (xy 36.140713 -10.393831)
			(xy 36.071366 -10.4462) (xy 35.997482 -10.491947) (xy 35.919693 -10.530681) (xy 35.838661 -10.562073)
			(xy 35.755079 -10.585854) (xy 35.669659 -10.601822) (xy 35.58313 -10.60984) (xy 35.49623 -10.60984)
			(xy 35.409701 -10.601822) (xy 35.324281 -10.585854) (xy 35.240699 -10.562073) (xy 35.159667 -10.530681)
			(xy 35.081878 -10.491947) (xy 35.007994 -10.4462) (xy 34.938647 -10.393831) (xy 34.874427 -10.335287)
			(xy 34.815883 -10.271067) (xy 34.763514 -10.20172) (xy 34.717767 -10.127836) (xy 34.679033 -10.050047)
			(xy 34.647641 -9.969015) (xy 34.62386 -9.885433) (xy 34.607892 -9.800013) (xy 34.599874 -9.713484)
			(xy 31.399486 -9.713484) (xy 31.391468 -9.800013) (xy 31.3755 -9.885433) (xy 31.351719 -9.969015)
			(xy 31.320327 -10.050047) (xy 31.281593 -10.127836) (xy 31.235846 -10.20172) (xy 31.183477 -10.271067)
			(xy 31.124933 -10.335287) (xy 31.060713 -10.393831) (xy 30.991366 -10.4462) (xy 30.917482 -10.491947)
			(xy 30.839693 -10.530681) (xy 30.758661 -10.562073) (xy 30.675079 -10.585854) (xy 30.589659 -10.601822)
			(xy 30.50313 -10.60984) (xy 30.41623 -10.60984) (xy 30.329701 -10.601822) (xy 30.244281 -10.585854)
			(xy 30.160699 -10.562073) (xy 30.079667 -10.530681) (xy 30.001878 -10.491947) (xy 29.927994 -10.4462)
			(xy 29.858647 -10.393831) (xy 29.794427 -10.335287) (xy 29.735883 -10.271067) (xy 29.683514 -10.20172)
			(xy 29.637767 -10.127836) (xy 29.599033 -10.050047) (xy 29.567641 -9.969015) (xy 29.54386 -9.885433)
			(xy 29.527892 -9.800013) (xy 29.519874 -9.713484) (xy 27.795391 -9.713484) (xy 27.809639 -9.743877)
			(xy 27.825707 -9.797284) (xy 27.833827 -9.85246) (xy 27.834336 -9.880346) (xy 27.833827 -9.908232)
			(xy 27.825707 -9.963408) (xy 27.809639 -10.016815) (xy 27.785967 -10.067312) (xy 27.755194 -10.113825)
			(xy 27.717977 -10.155362) (xy 27.675109 -10.191037) (xy 27.627503 -10.220091) (xy 27.576174 -10.241903)
			(xy 27.522217 -10.256009) (xy 27.46678 -10.262109) (xy 27.411046 -10.260072) (xy 27.356203 -10.249942)
			(xy 27.303419 -10.231935) (xy 27.253819 -10.206434) (xy 27.208461 -10.173983) (xy 27.168312 -10.135274)
			(xy 27.134226 -10.091131) (xy 27.10693 -10.042496) (xy 27.087007 -9.990405) (xy 27.074881 -9.935968)
			(xy 27.07081 -9.880346) (xy 24.830784 -9.880346) (xy 24.813307 -9.884915) (xy 24.75787 -9.891015)
			(xy 24.702136 -9.888978) (xy 24.647293 -9.878848) (xy 24.594509 -9.860841) (xy 24.544909 -9.83534)
			(xy 24.499551 -9.802889) (xy 24.459402 -9.76418) (xy 24.425316 -9.720037) (xy 24.39802 -9.671402)
			(xy 24.378097 -9.619311) (xy 24.365971 -9.564874) (xy 24.3619 -9.509252) (xy 17.16753 -9.509252)
			(xy 17.142864 -9.542463) (xy 17.087238 -9.60353) (xy 17.025795 -9.65874) (xy 16.959148 -9.707543)
			(xy 16.887963 -9.749449) (xy 16.812951 -9.784041) (xy 16.734861 -9.810974) (xy 16.654473 -9.829978)
			(xy 16.572589 -9.840864) (xy 16.490028 -9.843522) (xy 16.448786 -9.84123) (xy 16.41656 -9.83873)
			(xy 16.352606 -9.829318) (xy 16.321024 -9.822434) (xy 16.318738 -9.821926) (xy 16.283686 -9.813036)
			(xy 16.282924 -9.812782) (xy 16.275558 -9.81075) (xy 16.260318 -9.806178) (xy 16.24076 -9.80313)
			(xy 16.226032 -9.801395) (xy 16.196494 -9.803948) (xy 16.168339 -9.813236) (xy 16.143079 -9.828758)
			(xy 16.132302 -9.838944) (xy 15.694914 -10.276332) (xy 15.684327 -10.287491) (xy 15.668315 -10.313743)
			(xy 15.659045 -10.343062) (xy 15.657576 -10.358374) (xy 15.657576 -10.617962) (xy 25.381202 -10.617962)
			(xy 25.385273 -10.56234) (xy 25.397399 -10.507903) (xy 25.417322 -10.455812) (xy 25.444618 -10.407177)
			(xy 25.478704 -10.363034) (xy 25.518853 -10.324325) (xy 25.564211 -10.291874) (xy 25.613811 -10.266373)
			(xy 25.666595 -10.248366) (xy 25.721438 -10.238236) (xy 25.777172 -10.236199) (xy 25.832609 -10.242299)
			(xy 25.886566 -10.256405) (xy 25.937895 -10.278217) (xy 25.985501 -10.307271) (xy 26.028369 -10.342946)
			(xy 26.065586 -10.384483) (xy 26.096359 -10.430996) (xy 26.120031 -10.481493) (xy 26.136099 -10.5349)
			(xy 26.144219 -10.590076) (xy 26.144728 -10.617962) (xy 26.144219 -10.645848) (xy 26.136099 -10.701024)
			(xy 26.120031 -10.754431) (xy 26.096359 -10.804928) (xy 26.065586 -10.851441) (xy 26.028369 -10.892978)
			(xy 25.985501 -10.928653) (xy 25.937895 -10.957707) (xy 25.886566 -10.979519) (xy 25.832609 -10.993625)
			(xy 25.777172 -10.999725) (xy 25.721438 -10.997688) (xy 25.666595 -10.987558) (xy 25.613811 -10.969551)
			(xy 25.564211 -10.94405) (xy 25.518853 -10.911599) (xy 25.478704 -10.87289) (xy 25.444618 -10.828747)
			(xy 25.417322 -10.780112) (xy 25.397399 -10.728021) (xy 25.385273 -10.673584) (xy 25.381202 -10.617962)
			(xy 15.657576 -10.617962) (xy 15.657576 -10.672064) (xy 15.659572 -10.69384) (xy 15.670071 -10.736287)
			(xy 15.687671 -10.776314) (xy 15.711855 -10.812744) (xy 15.74191 -10.844503) (xy 15.776952 -10.870657)
			(xy 15.815949 -10.890435) (xy 15.857753 -10.903256) (xy 15.901133 -10.908742) (xy 15.944813 -10.906732)
			(xy 15.987506 -10.897284) (xy 16.027956 -10.880678) (xy 16.046704 -10.869422) (xy 16.081935 -10.846574)
			(xy 16.156185 -10.807346) (xy 16.234032 -10.775855) (xy 16.314674 -10.752428) (xy 16.397276 -10.737306)
			(xy 16.480987 -10.730645) (xy 16.564942 -10.732513) (xy 16.648274 -10.742892) (xy 16.730122 -10.761675)
			(xy 16.809641 -10.788667) (xy 16.886011 -10.823589) (xy 16.958442 -10.866082) (xy 16.9926 -10.890504)
			(xy 17.032902 -10.920946) (xy 17.106519 -10.990099) (xy 17.139412 -11.028426) (xy 17.154092 -11.046282)
			(xy 17.181666 -11.083389) (xy 17.19453 -11.102594) (xy 17.216393 -11.136678) (xy 17.254109 -11.20834)
			(xy 17.284628 -11.28335) (xy 17.307657 -11.360988) (xy 17.322972 -11.440507) (xy 17.330429 -11.521144)
			(xy 17.329955 -11.602124) (xy 17.321554 -11.682668) (xy 17.305307 -11.762002) (xy 17.293844 -11.80084)
			(xy 17.28343 -11.834622) (xy 17.300448 -11.903202) (xy 17.96034 -12.563094) (xy 25.690066 -12.563094)
			(xy 25.694137 -12.507472) (xy 25.706263 -12.453035) (xy 25.726186 -12.400944) (xy 25.753482 -12.352309)
			(xy 25.787568 -12.308166) (xy 25.827717 -12.269457) (xy 25.873075 -12.237006) (xy 25.922675 -12.211505)
			(xy 25.975459 -12.193498) (xy 26.030302 -12.183368) (xy 26.086036 -12.181331) (xy 26.141473 -12.187431)
			(xy 26.19543 -12.201537) (xy 26.246759 -12.223349) (xy 26.294365 -12.252403) (xy 26.295664 -12.253484)
			(xy 29.519874 -12.253484) (xy 29.519874 -12.166584) (xy 29.527892 -12.080055) (xy 29.54386 -11.994635)
			(xy 29.567641 -11.911053) (xy 29.599033 -11.830021) (xy 29.637767 -11.752232) (xy 29.683514 -11.678348)
			(xy 29.735883 -11.609001) (xy 29.794427 -11.544781) (xy 29.858647 -11.486237) (xy 29.927994 -11.433868)
			(xy 30.001878 -11.388121) (xy 30.079667 -11.349387) (xy 30.160699 -11.317995) (xy 30.244281 -11.294214)
			(xy 30.329701 -11.278246) (xy 30.41623 -11.270228) (xy 30.50313 -11.270228) (xy 30.589659 -11.278246)
			(xy 30.675079 -11.294214) (xy 30.758661 -11.317995) (xy 30.839693 -11.349387) (xy 30.917482 -11.388121)
			(xy 30.991366 -11.433868) (xy 31.060713 -11.486237) (xy 31.124933 -11.544781) (xy 31.183477 -11.609001)
			(xy 31.235846 -11.678348) (xy 31.281593 -11.752232) (xy 31.320327 -11.830021) (xy 31.351719 -11.911053)
			(xy 31.3755 -11.994635) (xy 31.391468 -12.080055) (xy 31.399486 -12.166584) (xy 31.399988 -12.210034)
			(xy 31.399486 -12.253484) (xy 34.599874 -12.253484) (xy 34.599874 -12.166584) (xy 34.607892 -12.080055)
			(xy 34.62386 -11.994635) (xy 34.647641 -11.911053) (xy 34.679033 -11.830021) (xy 34.717767 -11.752232)
			(xy 34.763514 -11.678348) (xy 34.815883 -11.609001) (xy 34.874427 -11.544781) (xy 34.938647 -11.486237)
			(xy 35.007994 -11.433868) (xy 35.081878 -11.388121) (xy 35.159667 -11.349387) (xy 35.240699 -11.317995)
			(xy 35.324281 -11.294214) (xy 35.409701 -11.278246) (xy 35.49623 -11.270228) (xy 35.58313 -11.270228)
			(xy 35.669659 -11.278246) (xy 35.755079 -11.294214) (xy 35.838661 -11.317995) (xy 35.919693 -11.349387)
			(xy 35.997482 -11.388121) (xy 36.071366 -11.433868) (xy 36.140713 -11.486237) (xy 36.204933 -11.544781)
			(xy 36.263477 -11.609001) (xy 36.315846 -11.678348) (xy 36.361593 -11.752232) (xy 36.400327 -11.830021)
			(xy 36.431719 -11.911053) (xy 36.4555 -11.994635) (xy 36.471468 -12.080055) (xy 36.479486 -12.166584)
			(xy 36.479988 -12.210034) (xy 36.479486 -12.253484) (xy 36.471468 -12.340013) (xy 36.4555 -12.425433)
			(xy 36.431719 -12.509015) (xy 36.400327 -12.590047) (xy 36.361593 -12.667836) (xy 36.315846 -12.74172)
			(xy 36.263477 -12.811067) (xy 36.204933 -12.875287) (xy 36.140713 -12.933831) (xy 36.071366 -12.9862)
			(xy 35.997482 -13.031947) (xy 35.936717 -13.062204) (xy 39.637714 -13.062204) (xy 39.641785 -13.006582)
			(xy 39.653911 -12.952145) (xy 39.673834 -12.900054) (xy 39.70113 -12.851419) (xy 39.735216 -12.807276)
			(xy 39.775365 -12.768567) (xy 39.820723 -12.736116) (xy 39.870323 -12.710615) (xy 39.923107 -12.692608)
			(xy 39.97795 -12.682478) (xy 40.033684 -12.680441) (xy 40.089121 -12.686541) (xy 40.143078 -12.700647)
			(xy 40.194407 -12.722459) (xy 40.242013 -12.751513) (xy 40.284881 -12.787188) (xy 40.322098 -12.828725)
			(xy 40.352871 -12.875238) (xy 40.376543 -12.925735) (xy 40.392611 -12.979142) (xy 40.400731 -13.034318)
			(xy 40.40124 -13.062204) (xy 40.400731 -13.09009) (xy 40.392611 -13.145266) (xy 40.376543 -13.198673)
			(xy 40.352871 -13.24917) (xy 40.322098 -13.295683) (xy 40.284881 -13.33722) (xy 40.242013 -13.372895)
			(xy 40.194407 -13.401949) (xy 40.143078 -13.423761) (xy 40.089121 -13.437867) (xy 40.033684 -13.443967)
			(xy 39.97795 -13.44193) (xy 39.923107 -13.4318) (xy 39.870323 -13.413793) (xy 39.820723 -13.388292)
			(xy 39.775365 -13.355841) (xy 39.735216 -13.317132) (xy 39.70113 -13.272989) (xy 39.673834 -13.224354)
			(xy 39.653911 -13.172263) (xy 39.641785 -13.117826) (xy 39.637714 -13.062204) (xy 35.936717 -13.062204)
			(xy 35.919693 -13.070681) (xy 35.838661 -13.102073) (xy 35.755079 -13.125854) (xy 35.669659 -13.141822)
			(xy 35.58313 -13.14984) (xy 35.49623 -13.14984) (xy 35.409701 -13.141822) (xy 35.324281 -13.125854)
			(xy 35.240699 -13.102073) (xy 35.159667 -13.070681) (xy 35.081878 -13.031947) (xy 35.007994 -12.9862)
			(xy 34.938647 -12.933831) (xy 34.874427 -12.875287) (xy 34.815883 -12.811067) (xy 34.763514 -12.74172)
			(xy 34.717767 -12.667836) (xy 34.679033 -12.590047) (xy 34.647641 -12.509015) (xy 34.62386 -12.425433)
			(xy 34.607892 -12.340013) (xy 34.599874 -12.253484) (xy 31.399486 -12.253484) (xy 31.391468 -12.340013)
			(xy 31.3755 -12.425433) (xy 31.351719 -12.509015) (xy 31.320327 -12.590047) (xy 31.281593 -12.667836)
			(xy 31.235846 -12.74172) (xy 31.183477 -12.811067) (xy 31.124933 -12.875287) (xy 31.060713 -12.933831)
			(xy 30.991366 -12.9862) (xy 30.917482 -13.031947) (xy 30.839693 -13.070681) (xy 30.758661 -13.102073)
			(xy 30.675079 -13.125854) (xy 30.589659 -13.141822) (xy 30.50313 -13.14984) (xy 30.41623 -13.14984)
			(xy 30.329701 -13.141822) (xy 30.244281 -13.125854) (xy 30.160699 -13.102073) (xy 30.079667 -13.070681)
			(xy 30.001878 -13.031947) (xy 29.927994 -12.9862) (xy 29.858647 -12.933831) (xy 29.794427 -12.875287)
			(xy 29.735883 -12.811067) (xy 29.683514 -12.74172) (xy 29.637767 -12.667836) (xy 29.599033 -12.590047)
			(xy 29.567641 -12.509015) (xy 29.54386 -12.425433) (xy 29.527892 -12.340013) (xy 29.519874 -12.253484)
			(xy 26.295664 -12.253484) (xy 26.337233 -12.288078) (xy 26.37445 -12.329615) (xy 26.405223 -12.376128)
			(xy 26.428895 -12.426625) (xy 26.444963 -12.480032) (xy 26.453083 -12.535208) (xy 26.453592 -12.563094)
			(xy 26.453083 -12.59098) (xy 26.444963 -12.646156) (xy 26.436558 -12.674092) (xy 26.898852 -12.674092)
			(xy 26.902923 -12.61847) (xy 26.915049 -12.564033) (xy 26.934972 -12.511942) (xy 26.962268 -12.463307)
			(xy 26.996354 -12.419164) (xy 27.036503 -12.380455) (xy 27.081861 -12.348004) (xy 27.131461 -12.322503)
			(xy 27.184245 -12.304496) (xy 27.239088 -12.294366) (xy 27.294822 -12.292329) (xy 27.350259 -12.298429)
			(xy 27.404216 -12.312535) (xy 27.455545 -12.334347) (xy 27.503151 -12.363401) (xy 27.546019 -12.399076)
			(xy 27.583236 -12.440613) (xy 27.614009 -12.487126) (xy 27.637681 -12.537623) (xy 27.653749 -12.59103)
			(xy 27.661869 -12.646206) (xy 27.662378 -12.674092) (xy 27.661869 -12.701978) (xy 27.653749 -12.757154)
			(xy 27.637681 -12.810561) (xy 27.614009 -12.861058) (xy 27.583236 -12.907571) (xy 27.546019 -12.949108)
			(xy 27.503151 -12.984783) (xy 27.455545 -13.013837) (xy 27.404216 -13.035649) (xy 27.350259 -13.049755)
			(xy 27.294822 -13.055855) (xy 27.239088 -13.053818) (xy 27.184245 -13.043688) (xy 27.131461 -13.025681)
			(xy 27.081861 -13.00018) (xy 27.036503 -12.967729) (xy 26.996354 -12.92902) (xy 26.962268 -12.884877)
			(xy 26.934972 -12.836242) (xy 26.915049 -12.784151) (xy 26.902923 -12.729714) (xy 26.898852 -12.674092)
			(xy 26.436558 -12.674092) (xy 26.428895 -12.699563) (xy 26.405223 -12.75006) (xy 26.37445 -12.796573)
			(xy 26.337233 -12.83811) (xy 26.294365 -12.873785) (xy 26.246759 -12.902839) (xy 26.19543 -12.924651)
			(xy 26.141473 -12.938757) (xy 26.086036 -12.944857) (xy 26.030302 -12.94282) (xy 25.975459 -12.93269)
			(xy 25.922675 -12.914683) (xy 25.873075 -12.889182) (xy 25.827717 -12.856731) (xy 25.787568 -12.818022)
			(xy 25.753482 -12.773879) (xy 25.726186 -12.725244) (xy 25.706263 -12.673153) (xy 25.694137 -12.618716)
			(xy 25.690066 -12.563094) (xy 17.96034 -12.563094) (xy 18.05432 -12.657074) (xy 18.05432 -14.7955)
			(xy 27.317698 -14.7955) (xy 27.321769 -14.739878) (xy 27.333895 -14.685441) (xy 27.353818 -14.63335)
			(xy 27.381114 -14.584715) (xy 27.4152 -14.540572) (xy 27.455349 -14.501863) (xy 27.500707 -14.469412)
			(xy 27.550307 -14.443911) (xy 27.603091 -14.425904) (xy 27.657934 -14.415774) (xy 27.713668 -14.413737)
			(xy 27.769105 -14.419837) (xy 27.823062 -14.433943) (xy 27.874391 -14.455755) (xy 27.921997 -14.484809)
			(xy 27.964865 -14.520484) (xy 28.002082 -14.562021) (xy 28.032855 -14.608534) (xy 28.056527 -14.659031)
			(xy 28.072595 -14.712438) (xy 28.080715 -14.767614) (xy 28.081187 -14.793484) (xy 29.519874 -14.793484)
			(xy 29.519874 -14.706584) (xy 29.527892 -14.620055) (xy 29.54386 -14.534635) (xy 29.567641 -14.451053)
			(xy 29.599033 -14.370021) (xy 29.637767 -14.292232) (xy 29.683514 -14.218348) (xy 29.735883 -14.149001)
			(xy 29.794427 -14.084781) (xy 29.858647 -14.026237) (xy 29.927994 -13.973868) (xy 30.001878 -13.928121)
			(xy 30.079667 -13.889387) (xy 30.160699 -13.857995) (xy 30.244281 -13.834214) (xy 30.329701 -13.818246)
			(xy 30.41623 -13.810228) (xy 30.50313 -13.810228) (xy 30.589659 -13.818246) (xy 30.675079 -13.834214)
			(xy 30.758661 -13.857995) (xy 30.839693 -13.889387) (xy 30.917482 -13.928121) (xy 30.991366 -13.973868)
			(xy 31.060713 -14.026237) (xy 31.124933 -14.084781) (xy 31.183477 -14.149001) (xy 31.235846 -14.218348)
			(xy 31.281593 -14.292232) (xy 31.320327 -14.370021) (xy 31.351719 -14.451053) (xy 31.3755 -14.534635)
			(xy 31.391468 -14.620055) (xy 31.399486 -14.706584) (xy 31.399988 -14.750034) (xy 31.399486 -14.793484)
			(xy 31.391468 -14.880013) (xy 31.3755 -14.965433) (xy 31.351719 -15.049015) (xy 31.320327 -15.130047)
			(xy 31.281593 -15.207836) (xy 31.235846 -15.28172) (xy 31.183477 -15.351067) (xy 31.124933 -15.415287)
			(xy 31.060713 -15.473831) (xy 30.991366 -15.5262) (xy 30.917482 -15.571947) (xy 30.839693 -15.610681)
			(xy 30.758661 -15.642073) (xy 30.675079 -15.665854) (xy 30.589659 -15.681822) (xy 30.50313 -15.68984)
			(xy 30.41623 -15.68984) (xy 30.329701 -15.681822) (xy 30.244281 -15.665854) (xy 30.160699 -15.642073)
			(xy 30.079667 -15.610681) (xy 30.001878 -15.571947) (xy 29.927994 -15.5262) (xy 29.858647 -15.473831)
			(xy 29.794427 -15.415287) (xy 29.735883 -15.351067) (xy 29.683514 -15.28172) (xy 29.637767 -15.207836)
			(xy 29.599033 -15.130047) (xy 29.567641 -15.049015) (xy 29.54386 -14.965433) (xy 29.527892 -14.880013)
			(xy 29.519874 -14.793484) (xy 28.081187 -14.793484) (xy 28.081224 -14.7955) (xy 28.080715 -14.823386)
			(xy 28.072595 -14.878562) (xy 28.056527 -14.931969) (xy 28.032855 -14.982466) (xy 28.002082 -15.028979)
			(xy 27.964865 -15.070516) (xy 27.921997 -15.106191) (xy 27.874391 -15.135245) (xy 27.823062 -15.157057)
			(xy 27.769105 -15.171163) (xy 27.713668 -15.177263) (xy 27.657934 -15.175226) (xy 27.603091 -15.165096)
			(xy 27.550307 -15.147089) (xy 27.500707 -15.121588) (xy 27.455349 -15.089137) (xy 27.4152 -15.050428)
			(xy 27.381114 -15.006285) (xy 27.353818 -14.95765) (xy 27.333895 -14.905559) (xy 27.321769 -14.851122)
			(xy 27.317698 -14.7955) (xy 18.05432 -14.7955) (xy 18.05432 -14.983206) (xy 17.366234 -15.671292)
			(xy 17.316958 -15.671292) (xy 17.294631 -15.671755) (xy 17.250662 -15.679553) (xy 17.208734 -15.694917)
			(xy 17.170138 -15.717376) (xy 17.136063 -15.746236) (xy 17.107559 -15.78061) (xy 17.085503 -15.819438)
			(xy 17.084445 -15.822422) (xy 26.122882 -15.822422) (xy 26.126953 -15.7668) (xy 26.139079 -15.712363)
			(xy 26.159002 -15.660272) (xy 26.186298 -15.611637) (xy 26.220384 -15.567494) (xy 26.260533 -15.528785)
			(xy 26.305891 -15.496334) (xy 26.355491 -15.470833) (xy 26.408275 -15.452826) (xy 26.463118 -15.442696)
			(xy 26.518852 -15.440659) (xy 26.574289 -15.446759) (xy 26.628246 -15.460865) (xy 26.679575 -15.482677)
			(xy 26.727181 -15.511731) (xy 26.770049 -15.547406) (xy 26.807266 -15.588943) (xy 26.838039 -15.635456)
			(xy 26.861711 -15.685953) (xy 26.877779 -15.73936) (xy 26.885899 -15.794536) (xy 26.886408 -15.822422)
			(xy 26.885899 -15.850308) (xy 26.877779 -15.905484) (xy 26.861711 -15.958891) (xy 26.838039 -16.009388)
			(xy 26.807266 -16.055901) (xy 26.770049 -16.097438) (xy 26.727181 -16.133113) (xy 26.679575 -16.162167)
			(xy 26.628246 -16.183979) (xy 26.574289 -16.198085) (xy 26.518852 -16.204185) (xy 26.463118 -16.202148)
			(xy 26.408275 -16.192018) (xy 26.355491 -16.174011) (xy 26.305891 -16.14851) (xy 26.260533 -16.116059)
			(xy 26.220384 -16.07735) (xy 26.186298 -16.033207) (xy 26.159002 -15.984572) (xy 26.139079 -15.932481)
			(xy 26.126953 -15.878044) (xy 26.122882 -15.822422) (xy 17.084445 -15.822422) (xy 17.070576 -15.861524)
			(xy 17.063237 -15.905571) (xy 17.063713 -15.950223) (xy 17.071987 -15.994105) (xy 17.087807 -16.035863)
			(xy 17.110684 -16.074213) (xy 17.124934 -16.091408) (xy 17.150972 -16.12172) (xy 17.197712 -16.18654)
			(xy 17.237976 -16.255569) (xy 17.271388 -16.328162) (xy 17.297638 -16.403642) (xy 17.316479 -16.481303)
			(xy 17.327735 -16.56042) (xy 17.331302 -16.640255) (xy 17.329658 -16.68018) (xy 17.327098 -16.719949)
			(xy 17.315286 -16.798766) (xy 17.295939 -16.87608) (xy 17.269236 -16.95117) (xy 17.235426 -17.02334)
			(xy 17.194822 -17.091918) (xy 17.147802 -17.156267) (xy 17.094803 -17.215789) (xy 17.036319 -17.269929)
			(xy 16.972892 -17.318186) (xy 16.93926 -17.339564) (xy 16.905444 -17.359945) (xy 16.834637 -17.394892)
			(xy 16.760818 -17.42292) (xy 16.68466 -17.443773) (xy 16.606859 -17.45726) (xy 16.528126 -17.463259)
			(xy 16.44918 -17.461714) (xy 16.370742 -17.452639) (xy 16.293528 -17.436118) (xy 16.255746 -17.424654)
			(xy 16.217445 -17.412039) (xy 16.143283 -17.380359) (xy 16.072559 -17.341605) (xy 16.005948 -17.296147)
			(xy 15.944081 -17.244415) (xy 15.887548 -17.186903) (xy 15.836886 -17.124157) (xy 15.792578 -17.056775)
			(xy 15.7734 -17.021302) (xy 15.771114 -17.017492) (xy 15.762284 -17.003524) (xy 15.738776 -16.980317)
			(xy 15.71009 -16.963935) (xy 15.678157 -16.955481) (xy 15.66164 -16.955008) (xy 14.788642 -16.955008)
			(xy 14.766742 -16.955472) (xy 14.723591 -16.962993) (xy 14.68237 -16.977802) (xy 14.644298 -16.999461)
			(xy 14.610505 -17.027327) (xy 14.581991 -17.060576) (xy 14.5596 -17.098221) (xy 14.543997 -17.139149)
			(xy 14.535644 -17.182146) (xy 14.534787 -17.225939) (xy 14.541453 -17.269229) (xy 14.555444 -17.310736)
			(xy 14.576345 -17.349228) (xy 14.589506 -17.366742) (xy 14.614952 -17.396873) (xy 14.660616 -17.461181)
			(xy 14.699943 -17.529549) (xy 14.732574 -17.601353) (xy 14.758212 -17.675942) (xy 14.776623 -17.752634)
			(xy 14.787641 -17.830732) (xy 14.791165 -17.909525) (xy 14.787162 -17.988295) (xy 14.775669 -18.066324)
			(xy 14.756791 -18.142903) (xy 14.730699 -18.217334) (xy 14.697632 -18.288939) (xy 14.662026 -18.349976)
			(xy 26.862784 -18.349976) (xy 26.866855 -18.294354) (xy 26.878981 -18.239917) (xy 26.898904 -18.187826)
			(xy 26.9262 -18.139191) (xy 26.960286 -18.095048) (xy 27.000435 -18.056339) (xy 27.045793 -18.023888)
			(xy 27.095393 -17.998387) (xy 27.148177 -17.98038) (xy 27.20302 -17.97025) (xy 27.258754 -17.968213)
			(xy 27.314191 -17.974313) (xy 27.368148 -17.988419) (xy 27.419477 -18.010231) (xy 27.467083 -18.039285)
			(xy 27.509951 -18.07496) (xy 27.547168 -18.116497) (xy 27.577941 -18.16301) (xy 27.601613 -18.213507)
			(xy 27.617681 -18.266914) (xy 27.625801 -18.32209) (xy 27.62631 -18.349976) (xy 27.625801 -18.377862)
			(xy 27.617681 -18.433038) (xy 27.601613 -18.486445) (xy 27.577941 -18.536942) (xy 27.547168 -18.583455)
			(xy 27.509951 -18.624992) (xy 27.467083 -18.660667) (xy 27.419477 -18.689721) (xy 27.368148 -18.711533)
			(xy 27.314191 -18.725639) (xy 27.258754 -18.731739) (xy 27.20302 -18.729702) (xy 27.148177 -18.719572)
			(xy 27.095393 -18.701565) (xy 27.045793 -18.676064) (xy 27.000435 -18.643613) (xy 26.960286 -18.604904)
			(xy 26.9262 -18.560761) (xy 26.898904 -18.512126) (xy 26.878981 -18.460035) (xy 26.866855 -18.405598)
			(xy 26.862784 -18.349976) (xy 14.662026 -18.349976) (xy 14.65789 -18.357066) (xy 14.611836 -18.421095)
			(xy 14.586204 -18.451068) (xy 14.558909 -18.481493) (xy 14.499256 -18.537379) (xy 14.434377 -18.587103)
			(xy 14.364906 -18.630179) (xy 14.291521 -18.666186) (xy 14.214941 -18.694772) (xy 14.135912 -18.715657)
			(xy 14.055207 -18.728638) (xy 13.973615 -18.733587) (xy 13.891933 -18.730457) (xy 13.810959 -18.719278)
			(xy 13.771118 -18.710148) (xy 13.755191 -18.706821) (xy 13.722671 -18.707456) (xy 13.69137 -18.716297)
			(xy 13.663323 -18.732769) (xy 13.651484 -18.74393) (xy 13.2461 -19.149314) (xy 13.2461 -20.194524)
			(xy 12.471049 -20.969478) (xy 26.063446 -20.969478) (xy 26.067517 -20.913856) (xy 26.079643 -20.859419)
			(xy 26.099566 -20.807328) (xy 26.126862 -20.758693) (xy 26.160948 -20.71455) (xy 26.201097 -20.675841)
			(xy 26.246455 -20.64339) (xy 26.296055 -20.617889) (xy 26.348839 -20.599882) (xy 26.403682 -20.589752)
			(xy 26.459416 -20.587715) (xy 26.514853 -20.593815) (xy 26.56881 -20.607921) (xy 26.620139 -20.629733)
			(xy 26.667745 -20.658787) (xy 26.710613 -20.694462) (xy 26.74783 -20.735999) (xy 26.778603 -20.782512)
			(xy 26.802275 -20.833009) (xy 26.818343 -20.886416) (xy 26.826463 -20.941592) (xy 26.826972 -20.969478)
			(xy 26.826463 -20.997364) (xy 26.818343 -21.05254) (xy 26.802275 -21.105947) (xy 26.778603 -21.156444)
			(xy 26.74783 -21.202957) (xy 26.710613 -21.244494) (xy 26.667745 -21.280169) (xy 26.620139 -21.309223)
			(xy 26.56881 -21.331035) (xy 26.514853 -21.345141) (xy 26.459416 -21.351241) (xy 26.403682 -21.349204)
			(xy 26.348839 -21.339074) (xy 26.296055 -21.321067) (xy 26.246455 -21.295566) (xy 26.201097 -21.263115)
			(xy 26.160948 -21.224406) (xy 26.126862 -21.180263) (xy 26.099566 -21.131628) (xy 26.079643 -21.079537)
			(xy 26.067517 -21.0251) (xy 26.063446 -20.969478) (xy 12.471049 -20.969478) (xy 11.217148 -22.223222)
			(xy 11.205796 -22.23537) (xy 11.189199 -22.264164) (xy 11.180593 -22.296267) (xy 11.180064 -22.312884)
			(xy 11.180064 -27.589988) (xy 11.194265 -27.607614) (xy 11.227794 -27.638014) (xy 11.266173 -27.662003)
			(xy 11.30819 -27.678823) (xy 11.35252 -27.687943) (xy 11.397765 -27.689077) (xy 11.442497 -27.682188)
			(xy 11.485304 -27.667494) (xy 11.524835 -27.645457) (xy 11.559845 -27.616774) (xy 11.589227 -27.58235)
			(xy 11.612055 -27.54327) (xy 11.620246 -27.52217) (xy 11.65355 -27.424888) (xy 11.726786 -27.232722)
			(xy 11.807482 -27.043569) (xy 11.895517 -26.857717) (xy 11.990754 -26.675451) (xy 12.093049 -26.497051)
			(xy 12.202244 -26.322788) (xy 12.318172 -26.152931) (xy 12.440657 -25.987739) (xy 12.56951 -25.827464)
			(xy 12.704534 -25.672353) (xy 12.845523 -25.522643) (xy 12.99226 -25.378562) (xy 13.068046 -25.309068)
			(xy 13.143846 -25.24092) (xy 13.299991 -25.109859) (xy 13.461101 -24.984953) (xy 13.626934 -24.866389)
			(xy 13.79724 -24.754345) (xy 13.971764 -24.648991) (xy 14.150242 -24.550484) (xy 14.332407 -24.458973)
			(xy 14.517983 -24.374597) (xy 14.706693 -24.29748) (xy 14.898251 -24.227741) (xy 15.092369 -24.165483)
			(xy 15.288756 -24.110801) (xy 15.487116 -24.063776) (xy 15.687151 -24.024479) (xy 15.888559 -23.99297)
			(xy 16.091038 -23.969296) (xy 16.294283 -23.953492) (xy 16.497987 -23.945582) (xy 16.599916 -23.945088)
			(xy 16.706183 -23.945626) (xy 16.918541 -23.954227) (xy 17.130379 -23.97141) (xy 17.341348 -23.997147)
			(xy 17.551103 -24.031396) (xy 17.759301 -24.074102) (xy 17.965602 -24.125193) (xy 18.067782 -24.154384)
			(xy 18.149479 -24.178495) (xy 18.311436 -24.231337) (xy 18.391632 -24.260048) (xy 18.483546 -24.293875)
			(xy 18.665065 -24.367492) (xy 18.843714 -24.447823) (xy 19.019246 -24.534756) (xy 19.191415 -24.628171)
			(xy 19.359984 -24.727938) (xy 19.524717 -24.833917) (xy 19.685386 -24.945963) (xy 19.841768 -25.063919)
			(xy 19.993644 -25.18762) (xy 20.067524 -25.251918) (xy 20.143479 -25.319279) (xy 20.290742 -25.459063)
			(xy 20.432495 -25.604432) (xy 20.568526 -25.755168) (xy 20.698632 -25.911047) (xy 20.822618 -26.071837)
			(xy 20.940301 -26.237296) (xy 21.051503 -26.407178) (xy 21.15606 -26.581229) (xy 21.253814 -26.75919)
			(xy 21.34462 -26.940795) (xy 21.428342 -27.125772) (xy 21.504856 -27.313845) (xy 21.574046 -27.504734)
			(xy 21.635811 -27.698153) (xy 21.690057 -27.893814) (xy 21.736704 -28.091425) (xy 21.775681 -28.29069)
			(xy 21.806931 -28.491313) (xy 21.830407 -28.692992) (xy 21.846075 -28.895429) (xy 21.853909 -29.098319)
			(xy 21.854414 -29.19984) (xy 21.853905 -29.303806) (xy 21.845679 -29.511576) (xy 21.82924 -29.718858)
			(xy 21.804614 -29.925328) (xy 21.771839 -30.130661) (xy 21.730967 -30.334538) (xy 21.682062 -30.536637)
			(xy 21.6252 -30.736644) (xy 21.560471 -30.934245) (xy 21.487975 -31.129131) (xy 21.407826 -31.320996)
			(xy 21.364448 -31.415482) (xy 21.341842 -31.463742) (xy 21.295651 -31.559269) (xy 21.19657 -31.746935)
			(xy 21.089994 -31.930447) (xy 20.976098 -32.109508) (xy 20.855065 -32.283825) (xy 20.727094 -32.453114)
			(xy 20.592394 -32.617099) (xy 20.522184 -32.696658) (xy 20.452062 -32.774535) (xy 20.306464 -32.925293)
			(xy 20.15497 -33.070125) (xy 19.99782 -33.2088) (xy 19.835265 -33.341097) (xy 19.667563 -33.466805)
			(xy 19.494981 -33.585726) (xy 19.317793 -33.697669) (xy 19.227292 -33.750504) (xy 19.135383 -33.802968)
			(xy 18.947979 -33.90134) (xy 18.756764 -33.992085) (xy 18.562051 -34.075056) (xy 18.364153 -34.150117)
			(xy 18.163394 -34.217148) (xy 17.960098 -34.27604) (xy 17.754595 -34.326697) (xy 17.547218 -34.369037)
			(xy 17.338305 -34.40299) (xy 17.128194 -34.428503) (xy 16.917226 -34.445533) (xy 16.705743 -34.454054)
			(xy 16.599916 -34.454592) (xy 16.475964 -34.454592) (xy 16.475964 -34.453068) (xy 16.381562 -34.4504)
			(xy 16.193023 -34.439123) (xy 16.00501 -34.42108) (xy 15.817767 -34.396295) (xy 15.631534 -34.364799)
			(xy 15.538958 -34.346134) (xy 15.439651 -34.325163) (xy 15.242571 -34.276526) (xy 15.047516 -34.220314)
			(xy 14.854778 -34.156611) (xy 14.664644 -34.085512) (xy 14.477398 -34.007123) (xy 14.293318 -33.921562)
			(xy 14.11268 -33.828956) (xy 13.935754 -33.729442) (xy 13.762802 -33.62317) (xy 13.594083 -33.510298)
			(xy 13.42985 -33.390995) (xy 13.270346 -33.265438) (xy 13.11581 -33.133814) (xy 12.966473 -32.996321)
			(xy 12.822557 -32.853163) (xy 12.684277 -32.704554) (xy 12.551839 -32.550716) (xy 12.425441 -32.391878)
			(xy 12.305271 -32.228277) (xy 12.19151 -32.060157) (xy 12.084326 -31.887769) (xy 11.983879 -31.71137)
			(xy 11.890319 -31.531224) (xy 11.803787 -31.347599) (xy 11.72441 -31.160769) (xy 11.652308 -30.971013)
			(xy 11.619484 -30.87497) (xy 11.611091 -30.854047) (xy 11.588024 -30.81532) (xy 11.558492 -30.781265)
			(xy 11.523419 -30.752951) (xy 11.483903 -30.731262) (xy 11.441183 -30.71688) (xy 11.396596 -30.710254)
			(xy 11.35154 -30.711593) (xy 11.307425 -30.720853) (xy 11.265634 -30.737746) (xy 11.227475 -30.761741)
			(xy 11.194144 -30.792088) (xy 11.180064 -30.809692) (xy 11.180064 -32.239966) (xy 11.180601 -32.256584)
			(xy 11.18919 -32.288691) (xy 11.205792 -32.317483) (xy 11.217148 -32.329628) (xy 20.079208 -41.191434)
			(xy 20.079208 -54.679342) (xy 12.835636 -61.922914) (xy 12.835636 -62.143555) (xy 15.679156 -62.143555)
			(xy 15.679156 -62.062445) (xy 15.687106 -61.981726) (xy 15.702929 -61.902175) (xy 15.726474 -61.824559)
			(xy 15.757513 -61.749623) (xy 15.795748 -61.678091) (xy 15.84081 -61.610651) (xy 15.892265 -61.547952)
			(xy 15.949618 -61.490599) (xy 16.012317 -61.439144) (xy 16.079757 -61.394082) (xy 16.151289 -61.355847)
			(xy 16.226225 -61.324808) (xy 16.303841 -61.301263) (xy 16.383392 -61.28544) (xy 16.464111 -61.27749)
			(xy 16.545221 -61.27749) (xy 16.62594 -61.28544) (xy 16.705491 -61.301263) (xy 16.783107 -61.324808)
			(xy 16.858043 -61.355847) (xy 16.929575 -61.394082) (xy 16.997015 -61.439144) (xy 17.059714 -61.490599)
			(xy 17.117067 -61.547952) (xy 17.168522 -61.610651) (xy 17.213584 -61.678091) (xy 17.251819 -61.749623)
			(xy 17.282858 -61.824559) (xy 17.306403 -61.902175) (xy 17.322226 -61.981726) (xy 17.330176 -62.062445)
			(xy 17.330674 -62.103) (xy 17.330176 -62.143555) (xy 17.322226 -62.224274) (xy 17.306403 -62.303825)
			(xy 17.282858 -62.381441) (xy 17.251819 -62.456377) (xy 17.213584 -62.527909) (xy 17.168522 -62.595349)
			(xy 17.117067 -62.658048) (xy 17.059714 -62.715401) (xy 16.997015 -62.766856) (xy 16.929575 -62.811918)
			(xy 16.858043 -62.850153) (xy 16.783107 -62.881192) (xy 16.705491 -62.904737) (xy 16.62594 -62.92056)
			(xy 16.545221 -62.92851) (xy 16.464111 -62.92851) (xy 16.383392 -62.92056) (xy 16.303841 -62.904737)
			(xy 16.226225 -62.881192) (xy 16.151289 -62.850153) (xy 16.079757 -62.811918) (xy 16.012317 -62.766856)
			(xy 15.949618 -62.715401) (xy 15.892265 -62.658048) (xy 15.84081 -62.595349) (xy 15.795748 -62.527909)
			(xy 15.757513 -62.456377) (xy 15.726474 -62.381441) (xy 15.702929 -62.303825) (xy 15.687106 -62.224274)
			(xy 15.679156 -62.143555) (xy 12.835636 -62.143555) (xy 12.835636 -63.413555) (xy 13.139156 -63.413555)
			(xy 13.139156 -63.332445) (xy 13.147106 -63.251726) (xy 13.162929 -63.172175) (xy 13.186474 -63.094559)
			(xy 13.217513 -63.019623) (xy 13.255748 -62.948091) (xy 13.30081 -62.880651) (xy 13.352265 -62.817952)
			(xy 13.409618 -62.760599) (xy 13.472317 -62.709144) (xy 13.539757 -62.664082) (xy 13.611289 -62.625847)
			(xy 13.686225 -62.594808) (xy 13.763841 -62.571263) (xy 13.843392 -62.55544) (xy 13.924111 -62.54749)
			(xy 14.005221 -62.54749) (xy 14.08594 -62.55544) (xy 14.165491 -62.571263) (xy 14.243107 -62.594808)
			(xy 14.318043 -62.625847) (xy 14.389575 -62.664082) (xy 14.457015 -62.709144) (xy 14.519714 -62.760599)
			(xy 14.577067 -62.817952) (xy 14.628522 -62.880651) (xy 14.673584 -62.948091) (xy 14.711819 -63.019623)
			(xy 14.742858 -63.094559) (xy 14.766403 -63.172175) (xy 14.782226 -63.251726) (xy 14.790176 -63.332445)
			(xy 14.790674 -63.373) (xy 14.790176 -63.413555) (xy 14.782226 -63.494274) (xy 14.766403 -63.573825)
			(xy 14.742858 -63.651441) (xy 14.711819 -63.726377) (xy 14.673584 -63.797909) (xy 14.628522 -63.865349)
			(xy 14.577067 -63.928048) (xy 14.519714 -63.985401) (xy 14.457015 -64.036856) (xy 14.389575 -64.081918)
			(xy 14.318043 -64.120153) (xy 14.243107 -64.151192) (xy 14.165491 -64.174737) (xy 14.08594 -64.19056)
			(xy 14.005221 -64.19851) (xy 13.924111 -64.19851) (xy 13.843392 -64.19056) (xy 13.763841 -64.174737)
			(xy 13.686225 -64.151192) (xy 13.611289 -64.120153) (xy 13.539757 -64.081918) (xy 13.472317 -64.036856)
			(xy 13.409618 -63.985401) (xy 13.352265 -63.928048) (xy 13.30081 -63.865349) (xy 13.255748 -63.797909)
			(xy 13.217513 -63.726377) (xy 13.186474 -63.651441) (xy 13.162929 -63.573825) (xy 13.147106 -63.494274)
			(xy 13.139156 -63.413555) (xy 12.835636 -63.413555) (xy 12.835636 -64.683555) (xy 15.679156 -64.683555)
			(xy 15.679156 -64.602445) (xy 15.687106 -64.521726) (xy 15.702929 -64.442175) (xy 15.726474 -64.364559)
			(xy 15.757513 -64.289623) (xy 15.795748 -64.218091) (xy 15.84081 -64.150651) (xy 15.892265 -64.087952)
			(xy 15.949618 -64.030599) (xy 16.012317 -63.979144) (xy 16.079757 -63.934082) (xy 16.151289 -63.895847)
			(xy 16.226225 -63.864808) (xy 16.303841 -63.841263) (xy 16.383392 -63.82544) (xy 16.464111 -63.81749)
			(xy 16.545221 -63.81749) (xy 16.62594 -63.82544) (xy 16.705491 -63.841263) (xy 16.783107 -63.864808)
			(xy 16.858043 -63.895847) (xy 16.929575 -63.934082) (xy 16.997015 -63.979144) (xy 17.059714 -64.030599)
			(xy 17.117067 -64.087952) (xy 17.168522 -64.150651) (xy 17.213584 -64.218091) (xy 17.251819 -64.289623)
			(xy 17.282858 -64.364559) (xy 17.306403 -64.442175) (xy 17.322226 -64.521726) (xy 17.330176 -64.602445)
			(xy 17.330674 -64.643) (xy 17.330176 -64.683555) (xy 17.322226 -64.764274) (xy 17.306403 -64.843825)
			(xy 17.282858 -64.921441) (xy 17.251819 -64.996377) (xy 17.213584 -65.067909) (xy 17.168522 -65.135349)
			(xy 17.117067 -65.198048) (xy 17.059714 -65.255401) (xy 16.997015 -65.306856) (xy 16.929575 -65.351918)
			(xy 16.858043 -65.390153) (xy 16.783107 -65.421192) (xy 16.705491 -65.444737) (xy 16.62594 -65.46056)
			(xy 16.545221 -65.46851) (xy 16.464111 -65.46851) (xy 16.383392 -65.46056) (xy 16.303841 -65.444737)
			(xy 16.226225 -65.421192) (xy 16.151289 -65.390153) (xy 16.079757 -65.351918) (xy 16.012317 -65.306856)
			(xy 15.949618 -65.255401) (xy 15.892265 -65.198048) (xy 15.84081 -65.135349) (xy 15.795748 -65.067909)
			(xy 15.757513 -64.996377) (xy 15.726474 -64.921441) (xy 15.702929 -64.843825) (xy 15.687106 -64.764274)
			(xy 15.679156 -64.683555) (xy 12.835636 -64.683555) (xy 12.835636 -65.953555) (xy 13.139156 -65.953555)
			(xy 13.139156 -65.872445) (xy 13.147106 -65.791726) (xy 13.162929 -65.712175) (xy 13.186474 -65.634559)
			(xy 13.217513 -65.559623) (xy 13.255748 -65.488091) (xy 13.30081 -65.420651) (xy 13.352265 -65.357952)
			(xy 13.409618 -65.300599) (xy 13.472317 -65.249144) (xy 13.539757 -65.204082) (xy 13.611289 -65.165847)
			(xy 13.686225 -65.134808) (xy 13.763841 -65.111263) (xy 13.843392 -65.09544) (xy 13.924111 -65.08749)
			(xy 14.005221 -65.08749) (xy 14.08594 -65.09544) (xy 14.165491 -65.111263) (xy 14.243107 -65.134808)
			(xy 14.318043 -65.165847) (xy 14.389575 -65.204082) (xy 14.457015 -65.249144) (xy 14.519714 -65.300599)
			(xy 14.577067 -65.357952) (xy 14.628522 -65.420651) (xy 14.673584 -65.488091) (xy 14.711819 -65.559623)
			(xy 14.742858 -65.634559) (xy 14.766403 -65.712175) (xy 14.782226 -65.791726) (xy 14.790176 -65.872445)
			(xy 14.790674 -65.913) (xy 14.790176 -65.953555) (xy 14.782226 -66.034274) (xy 14.766403 -66.113825)
			(xy 14.742858 -66.191441) (xy 14.711819 -66.266377) (xy 14.673584 -66.337909) (xy 14.628522 -66.405349)
			(xy 14.577067 -66.468048) (xy 14.519714 -66.525401) (xy 14.457015 -66.576856) (xy 14.389575 -66.621918)
			(xy 14.318043 -66.660153) (xy 14.243107 -66.691192) (xy 14.165491 -66.714737) (xy 14.08594 -66.73056)
			(xy 14.005221 -66.73851) (xy 13.924111 -66.73851) (xy 13.843392 -66.73056) (xy 13.763841 -66.714737)
			(xy 13.686225 -66.691192) (xy 13.611289 -66.660153) (xy 13.539757 -66.621918) (xy 13.472317 -66.576856)
			(xy 13.409618 -66.525401) (xy 13.352265 -66.468048) (xy 13.30081 -66.405349) (xy 13.255748 -66.337909)
			(xy 13.217513 -66.266377) (xy 13.186474 -66.191441) (xy 13.162929 -66.113825) (xy 13.147106 -66.034274)
			(xy 13.139156 -65.953555) (xy 12.835636 -65.953555) (xy 12.835636 -67.223555) (xy 15.679156 -67.223555)
			(xy 15.679156 -67.142445) (xy 15.687106 -67.061726) (xy 15.702929 -66.982175) (xy 15.726474 -66.904559)
			(xy 15.757513 -66.829623) (xy 15.795748 -66.758091) (xy 15.84081 -66.690651) (xy 15.892265 -66.627952)
			(xy 15.949618 -66.570599) (xy 16.012317 -66.519144) (xy 16.079757 -66.474082) (xy 16.151289 -66.435847)
			(xy 16.226225 -66.404808) (xy 16.303841 -66.381263) (xy 16.383392 -66.36544) (xy 16.464111 -66.35749)
			(xy 16.545221 -66.35749) (xy 16.62594 -66.36544) (xy 16.705491 -66.381263) (xy 16.783107 -66.404808)
			(xy 16.858043 -66.435847) (xy 16.929575 -66.474082) (xy 16.997015 -66.519144) (xy 17.059714 -66.570599)
			(xy 17.117067 -66.627952) (xy 17.168522 -66.690651) (xy 17.213584 -66.758091) (xy 17.251819 -66.829623)
			(xy 17.282858 -66.904559) (xy 17.306403 -66.982175) (xy 17.322226 -67.061726) (xy 17.330176 -67.142445)
			(xy 17.330674 -67.183) (xy 17.330176 -67.223555) (xy 17.322226 -67.304274) (xy 17.306403 -67.383825)
			(xy 17.282858 -67.461441) (xy 17.251819 -67.536377) (xy 17.213584 -67.607909) (xy 17.168522 -67.675349)
			(xy 17.117067 -67.738048) (xy 17.059714 -67.795401) (xy 16.997015 -67.846856) (xy 16.929575 -67.891918)
			(xy 16.858043 -67.930153) (xy 16.783107 -67.961192) (xy 16.705491 -67.984737) (xy 16.62594 -68.00056)
			(xy 16.545221 -68.00851) (xy 16.464111 -68.00851) (xy 16.383392 -68.00056) (xy 16.303841 -67.984737)
			(xy 16.226225 -67.961192) (xy 16.151289 -67.930153) (xy 16.079757 -67.891918) (xy 16.012317 -67.846856)
			(xy 15.949618 -67.795401) (xy 15.892265 -67.738048) (xy 15.84081 -67.675349) (xy 15.795748 -67.607909)
			(xy 15.757513 -67.536377) (xy 15.726474 -67.461441) (xy 15.702929 -67.383825) (xy 15.687106 -67.304274)
			(xy 15.679156 -67.223555) (xy 12.835636 -67.223555) (xy 12.835636 -68.493555) (xy 13.139156 -68.493555)
			(xy 13.139156 -68.412445) (xy 13.147106 -68.331726) (xy 13.162929 -68.252175) (xy 13.186474 -68.174559)
			(xy 13.217513 -68.099623) (xy 13.255748 -68.028091) (xy 13.30081 -67.960651) (xy 13.352265 -67.897952)
			(xy 13.409618 -67.840599) (xy 13.472317 -67.789144) (xy 13.539757 -67.744082) (xy 13.611289 -67.705847)
			(xy 13.686225 -67.674808) (xy 13.763841 -67.651263) (xy 13.843392 -67.63544) (xy 13.924111 -67.62749)
			(xy 14.005221 -67.62749) (xy 14.08594 -67.63544) (xy 14.165491 -67.651263) (xy 14.243107 -67.674808)
			(xy 14.318043 -67.705847) (xy 14.389575 -67.744082) (xy 14.457015 -67.789144) (xy 14.519714 -67.840599)
			(xy 14.577067 -67.897952) (xy 14.628522 -67.960651) (xy 14.673584 -68.028091) (xy 14.711819 -68.099623)
			(xy 14.742858 -68.174559) (xy 14.766403 -68.252175) (xy 14.782226 -68.331726) (xy 14.790176 -68.412445)
			(xy 14.790674 -68.453) (xy 14.790176 -68.493555) (xy 14.782226 -68.574274) (xy 14.766403 -68.653825)
			(xy 14.742858 -68.731441) (xy 14.711819 -68.806377) (xy 14.673584 -68.877909) (xy 14.628522 -68.945349)
			(xy 14.577067 -69.008048) (xy 14.519714 -69.065401) (xy 14.457015 -69.116856) (xy 14.389575 -69.161918)
			(xy 14.318043 -69.200153) (xy 14.243107 -69.231192) (xy 14.165491 -69.254737) (xy 14.08594 -69.27056)
			(xy 14.005221 -69.27851) (xy 13.924111 -69.27851) (xy 13.843392 -69.27056) (xy 13.763841 -69.254737)
			(xy 13.686225 -69.231192) (xy 13.611289 -69.200153) (xy 13.539757 -69.161918) (xy 13.472317 -69.116856)
			(xy 13.409618 -69.065401) (xy 13.352265 -69.008048) (xy 13.30081 -68.945349) (xy 13.255748 -68.877909)
			(xy 13.217513 -68.806377) (xy 13.186474 -68.731441) (xy 13.162929 -68.653825) (xy 13.147106 -68.574274)
			(xy 13.139156 -68.493555) (xy 12.835636 -68.493555) (xy 12.835636 -69.763555) (xy 15.679156 -69.763555)
			(xy 15.679156 -69.682445) (xy 15.687106 -69.601726) (xy 15.702929 -69.522175) (xy 15.726474 -69.444559)
			(xy 15.757513 -69.369623) (xy 15.795748 -69.298091) (xy 15.84081 -69.230651) (xy 15.892265 -69.167952)
			(xy 15.949618 -69.110599) (xy 16.012317 -69.059144) (xy 16.079757 -69.014082) (xy 16.151289 -68.975847)
			(xy 16.226225 -68.944808) (xy 16.303841 -68.921263) (xy 16.383392 -68.90544) (xy 16.464111 -68.89749)
			(xy 16.545221 -68.89749) (xy 16.62594 -68.90544) (xy 16.705491 -68.921263) (xy 16.783107 -68.944808)
			(xy 16.858043 -68.975847) (xy 16.929575 -69.014082) (xy 16.997015 -69.059144) (xy 17.059714 -69.110599)
			(xy 17.117067 -69.167952) (xy 17.168522 -69.230651) (xy 17.213584 -69.298091) (xy 17.251819 -69.369623)
			(xy 17.282858 -69.444559) (xy 17.306403 -69.522175) (xy 17.322226 -69.601726) (xy 17.330176 -69.682445)
			(xy 17.330674 -69.723) (xy 17.330176 -69.763555) (xy 17.322226 -69.844274) (xy 17.306403 -69.923825)
			(xy 17.282858 -70.001441) (xy 17.251819 -70.076377) (xy 17.213584 -70.147909) (xy 17.168522 -70.215349)
			(xy 17.117067 -70.278048) (xy 17.059714 -70.335401) (xy 16.997015 -70.386856) (xy 16.929575 -70.431918)
			(xy 16.858043 -70.470153) (xy 16.783107 -70.501192) (xy 16.705491 -70.524737) (xy 16.62594 -70.54056)
			(xy 16.545221 -70.54851) (xy 16.464111 -70.54851) (xy 16.383392 -70.54056) (xy 16.303841 -70.524737)
			(xy 16.226225 -70.501192) (xy 16.151289 -70.470153) (xy 16.079757 -70.431918) (xy 16.012317 -70.386856)
			(xy 15.949618 -70.335401) (xy 15.892265 -70.278048) (xy 15.84081 -70.215349) (xy 15.795748 -70.147909)
			(xy 15.757513 -70.076377) (xy 15.726474 -70.001441) (xy 15.702929 -69.923825) (xy 15.687106 -69.844274)
			(xy 15.679156 -69.763555) (xy 12.835636 -69.763555) (xy 12.835636 -71.033555) (xy 13.139156 -71.033555)
			(xy 13.139156 -70.952445) (xy 13.147106 -70.871726) (xy 13.162929 -70.792175) (xy 13.186474 -70.714559)
			(xy 13.217513 -70.639623) (xy 13.255748 -70.568091) (xy 13.30081 -70.500651) (xy 13.352265 -70.437952)
			(xy 13.409618 -70.380599) (xy 13.472317 -70.329144) (xy 13.539757 -70.284082) (xy 13.611289 -70.245847)
			(xy 13.686225 -70.214808) (xy 13.763841 -70.191263) (xy 13.843392 -70.17544) (xy 13.924111 -70.16749)
			(xy 14.005221 -70.16749) (xy 14.08594 -70.17544) (xy 14.165491 -70.191263) (xy 14.243107 -70.214808)
			(xy 14.318043 -70.245847) (xy 14.389575 -70.284082) (xy 14.457015 -70.329144) (xy 14.519714 -70.380599)
			(xy 14.577067 -70.437952) (xy 14.628522 -70.500651) (xy 14.673584 -70.568091) (xy 14.711819 -70.639623)
			(xy 14.742858 -70.714559) (xy 14.766403 -70.792175) (xy 14.782226 -70.871726) (xy 14.790176 -70.952445)
			(xy 14.790674 -70.993) (xy 14.790176 -71.033555) (xy 14.782226 -71.114274) (xy 14.766403 -71.193825)
			(xy 14.742858 -71.271441) (xy 14.711819 -71.346377) (xy 14.673584 -71.417909) (xy 14.628522 -71.485349)
			(xy 14.577067 -71.548048) (xy 14.519714 -71.605401) (xy 14.457015 -71.656856) (xy 14.389575 -71.701918)
			(xy 14.318043 -71.740153) (xy 14.243107 -71.771192) (xy 14.165491 -71.794737) (xy 14.08594 -71.81056)
			(xy 14.005221 -71.81851) (xy 13.924111 -71.81851) (xy 13.843392 -71.81056) (xy 13.763841 -71.794737)
			(xy 13.686225 -71.771192) (xy 13.611289 -71.740153) (xy 13.539757 -71.701918) (xy 13.472317 -71.656856)
			(xy 13.409618 -71.605401) (xy 13.352265 -71.548048) (xy 13.30081 -71.485349) (xy 13.255748 -71.417909)
			(xy 13.217513 -71.346377) (xy 13.186474 -71.271441) (xy 13.162929 -71.193825) (xy 13.147106 -71.114274)
			(xy 13.139156 -71.033555) (xy 12.835636 -71.033555) (xy 12.835636 -72.193404) (xy 15.920212 -75.278234)
			(xy 15.920212 -88.764618) (xy 12.79652 -91.88831) (xy 12.79652 -96.687555) (xy 15.679156 -96.687555)
			(xy 15.679156 -96.606445) (xy 15.687106 -96.525726) (xy 15.702929 -96.446175) (xy 15.726474 -96.368559)
			(xy 15.757513 -96.293623) (xy 15.795748 -96.222091) (xy 15.84081 -96.154651) (xy 15.892265 -96.091952)
			(xy 15.949618 -96.034599) (xy 16.012317 -95.983144) (xy 16.079757 -95.938082) (xy 16.151289 -95.899847)
			(xy 16.226225 -95.868808) (xy 16.303841 -95.845263) (xy 16.383392 -95.82944) (xy 16.464111 -95.82149)
			(xy 16.545221 -95.82149) (xy 16.62594 -95.82944) (xy 16.705491 -95.845263) (xy 16.783107 -95.868808)
			(xy 16.858043 -95.899847) (xy 16.929575 -95.938082) (xy 16.997015 -95.983144) (xy 17.059714 -96.034599)
			(xy 17.117067 -96.091952) (xy 17.168522 -96.154651) (xy 17.213584 -96.222091) (xy 17.251819 -96.293623)
			(xy 17.282858 -96.368559) (xy 17.306403 -96.446175) (xy 17.322226 -96.525726) (xy 17.330176 -96.606445)
			(xy 17.330674 -96.647) (xy 17.330176 -96.687555) (xy 17.322226 -96.768274) (xy 17.306403 -96.847825)
			(xy 17.282858 -96.925441) (xy 17.251819 -97.000377) (xy 17.213584 -97.071909) (xy 17.168522 -97.139349)
			(xy 17.117067 -97.202048) (xy 17.059714 -97.259401) (xy 16.997015 -97.310856) (xy 16.929575 -97.355918)
			(xy 16.858043 -97.394153) (xy 16.783107 -97.425192) (xy 16.705491 -97.448737) (xy 16.62594 -97.46456)
			(xy 16.545221 -97.47251) (xy 16.464111 -97.47251) (xy 16.383392 -97.46456) (xy 16.303841 -97.448737)
			(xy 16.226225 -97.425192) (xy 16.151289 -97.394153) (xy 16.079757 -97.355918) (xy 16.012317 -97.310856)
			(xy 15.949618 -97.259401) (xy 15.892265 -97.202048) (xy 15.84081 -97.139349) (xy 15.795748 -97.071909)
			(xy 15.757513 -97.000377) (xy 15.726474 -96.925441) (xy 15.702929 -96.847825) (xy 15.687106 -96.768274)
			(xy 15.679156 -96.687555) (xy 12.79652 -96.687555) (xy 12.79652 -97.957555) (xy 13.139156 -97.957555)
			(xy 13.139156 -97.876445) (xy 13.147106 -97.795726) (xy 13.162929 -97.716175) (xy 13.186474 -97.638559)
			(xy 13.217513 -97.563623) (xy 13.255748 -97.492091) (xy 13.30081 -97.424651) (xy 13.352265 -97.361952)
			(xy 13.409618 -97.304599) (xy 13.472317 -97.253144) (xy 13.539757 -97.208082) (xy 13.611289 -97.169847)
			(xy 13.686225 -97.138808) (xy 13.763841 -97.115263) (xy 13.843392 -97.09944) (xy 13.924111 -97.09149)
			(xy 14.005221 -97.09149) (xy 14.08594 -97.09944) (xy 14.165491 -97.115263) (xy 14.243107 -97.138808)
			(xy 14.318043 -97.169847) (xy 14.389575 -97.208082) (xy 14.457015 -97.253144) (xy 14.519714 -97.304599)
			(xy 14.577067 -97.361952) (xy 14.628522 -97.424651) (xy 14.673584 -97.492091) (xy 14.711819 -97.563623)
			(xy 14.742858 -97.638559) (xy 14.766403 -97.716175) (xy 14.782226 -97.795726) (xy 14.790176 -97.876445)
			(xy 14.790674 -97.917) (xy 14.790176 -97.957555) (xy 14.782226 -98.038274) (xy 14.766403 -98.117825)
			(xy 14.742858 -98.195441) (xy 14.711819 -98.270377) (xy 14.673584 -98.341909) (xy 14.628522 -98.409349)
			(xy 14.577067 -98.472048) (xy 14.519714 -98.529401) (xy 14.457015 -98.580856) (xy 14.389575 -98.625918)
			(xy 14.318043 -98.664153) (xy 14.243107 -98.695192) (xy 14.165491 -98.718737) (xy 14.08594 -98.73456)
			(xy 14.005221 -98.74251) (xy 13.924111 -98.74251) (xy 13.843392 -98.73456) (xy 13.763841 -98.718737)
			(xy 13.686225 -98.695192) (xy 13.611289 -98.664153) (xy 13.539757 -98.625918) (xy 13.472317 -98.580856)
			(xy 13.409618 -98.529401) (xy 13.352265 -98.472048) (xy 13.30081 -98.409349) (xy 13.255748 -98.341909)
			(xy 13.217513 -98.270377) (xy 13.186474 -98.195441) (xy 13.162929 -98.117825) (xy 13.147106 -98.038274)
			(xy 13.139156 -97.957555) (xy 12.79652 -97.957555) (xy 12.79652 -99.227555) (xy 15.679156 -99.227555)
			(xy 15.679156 -99.146445) (xy 15.687106 -99.065726) (xy 15.702929 -98.986175) (xy 15.726474 -98.908559)
			(xy 15.757513 -98.833623) (xy 15.795748 -98.762091) (xy 15.84081 -98.694651) (xy 15.892265 -98.631952)
			(xy 15.949618 -98.574599) (xy 16.012317 -98.523144) (xy 16.079757 -98.478082) (xy 16.151289 -98.439847)
			(xy 16.226225 -98.408808) (xy 16.303841 -98.385263) (xy 16.383392 -98.36944) (xy 16.464111 -98.36149)
			(xy 16.545221 -98.36149) (xy 16.62594 -98.36944) (xy 16.705491 -98.385263) (xy 16.783107 -98.408808)
			(xy 16.858043 -98.439847) (xy 16.929575 -98.478082) (xy 16.997015 -98.523144) (xy 17.059714 -98.574599)
			(xy 17.117067 -98.631952) (xy 17.168522 -98.694651) (xy 17.213584 -98.762091) (xy 17.251819 -98.833623)
			(xy 17.282858 -98.908559) (xy 17.306403 -98.986175) (xy 17.322226 -99.065726) (xy 17.330176 -99.146445)
			(xy 17.330674 -99.187) (xy 17.330176 -99.227555) (xy 17.322226 -99.308274) (xy 17.306403 -99.387825)
			(xy 17.282858 -99.465441) (xy 17.251819 -99.540377) (xy 17.213584 -99.611909) (xy 17.168522 -99.679349)
			(xy 17.117067 -99.742048) (xy 17.059714 -99.799401) (xy 16.997015 -99.850856) (xy 16.929575 -99.895918)
			(xy 16.858043 -99.934153) (xy 16.783107 -99.965192) (xy 16.705491 -99.988737) (xy 16.62594 -100.00456)
			(xy 16.545221 -100.01251) (xy 16.464111 -100.01251) (xy 16.383392 -100.00456) (xy 16.303841 -99.988737)
			(xy 16.226225 -99.965192) (xy 16.151289 -99.934153) (xy 16.079757 -99.895918) (xy 16.012317 -99.850856)
			(xy 15.949618 -99.799401) (xy 15.892265 -99.742048) (xy 15.84081 -99.679349) (xy 15.795748 -99.611909)
			(xy 15.757513 -99.540377) (xy 15.726474 -99.465441) (xy 15.702929 -99.387825) (xy 15.687106 -99.308274)
			(xy 15.679156 -99.227555) (xy 12.79652 -99.227555) (xy 12.79652 -100.497555) (xy 13.139156 -100.497555)
			(xy 13.139156 -100.416445) (xy 13.147106 -100.335726) (xy 13.162929 -100.256175) (xy 13.186474 -100.178559)
			(xy 13.217513 -100.103623) (xy 13.255748 -100.032091) (xy 13.30081 -99.964651) (xy 13.352265 -99.901952)
			(xy 13.409618 -99.844599) (xy 13.472317 -99.793144) (xy 13.539757 -99.748082) (xy 13.611289 -99.709847)
			(xy 13.686225 -99.678808) (xy 13.763841 -99.655263) (xy 13.843392 -99.63944) (xy 13.924111 -99.63149)
			(xy 14.005221 -99.63149) (xy 14.08594 -99.63944) (xy 14.165491 -99.655263) (xy 14.243107 -99.678808)
			(xy 14.318043 -99.709847) (xy 14.389575 -99.748082) (xy 14.457015 -99.793144) (xy 14.519714 -99.844599)
			(xy 14.577067 -99.901952) (xy 14.628522 -99.964651) (xy 14.673584 -100.032091) (xy 14.711819 -100.103623)
			(xy 14.742858 -100.178559) (xy 14.766403 -100.256175) (xy 14.782226 -100.335726) (xy 14.790176 -100.416445)
			(xy 14.790674 -100.457) (xy 14.790176 -100.497555) (xy 14.782226 -100.578274) (xy 14.766403 -100.657825)
			(xy 14.742858 -100.735441) (xy 14.711819 -100.810377) (xy 14.673584 -100.881909) (xy 14.628522 -100.949349)
			(xy 14.577067 -101.012048) (xy 14.519714 -101.069401) (xy 14.457015 -101.120856) (xy 14.389575 -101.165918)
			(xy 14.318043 -101.204153) (xy 14.243107 -101.235192) (xy 14.165491 -101.258737) (xy 14.08594 -101.27456)
			(xy 14.005221 -101.28251) (xy 13.924111 -101.28251) (xy 13.843392 -101.27456) (xy 13.763841 -101.258737)
			(xy 13.686225 -101.235192) (xy 13.611289 -101.204153) (xy 13.539757 -101.165918) (xy 13.472317 -101.120856)
			(xy 13.409618 -101.069401) (xy 13.352265 -101.012048) (xy 13.30081 -100.949349) (xy 13.255748 -100.881909)
			(xy 13.217513 -100.810377) (xy 13.186474 -100.735441) (xy 13.162929 -100.657825) (xy 13.147106 -100.578274)
			(xy 13.139156 -100.497555) (xy 12.79652 -100.497555) (xy 12.79652 -101.767555) (xy 15.679156 -101.767555)
			(xy 15.679156 -101.686445) (xy 15.687106 -101.605726) (xy 15.702929 -101.526175) (xy 15.726474 -101.448559)
			(xy 15.757513 -101.373623) (xy 15.795748 -101.302091) (xy 15.84081 -101.234651) (xy 15.892265 -101.171952)
			(xy 15.949618 -101.114599) (xy 16.012317 -101.063144) (xy 16.079757 -101.018082) (xy 16.151289 -100.979847)
			(xy 16.226225 -100.948808) (xy 16.303841 -100.925263) (xy 16.383392 -100.90944) (xy 16.464111 -100.90149)
			(xy 16.545221 -100.90149) (xy 16.62594 -100.90944) (xy 16.705491 -100.925263) (xy 16.783107 -100.948808)
			(xy 16.858043 -100.979847) (xy 16.929575 -101.018082) (xy 16.997015 -101.063144) (xy 17.059714 -101.114599)
			(xy 17.117067 -101.171952) (xy 17.168522 -101.234651) (xy 17.213584 -101.302091) (xy 17.251819 -101.373623)
			(xy 17.282858 -101.448559) (xy 17.306403 -101.526175) (xy 17.322226 -101.605726) (xy 17.330176 -101.686445)
			(xy 17.330674 -101.727) (xy 17.330176 -101.767555) (xy 17.322226 -101.848274) (xy 17.306403 -101.927825)
			(xy 17.282858 -102.005441) (xy 17.251819 -102.080377) (xy 17.213584 -102.151909) (xy 17.168522 -102.219349)
			(xy 17.117067 -102.282048) (xy 17.059714 -102.339401) (xy 16.997015 -102.390856) (xy 16.929575 -102.435918)
			(xy 16.858043 -102.474153) (xy 16.783107 -102.505192) (xy 16.705491 -102.528737) (xy 16.62594 -102.54456)
			(xy 16.545221 -102.55251) (xy 16.464111 -102.55251) (xy 16.383392 -102.54456) (xy 16.303841 -102.528737)
			(xy 16.226225 -102.505192) (xy 16.151289 -102.474153) (xy 16.079757 -102.435918) (xy 16.012317 -102.390856)
			(xy 15.949618 -102.339401) (xy 15.892265 -102.282048) (xy 15.84081 -102.219349) (xy 15.795748 -102.151909)
			(xy 15.757513 -102.080377) (xy 15.726474 -102.005441) (xy 15.702929 -101.927825) (xy 15.687106 -101.848274)
			(xy 15.679156 -101.767555) (xy 12.79652 -101.767555) (xy 12.79652 -103.037555) (xy 13.139156 -103.037555)
			(xy 13.139156 -102.956445) (xy 13.147106 -102.875726) (xy 13.162929 -102.796175) (xy 13.186474 -102.718559)
			(xy 13.217513 -102.643623) (xy 13.255748 -102.572091) (xy 13.30081 -102.504651) (xy 13.352265 -102.441952)
			(xy 13.409618 -102.384599) (xy 13.472317 -102.333144) (xy 13.539757 -102.288082) (xy 13.611289 -102.249847)
			(xy 13.686225 -102.218808) (xy 13.763841 -102.195263) (xy 13.843392 -102.17944) (xy 13.924111 -102.17149)
			(xy 14.005221 -102.17149) (xy 14.08594 -102.17944) (xy 14.165491 -102.195263) (xy 14.243107 -102.218808)
			(xy 14.318043 -102.249847) (xy 14.389575 -102.288082) (xy 14.457015 -102.333144) (xy 14.519714 -102.384599)
			(xy 14.577067 -102.441952) (xy 14.628522 -102.504651) (xy 14.673584 -102.572091) (xy 14.711819 -102.643623)
			(xy 14.742858 -102.718559) (xy 14.766403 -102.796175) (xy 14.782226 -102.875726) (xy 14.790176 -102.956445)
			(xy 14.790674 -102.997) (xy 14.790176 -103.037555) (xy 14.782226 -103.118274) (xy 14.766403 -103.197825)
			(xy 14.742858 -103.275441) (xy 14.711819 -103.350377) (xy 14.673584 -103.421909) (xy 14.628522 -103.489349)
			(xy 14.577067 -103.552048) (xy 14.519714 -103.609401) (xy 14.457015 -103.660856) (xy 14.389575 -103.705918)
			(xy 14.318043 -103.744153) (xy 14.243107 -103.775192) (xy 14.165491 -103.798737) (xy 14.08594 -103.81456)
			(xy 14.005221 -103.82251) (xy 13.924111 -103.82251) (xy 13.843392 -103.81456) (xy 13.763841 -103.798737)
			(xy 13.686225 -103.775192) (xy 13.611289 -103.744153) (xy 13.539757 -103.705918) (xy 13.472317 -103.660856)
			(xy 13.409618 -103.609401) (xy 13.352265 -103.552048) (xy 13.30081 -103.489349) (xy 13.255748 -103.421909)
			(xy 13.217513 -103.350377) (xy 13.186474 -103.275441) (xy 13.162929 -103.197825) (xy 13.147106 -103.118274)
			(xy 13.139156 -103.037555) (xy 12.79652 -103.037555) (xy 12.79652 -104.307555) (xy 15.679156 -104.307555)
			(xy 15.679156 -104.226445) (xy 15.687106 -104.145726) (xy 15.702929 -104.066175) (xy 15.726474 -103.988559)
			(xy 15.757513 -103.913623) (xy 15.795748 -103.842091) (xy 15.84081 -103.774651) (xy 15.892265 -103.711952)
			(xy 15.949618 -103.654599) (xy 16.012317 -103.603144) (xy 16.079757 -103.558082) (xy 16.151289 -103.519847)
			(xy 16.226225 -103.488808) (xy 16.303841 -103.465263) (xy 16.383392 -103.44944) (xy 16.464111 -103.44149)
			(xy 16.545221 -103.44149) (xy 16.62594 -103.44944) (xy 16.705491 -103.465263) (xy 16.783107 -103.488808)
			(xy 16.858043 -103.519847) (xy 16.929575 -103.558082) (xy 16.997015 -103.603144) (xy 17.059714 -103.654599)
			(xy 17.117067 -103.711952) (xy 17.168522 -103.774651) (xy 17.213584 -103.842091) (xy 17.251819 -103.913623)
			(xy 17.282858 -103.988559) (xy 17.306403 -104.066175) (xy 17.322226 -104.145726) (xy 17.330176 -104.226445)
			(xy 17.330674 -104.267) (xy 17.330176 -104.307555) (xy 17.322226 -104.388274) (xy 17.306403 -104.467825)
			(xy 17.282858 -104.545441) (xy 17.251819 -104.620377) (xy 17.213584 -104.691909) (xy 17.168522 -104.759349)
			(xy 17.117067 -104.822048) (xy 17.059714 -104.879401) (xy 16.997015 -104.930856) (xy 16.929575 -104.975918)
			(xy 16.858043 -105.014153) (xy 16.783107 -105.045192) (xy 16.705491 -105.068737) (xy 16.62594 -105.08456)
			(xy 16.545221 -105.09251) (xy 16.464111 -105.09251) (xy 16.383392 -105.08456) (xy 16.303841 -105.068737)
			(xy 16.226225 -105.045192) (xy 16.151289 -105.014153) (xy 16.079757 -104.975918) (xy 16.012317 -104.930856)
			(xy 15.949618 -104.879401) (xy 15.892265 -104.822048) (xy 15.84081 -104.759349) (xy 15.795748 -104.691909)
			(xy 15.757513 -104.620377) (xy 15.726474 -104.545441) (xy 15.702929 -104.467825) (xy 15.687106 -104.388274)
			(xy 15.679156 -104.307555) (xy 12.79652 -104.307555) (xy 12.79652 -105.30586) (xy 12.93876 -105.4481)
			(xy 12.950892 -105.459561) (xy 12.979771 -105.47627) (xy 13.011994 -105.484921) (xy 13.045358 -105.484921)
			(xy 13.077581 -105.47627) (xy 13.10646 -105.459561) (xy 13.118592 -105.4481) (xy 13.146024 -105.420414)
			(xy 13.15339 -105.38206) (xy 13.161635 -105.3416) (xy 13.185155 -105.262442) (xy 13.216454 -105.186026)
			(xy 13.25522 -105.113113) (xy 13.301067 -105.044432) (xy 13.353537 -104.980666) (xy 13.412106 -104.922454)
			(xy 13.47619 -104.870374) (xy 13.54515 -104.824947) (xy 13.618298 -104.786626) (xy 13.694903 -104.755793)
			(xy 13.774203 -104.732757) (xy 13.855405 -104.717746) (xy 13.937699 -104.71091) (xy 14.020265 -104.712319)
			(xy 14.102278 -104.721957) (xy 14.14272 -104.730296) (xy 14.177587 -104.738421) (xy 14.245881 -104.759918)
			(xy 14.279118 -104.773222) (xy 14.31658 -104.789172) (xy 14.388461 -104.827427) (xy 14.456228 -104.87257)
			(xy 14.519224 -104.924162) (xy 14.576837 -104.981703) (xy 14.628508 -105.044635) (xy 14.673735 -105.112346)
			(xy 14.712079 -105.184179) (xy 14.743168 -105.259437) (xy 14.7667 -105.337388) (xy 14.782447 -105.417278)
			(xy 14.790256 -105.498329) (xy 14.79005 -105.579755) (xy 14.781833 -105.660766) (xy 14.765683 -105.740575)
			(xy 14.741758 -105.818407) (xy 14.71029 -105.893507) (xy 14.671584 -105.965145) (xy 14.626016 -106.032627)
			(xy 14.574028 -106.095297) (xy 14.516126 -106.152547) (xy 14.45287 -106.203821) (xy 14.384876 -106.248622)
			(xy 14.312803 -106.286513) (xy 14.237351 -106.317128) (xy 14.159253 -106.34017) (xy 14.119352 -106.348276)
			(xy 14.1022 -106.352142) (xy 14.070799 -106.367931) (xy 14.044894 -106.391685) (xy 14.026449 -106.421603)
			(xy 14.016861 -106.455417) (xy 14.016228 -106.47299) (xy 14.016228 -112.109504) (xy 10.653776 -115.471702)
			(xy 10.64243 -115.483851) (xy 10.625847 -115.512648) (xy 10.617259 -115.544749) (xy 10.616692 -115.561364)
			(xy 10.616692 -118.09984) (xy 11.345418 -118.09984) (xy 11.345925 -117.99666) (xy 11.354026 -117.790459)
			(xy 11.370217 -117.584735) (xy 11.394472 -117.379805) (xy 11.426754 -117.175985) (xy 11.467013 -116.97359)
			(xy 11.515187 -116.772931) (xy 11.571201 -116.574319) (xy 11.63497 -116.378059) (xy 11.706395 -116.184453)
			(xy 11.785365 -115.993801) (xy 11.87176 -115.806397) (xy 11.965446 -115.622528) (xy 12.066278 -115.44248)
			(xy 12.174101 -115.266529) (xy 12.288748 -115.094946) (xy 12.410044 -114.927998) (xy 12.5378 -114.765939)
			(xy 12.671821 -114.609022) (xy 12.811898 -114.457487) (xy 12.957817 -114.311568) (xy 13.109352 -114.171491)
			(xy 13.266269 -114.03747) (xy 13.428328 -113.909714) (xy 13.595276 -113.788418) (xy 13.766859 -113.673771)
			(xy 13.94281 -113.565948) (xy 14.122858 -113.465116) (xy 14.306727 -113.37143) (xy 14.494131 -113.285035)
			(xy 14.684783 -113.206065) (xy 14.878389 -113.13464) (xy 15.074649 -113.070871) (xy 15.273261 -113.014857)
			(xy 15.47392 -112.966683) (xy 15.676315 -112.926424) (xy 15.880135 -112.894142) (xy 16.085065 -112.869887)
			(xy 16.290789 -112.853696) (xy 16.49699 -112.845595) (xy 16.60017 -112.845088) (xy 16.703348 -112.845592)
			(xy 16.909546 -112.853694) (xy 17.115267 -112.869885) (xy 17.320193 -112.89414) (xy 17.524009 -112.926422)
			(xy 17.726401 -112.966682) (xy 17.927055 -113.014856) (xy 18.125664 -113.070872) (xy 18.32192 -113.134641)
			(xy 18.515522 -113.206067) (xy 18.70617 -113.285039) (xy 18.89357 -113.371434) (xy 19.077434 -113.465121)
			(xy 19.257478 -113.565954) (xy 19.433424 -113.673778) (xy 19.605002 -113.788427) (xy 19.771945 -113.909723)
			(xy 19.933998 -114.037481) (xy 20.09091 -114.171502) (xy 20.24244 -114.311581) (xy 20.388352 -114.457501)
			(xy 20.528424 -114.609037) (xy 20.662438 -114.765955) (xy 20.790187 -114.928014) (xy 20.911476 -115.094964)
			(xy 21.026117 -115.266546) (xy 21.133932 -115.442498) (xy 21.234757 -115.622547) (xy 21.328435 -115.806415)
			(xy 21.414822 -115.993819) (xy 21.493784 -116.184471) (xy 21.565201 -116.378076) (xy 21.628961 -116.574335)
			(xy 21.684967 -116.772947) (xy 21.733132 -116.973604) (xy 21.773381 -117.175997) (xy 21.805654 -117.379815)
			(xy 21.8299 -117.584742) (xy 21.846081 -117.790464) (xy 21.854173 -117.996662) (xy 21.854668 -118.09984)
			(xy 21.854183 -118.201745) (xy 21.846285 -118.405403) (xy 21.830496 -118.608602) (xy 21.806839 -118.811035)
			(xy 21.775351 -119.012399) (xy 21.736078 -119.21239) (xy 21.68908 -119.410708) (xy 21.634428 -119.607055)
			(xy 21.572203 -119.801135) (xy 21.502499 -119.992655) (xy 21.425421 -120.181329) (xy 21.341085 -120.366873)
			(xy 21.249618 -120.549006) (xy 21.151158 -120.727456) (xy 21.045851 -120.901954) (xy 20.933858 -121.072237)
			(xy 20.815346 -121.23805) (xy 20.690494 -121.399142) (xy 20.559489 -121.555272) (xy 20.422528 -121.706205)
			(xy 20.279818 -121.851713) (xy 20.131573 -121.991579) (xy 19.978016 -122.12559) (xy 19.819378 -122.253547)
			(xy 19.655898 -122.375256) (xy 19.487821 -122.490534) (xy 19.315401 -122.599209) (xy 19.138896 -122.701116)
			(xy 18.958573 -122.796102) (xy 18.774702 -122.884024) (xy 18.58756 -122.964751) (xy 18.397428 -123.03816)
			(xy 18.204593 -123.104141) (xy 18.009345 -123.162596) (xy 17.811977 -123.213436) (xy 17.612786 -123.256584)
			(xy 17.412071 -123.291976) (xy 17.210135 -123.319558) (xy 17.007282 -123.33929) (xy 16.803816 -123.35114)
			(xy 16.600043 -123.355093) (xy 16.39627 -123.35114) (xy 16.192804 -123.33929) (xy 15.989951 -123.319558)
			(xy 15.788015 -123.291976) (xy 15.5873 -123.256584) (xy 15.388109 -123.213436) (xy 15.190741 -123.162596)
			(xy 14.995493 -123.104141) (xy 14.802658 -123.03816) (xy 14.612526 -122.964751) (xy 14.425384 -122.884024)
			(xy 14.241513 -122.796102) (xy 14.06119 -122.701116) (xy 13.884685 -122.599209) (xy 13.712265 -122.490534)
			(xy 13.544188 -122.375256) (xy 13.380708 -122.253547) (xy 13.22207 -122.12559) (xy 13.068513 -121.991579)
			(xy 12.920268 -121.851713) (xy 12.777558 -121.706205) (xy 12.640597 -121.555272) (xy 12.509592 -121.399142)
			(xy 12.38474 -121.23805) (xy 12.266228 -121.072237) (xy 12.154235 -120.901954) (xy 12.048928 -120.727456)
			(xy 11.950468 -120.549006) (xy 11.859001 -120.366873) (xy 11.774665 -120.181329) (xy 11.697587 -119.992655)
			(xy 11.627883 -119.801135) (xy 11.565658 -119.607055) (xy 11.511006 -119.410708) (xy 11.464008 -119.21239)
			(xy 11.424735 -119.012399) (xy 11.393247 -118.811035) (xy 11.36959 -118.608602) (xy 11.353801 -118.405403)
			(xy 11.345903 -118.201745) (xy 11.345418 -118.09984) (xy 10.616692 -118.09984) (xy 10.616692 -120.543066)
			(xy 21.317712 -131.244086) (xy 21.317712 -168.399206) (xy 21.332428 -168.417635) (xy 21.367463 -168.449197)
			(xy 21.407722 -168.473751) (xy 21.45182 -168.490453) (xy 21.498244 -168.498731) (xy 21.545397 -168.498299)
			(xy 21.591661 -168.489172) (xy 21.635446 -168.471665) (xy 21.675248 -168.446377) (xy 21.69287 -168.430702)
			(xy 22.498304 -167.625268) (xy 22.498304 -106.688636) (xy 21.530056 -105.720388) (xy 21.530056 -91.046808)
			(xy 22.754844 -89.821766) (xy 23.773384 -88.803226) (xy 23.773384 -25.68448) (xy 27.094688 -22.363176)
			(xy 27.110796 -22.346333) (xy 27.137194 -22.307933) (xy 27.156146 -22.265361) (xy 27.167017 -22.220048)
			(xy 27.169441 -22.173512) (xy 27.163337 -22.127314) (xy 27.14891 -22.083004) (xy 27.126645 -22.042069)
			(xy 27.097287 -22.00588) (xy 27.061822 -21.975653) (xy 27.041856 -21.963634) (xy 27.018245 -21.949497)
			(xy 26.974979 -21.915489) (xy 26.937048 -21.875618) (xy 26.905239 -21.830711) (xy 26.880211 -21.781701)
			(xy 26.862484 -21.729603) (xy 26.852425 -21.675498) (xy 26.850244 -21.62051) (xy 26.855985 -21.565779)
			(xy 26.86953 -21.512441) (xy 26.890597 -21.461602) (xy 26.918749 -21.414316) (xy 26.953403 -21.371566)
			(xy 26.993839 -21.334238) (xy 27.039218 -21.303106) (xy 27.088599 -21.278817) (xy 27.140957 -21.261874)
			(xy 27.195206 -21.252629) (xy 27.250221 -21.251273) (xy 27.304859 -21.257835) (xy 27.357988 -21.272179)
			(xy 27.408506 -21.294007) (xy 27.455363 -21.322866) (xy 27.497588 -21.358157) (xy 27.534305 -21.399149)
			(xy 27.549856 -21.421852) (xy 27.563826 -21.442934) (xy 27.653234 -21.503132) (xy 27.678126 -21.508212)
			(xy 27.70309 -21.513652) (xy 27.751385 -21.530327) (xy 27.797019 -21.553306) (xy 27.818334 -21.567394)
			(xy 27.838565 -21.564141) (xy 27.877689 -21.55197) (xy 27.914352 -21.533677) (xy 27.947604 -21.509737)
			(xy 27.962352 -21.495512) (xy 28.766008 -20.691856) (xy 28.766008 -18.53438) (xy 29.19349 -18.106644)
			(xy 29.547058 -17.753076) (xy 29.557585 -17.741939) (xy 29.573493 -17.715758) (xy 29.582689 -17.686535)
			(xy 29.584639 -17.655962) (xy 29.582364 -17.640808) (xy 29.578046 -17.61744) (xy 29.57449 -17.607534)
			(xy 29.560408 -17.566845) (xy 29.538865 -17.483474) (xy 29.525034 -17.398483) (xy 29.51903 -17.312584)
			(xy 29.520904 -17.226495) (xy 29.530641 -17.140938) (xy 29.548158 -17.05663) (xy 29.573309 -16.974276)
			(xy 29.605884 -16.894566) (xy 29.645609 -16.818168) (xy 29.692152 -16.745721) (xy 29.745123 -16.677832)
			(xy 29.804078 -16.615071) (xy 29.868524 -16.557961) (xy 29.937921 -16.506982) (xy 30.011688 -16.462561)
			(xy 30.089206 -16.42507) (xy 30.169828 -16.394822) (xy 30.252877 -16.372071) (xy 30.337658 -16.357007)
			(xy 30.423461 -16.349757) (xy 30.509568 -16.350381) (xy 30.595257 -16.358875) (xy 30.679811 -16.375166)
			(xy 30.762522 -16.399119) (xy 30.842696 -16.430533) (xy 30.919663 -16.469144) (xy 30.992778 -16.51463)
			(xy 31.061428 -16.56661) (xy 31.125039 -16.624648) (xy 31.183078 -16.688258) (xy 31.235059 -16.756907)
			(xy 31.280547 -16.830021) (xy 31.31916 -16.906988) (xy 31.350575 -16.987161) (xy 31.37453 -17.069871)
			(xy 31.390823 -17.154425) (xy 31.399318 -17.240114) (xy 31.399944 -17.326221) (xy 31.392695 -17.412024)
			(xy 31.377633 -17.496806) (xy 31.354884 -17.579855) (xy 31.324637 -17.660477) (xy 31.287147 -17.737997)
			(xy 31.242727 -17.811764) (xy 31.19175 -17.881162) (xy 31.134642 -17.945609) (xy 31.071881 -18.004566)
			(xy 31.003994 -18.057538) (xy 30.931548 -18.104082) (xy 30.85515 -18.143809) (xy 30.775441 -18.176385)
			(xy 30.693088 -18.201537) (xy 30.608779 -18.219056) (xy 30.523223 -18.228794) (xy 30.437134 -18.23067)
			(xy 30.351235 -18.224669) (xy 30.266243 -18.210839) (xy 30.182872 -18.189298) (xy 30.14218 -18.175224)
			(xy 30.132274 -18.171668) (xy 30.108906 -18.16735) (xy 30.093751 -18.165111) (xy 30.063189 -18.167077)
			(xy 30.033976 -18.176269) (xy 30.007795 -18.192157) (xy 29.996638 -18.202656) (xy 29.438854 -18.76044)
			(xy 29.427987 -18.771862) (xy 29.411737 -18.798866) (xy 29.402652 -18.829044) (xy 29.401516 -18.844768)
			(xy 29.401516 -18.968212) (xy 29.40397 -18.991432) (xy 29.416253 -19.036474) (xy 29.436548 -19.078519)
			(xy 29.464174 -19.116155) (xy 29.498203 -19.148118) (xy 29.537493 -19.173336) (xy 29.580724 -19.190962)
			(xy 29.626446 -19.200404) (xy 29.673123 -19.201346) (xy 29.719189 -19.193754) (xy 29.763096 -19.177886)
			(xy 29.80337 -19.154272) (xy 29.821378 -19.139408) (xy 29.853574 -19.110327) (xy 29.922445 -19.057553)
			(xy 29.995884 -19.011347) (xy 30.073267 -18.972103) (xy 30.153936 -18.940154) (xy 30.237205 -18.915772)
			(xy 30.322366 -18.899163) (xy 30.408695 -18.89047) (xy 30.495458 -18.889767) (xy 30.581916 -18.897058)
			(xy 30.667336 -18.912283) (xy 30.750989 -18.935311) (xy 30.832166 -18.965948) (xy 30.910176 -19.003931)
			(xy 30.984354 -19.04894) (xy 31.054072 -19.10059) (xy 31.118735 -19.158442) (xy 31.177794 -19.222005)
			(xy 31.230747 -19.290738) (xy 31.277144 -19.364057) (xy 31.316589 -19.441337) (xy 31.348748 -19.521923)
			(xy 31.373347 -19.605129) (xy 31.390177 -19.690246) (xy 31.399094 -19.776552) (xy 31.400023 -19.863313)
			(xy 31.392957 -19.94979) (xy 31.377954 -20.035249) (xy 31.355143 -20.118962) (xy 31.324718 -20.200218)
			(xy 31.306262 -20.239482) (xy 31.297377 -20.259199) (xy 31.285706 -20.300838) (xy 31.281259 -20.343853)
			(xy 31.284165 -20.386999) (xy 31.29434 -20.429029) (xy 31.311489 -20.468727) (xy 31.335118 -20.504945)
			(xy 31.364541 -20.536635) (xy 31.381446 -20.550124) (xy 32.182054 -20.550124) (xy 32.667956 -20.064222)
			(xy 32.667956 -17.094962) (xy 34.603944 -15.159228) (xy 34.615292 -15.147079) (xy 34.631879 -15.118283)
			(xy 34.640472 -15.086182) (xy 34.641028 -15.069566) (xy 34.641028 -15.027402) (xy 34.635948 -15.01013)
			(xy 34.624397 -14.968249) (xy 34.608137 -14.8829) (xy 34.59982 -14.796416) (xy 34.599517 -14.709532)
			(xy 34.607231 -14.622992) (xy 34.622897 -14.537532) (xy 34.64638 -14.453882) (xy 34.67748 -14.372755)
			(xy 34.715932 -14.294844) (xy 34.761408 -14.220812) (xy 34.813521 -14.151292) (xy 34.871824 -14.086875)
			(xy 34.935823 -14.028113) (xy 35.004969 -13.975506) (xy 35.078674 -13.929502) (xy 35.156309 -13.890494)
			(xy 35.237212 -13.858815) (xy 35.320692 -13.834735) (xy 35.406037 -13.81846) (xy 35.492521 -13.810128)
			(xy 35.579404 -13.80981) (xy 35.665946 -13.817509) (xy 35.751408 -13.83316) (xy 35.835062 -13.856628)
			(xy 35.916195 -13.887714) (xy 35.994113 -13.926153) (xy 36.031424 -13.94841) (xy 36.06859 -13.9718)
			(xy 36.138847 -14.024495) (xy 36.203884 -14.083512) (xy 36.263135 -14.148335) (xy 36.316084 -14.218401)
			(xy 36.362269 -14.293099) (xy 36.401288 -14.371777) (xy 36.417126 -14.412976) (xy 40.863518 -14.412976)
			(xy 40.867589 -14.357354) (xy 40.879715 -14.302917) (xy 40.899638 -14.250826) (xy 40.926934 -14.202191)
			(xy 40.96102 -14.158048) (xy 41.001169 -14.119339) (xy 41.046527 -14.086888) (xy 41.096127 -14.061387)
			(xy 41.148911 -14.04338) (xy 41.203754 -14.03325) (xy 41.259488 -14.031213) (xy 41.314925 -14.037313)
			(xy 41.368882 -14.051419) (xy 41.420211 -14.073231) (xy 41.467817 -14.102285) (xy 41.510685 -14.13796)
			(xy 41.547902 -14.179497) (xy 41.578675 -14.22601) (xy 41.602347 -14.276507) (xy 41.618415 -14.329914)
			(xy 41.626535 -14.38509) (xy 41.627044 -14.412976) (xy 41.626535 -14.440862) (xy 41.621118 -14.477672)
			(xy 60.058738 -14.477672) (xy 60.062629 -14.423327) (xy 60.074215 -14.370089) (xy 60.093259 -14.319041)
			(xy 60.119375 -14.271223) (xy 60.15203 -14.227609) (xy 60.190559 -14.189086) (xy 60.234179 -14.156439)
			(xy 60.282001 -14.130332) (xy 60.333052 -14.111296) (xy 60.386293 -14.09972) (xy 60.440639 -14.095838)
			(xy 60.494984 -14.099731) (xy 60.548222 -14.111318) (xy 60.599269 -14.130364) (xy 60.647086 -14.15648)
			(xy 60.66917 -14.172438) (xy 60.688182 -14.186034) (xy 60.730065 -14.206766) (xy 60.775033 -14.219492)
			(xy 60.82157 -14.223782) (xy 60.868107 -14.219492) (xy 60.913075 -14.206766) (xy 60.954958 -14.186034)
			(xy 60.97397 -14.172438) (xy 60.996016 -14.156413) (xy 61.043846 -14.130282) (xy 61.094909 -14.111224)
			(xy 61.148164 -14.099628) (xy 61.202527 -14.095729) (xy 61.256892 -14.099607) (xy 61.310152 -14.111183)
			(xy 61.361222 -14.130222) (xy 61.409062 -14.156335) (xy 61.452699 -14.188991) (xy 61.491243 -14.227526)
			(xy 61.523911 -14.271154) (xy 61.550037 -14.318987) (xy 61.569089 -14.370052) (xy 61.580679 -14.423308)
			(xy 61.584571 -14.477672) (xy 61.962748 -14.477672) (xy 61.966639 -14.423329) (xy 61.978223 -14.370093)
			(xy 61.997267 -14.319047) (xy 62.023381 -14.271231) (xy 62.056034 -14.227619) (xy 62.094562 -14.189097)
			(xy 62.138179 -14.15645) (xy 62.185999 -14.130343) (xy 62.237048 -14.111307) (xy 62.290286 -14.09973)
			(xy 62.344629 -14.095848) (xy 62.398973 -14.099739) (xy 62.452209 -14.111324) (xy 62.503254 -14.130368)
			(xy 62.55107 -14.156482) (xy 62.573154 -14.172438) (xy 62.592166 -14.186034) (xy 62.634049 -14.206766)
			(xy 62.679017 -14.219492) (xy 62.725554 -14.223782) (xy 62.772091 -14.219492) (xy 62.817059 -14.206766)
			(xy 62.858942 -14.186034) (xy 62.877954 -14.172438) (xy 62.9 -14.156412) (xy 62.947832 -14.130278)
			(xy 62.998896 -14.111218) (xy 63.052153 -14.099619) (xy 63.106518 -14.095719) (xy 63.160885 -14.099596)
			(xy 63.214147 -14.111172) (xy 63.26522 -14.13021) (xy 63.313062 -14.156324) (xy 63.356701 -14.188981)
			(xy 63.395248 -14.227516) (xy 63.427917 -14.271146) (xy 63.454044 -14.318981) (xy 63.473097 -14.370048)
			(xy 63.484688 -14.423306) (xy 63.488581 -14.477672) (xy 63.484696 -14.532039) (xy 63.473113 -14.585299)
			(xy 63.454067 -14.636369) (xy 63.427947 -14.684208) (xy 63.395284 -14.727842) (xy 63.356743 -14.766383)
			(xy 63.313109 -14.799047) (xy 63.26527 -14.825167) (xy 63.2142 -14.844213) (xy 63.16094 -14.855796)
			(xy 63.106573 -14.859681) (xy 63.052207 -14.855788) (xy 62.998949 -14.844198) (xy 62.947882 -14.825145)
			(xy 62.900047 -14.799018) (xy 62.877954 -14.783054) (xy 62.858942 -14.769458) (xy 62.817059 -14.748726)
			(xy 62.772091 -14.736) (xy 62.725554 -14.73171) (xy 62.679017 -14.736) (xy 62.634049 -14.748726)
			(xy 62.592166 -14.769458) (xy 62.573154 -14.783054) (xy 62.551024 -14.798948) (xy 62.503204 -14.825055)
			(xy 62.452156 -14.844092) (xy 62.398918 -14.855669) (xy 62.344574 -14.859552) (xy 62.290231 -14.855662)
			(xy 62.236995 -14.844077) (xy 62.185949 -14.825034) (xy 62.138133 -14.79892) (xy 62.09452 -14.766267)
			(xy 62.055998 -14.72774) (xy 62.023351 -14.684122) (xy 61.997244 -14.636302) (xy 61.978208 -14.585254)
			(xy 61.966631 -14.532016) (xy 61.962748 -14.477672) (xy 61.584571 -14.477672) (xy 61.580687 -14.532037)
			(xy 61.569104 -14.585295) (xy 61.55006 -14.636363) (xy 61.523941 -14.6842) (xy 61.491279 -14.727833)
			(xy 61.45274 -14.766373) (xy 61.409108 -14.799035) (xy 61.361272 -14.825155) (xy 61.310205 -14.844201)
			(xy 61.256947 -14.855785) (xy 61.202582 -14.859671) (xy 61.148218 -14.85578) (xy 61.094962 -14.844192)
			(xy 61.043896 -14.825141) (xy 60.996062 -14.799016) (xy 60.97397 -14.783054) (xy 60.954958 -14.769458)
			(xy 60.913075 -14.748726) (xy 60.868107 -14.736) (xy 60.82157 -14.73171) (xy 60.775033 -14.736) (xy 60.730065 -14.748726)
			(xy 60.688182 -14.769458) (xy 60.66917 -14.783054) (xy 60.647039 -14.798949) (xy 60.599219 -14.825059)
			(xy 60.548169 -14.844098) (xy 60.494929 -14.855677) (xy 60.440583 -14.859562) (xy 60.386238 -14.855672)
			(xy 60.332999 -14.844088) (xy 60.281951 -14.825045) (xy 60.234133 -14.798931) (xy 60.190517 -14.766278)
			(xy 60.151993 -14.727749) (xy 60.119345 -14.68413) (xy 60.093236 -14.636309) (xy 60.074199 -14.585258)
			(xy 60.062621 -14.532018) (xy 60.058738 -14.477672) (xy 41.621118 -14.477672) (xy 41.618415 -14.496038)
			(xy 41.602347 -14.549445) (xy 41.578675 -14.599942) (xy 41.547902 -14.646455) (xy 41.510685 -14.687992)
			(xy 41.467817 -14.723667) (xy 41.420211 -14.752721) (xy 41.368882 -14.774533) (xy 41.314925 -14.788639)
			(xy 41.259488 -14.794739) (xy 41.203754 -14.792702) (xy 41.148911 -14.782572) (xy 41.096127 -14.764565)
			(xy 41.046527 -14.739064) (xy 41.001169 -14.706613) (xy 40.96102 -14.667904) (xy 40.926934 -14.623761)
			(xy 40.899638 -14.575126) (xy 40.879715 -14.523035) (xy 40.867589 -14.468598) (xy 40.863518 -14.412976)
			(xy 36.417126 -14.412976) (xy 36.432801 -14.453751) (xy 36.456533 -14.538306) (xy 36.472278 -14.624706)
			(xy 36.479898 -14.712197) (xy 36.479328 -14.800017) (xy 36.470571 -14.887402) (xy 36.453705 -14.97359)
			(xy 36.428876 -15.057829) (xy 36.3963 -15.139387) (xy 36.356262 -15.217551) (xy 36.30911 -15.291642)
			(xy 36.255255 -15.361014) (xy 36.195167 -15.425062) (xy 36.129368 -15.483228) (xy 36.058433 -15.535006)
			(xy 35.982978 -15.579944) (xy 35.903663 -15.617651) (xy 35.821177 -15.647798) (xy 35.736239 -15.670123)
			(xy 35.64959 -15.68443) (xy 35.561984 -15.690597) (xy 35.474186 -15.688567) (xy 35.386958 -15.678361)
			(xy 35.301063 -15.660065) (xy 35.25901 -15.647416) (xy 35.242307 -15.642822) (xy 35.207694 -15.641782)
			(xy 35.174075 -15.650077) (xy 35.143919 -15.667097) (xy 35.131248 -15.678912) (xy 33.47692 -17.333484)
			(xy 34.599874 -17.333484) (xy 34.599874 -17.246584) (xy 34.607892 -17.160055) (xy 34.62386 -17.074635)
			(xy 34.647641 -16.991053) (xy 34.679033 -16.910021) (xy 34.717767 -16.832232) (xy 34.763514 -16.758348)
			(xy 34.815883 -16.689001) (xy 34.874427 -16.624781) (xy 34.938647 -16.566237) (xy 35.007994 -16.513868)
			(xy 35.081878 -16.468121) (xy 35.159667 -16.429387) (xy 35.240699 -16.397995) (xy 35.324281 -16.374214)
			(xy 35.409701 -16.358246) (xy 35.49623 -16.350228) (xy 35.58313 -16.350228) (xy 35.669659 -16.358246)
			(xy 35.755079 -16.374214) (xy 35.770884 -16.378711) (xy 60.058687 -16.378711) (xy 60.062573 -16.324358)
			(xy 60.074155 -16.271111) (xy 60.093197 -16.220055) (xy 60.119311 -16.172228) (xy 60.151966 -16.128605)
			(xy 60.190497 -16.090073) (xy 60.234119 -16.057416) (xy 60.281945 -16.031301) (xy 60.333001 -16.012258)
			(xy 60.386247 -16.000674) (xy 60.4406 -15.996787) (xy 60.494953 -16.000675) (xy 60.548199 -16.012258)
			(xy 60.599255 -16.031301) (xy 60.647081 -16.057417) (xy 60.66917 -16.073374) (xy 60.688182 -16.08697)
			(xy 60.730065 -16.107702) (xy 60.775033 -16.120428) (xy 60.82157 -16.124718) (xy 60.868107 -16.120428)
			(xy 60.913075 -16.107702) (xy 60.954958 -16.08697) (xy 60.97397 -16.073374) (xy 60.996076 -16.057436)
			(xy 61.043902 -16.031313) (xy 61.09496 -16.012262) (xy 61.148209 -16.000673) (xy 61.202566 -15.99678)
			(xy 61.256923 -16.000663) (xy 61.310174 -16.012243) (xy 61.361235 -16.031284) (xy 61.409067 -16.057399)
			(xy 61.452694 -16.090055) (xy 61.49123 -16.128588) (xy 61.523889 -16.172214) (xy 61.550006 -16.220043)
			(xy 61.56905 -16.271103) (xy 61.580634 -16.324354) (xy 61.58452 -16.378711) (xy 61.962697 -16.378711)
			(xy 61.966582 -16.32436) (xy 61.978163 -16.271115) (xy 61.997204 -16.220061) (xy 62.023317 -16.172236)
			(xy 62.05597 -16.128614) (xy 62.094499 -16.090083) (xy 62.138119 -16.057428) (xy 62.185943 -16.031312)
			(xy 62.236996 -16.012269) (xy 62.29024 -16.000685) (xy 62.344591 -15.996797) (xy 62.398942 -16.000683)
			(xy 62.452186 -16.012264) (xy 62.503241 -16.031305) (xy 62.551066 -16.057418) (xy 62.573154 -16.073374)
			(xy 62.592166 -16.08697) (xy 62.634049 -16.107702) (xy 62.679017 -16.120428) (xy 62.725554 -16.124718)
			(xy 62.772091 -16.120428) (xy 62.817059 -16.107702) (xy 62.858942 -16.08697) (xy 62.877954 -16.073374)
			(xy 62.90006 -16.057434) (xy 62.947888 -16.031309) (xy 62.998947 -16.012256) (xy 63.052198 -16.000665)
			(xy 63.106557 -15.99677) (xy 63.160916 -16.000652) (xy 63.21417 -16.012232) (xy 63.265233 -16.031273)
			(xy 63.313067 -16.057387) (xy 63.356697 -16.090045) (xy 63.395234 -16.128579) (xy 63.427895 -16.172206)
			(xy 63.454014 -16.220037) (xy 63.473059 -16.271099) (xy 63.484643 -16.324352) (xy 63.48853 -16.378711)
			(xy 63.48464 -16.43307) (xy 63.473053 -16.486322) (xy 63.454005 -16.537383) (xy 63.427883 -16.585212)
			(xy 63.39522 -16.628838) (xy 63.35668 -16.66737) (xy 63.313049 -16.700024) (xy 63.265214 -16.726136)
			(xy 63.214149 -16.745174) (xy 63.160895 -16.756751) (xy 63.106535 -16.76063) (xy 63.052177 -16.756732)
			(xy 62.998926 -16.745138) (xy 62.947868 -16.726082) (xy 62.900042 -16.699954) (xy 62.877954 -16.68399)
			(xy 62.858942 -16.670394) (xy 62.817059 -16.649662) (xy 62.772091 -16.636936) (xy 62.725554 -16.632646)
			(xy 62.679017 -16.636936) (xy 62.634049 -16.649662) (xy 62.592166 -16.670394) (xy 62.573154 -16.68399)
			(xy 62.551084 -16.69997) (xy 62.50326 -16.726086) (xy 62.452207 -16.74513) (xy 62.398963 -16.756714)
			(xy 62.344613 -16.760603) (xy 62.290262 -16.756718) (xy 62.237017 -16.745137) (xy 62.185963 -16.726097)
			(xy 62.138138 -16.699984) (xy 62.094515 -16.667331) (xy 62.055984 -16.628802) (xy 62.023329 -16.585182)
			(xy 61.997213 -16.537359) (xy 61.97817 -16.486305) (xy 61.966585 -16.433061) (xy 61.962697 -16.378711)
			(xy 61.58452 -16.378711) (xy 61.580631 -16.433068) (xy 61.569044 -16.486318) (xy 61.549997 -16.537376)
			(xy 61.523877 -16.585204) (xy 61.491215 -16.628828) (xy 61.452678 -16.667359) (xy 61.409048 -16.700013)
			(xy 61.361216 -16.726125) (xy 61.310154 -16.745163) (xy 61.256902 -16.75674) (xy 61.202544 -16.76062)
			(xy 61.148188 -16.756724) (xy 61.094939 -16.745132) (xy 61.043883 -16.726078) (xy 60.996058 -16.699953)
			(xy 60.97397 -16.68399) (xy 60.954958 -16.670394) (xy 60.913075 -16.649662) (xy 60.868107 -16.636936)
			(xy 60.82157 -16.632646) (xy 60.775033 -16.636936) (xy 60.730065 -16.649662) (xy 60.688182 -16.670394)
			(xy 60.66917 -16.68399) (xy 60.647099 -16.699972) (xy 60.599275 -16.72609) (xy 60.54822 -16.745136)
			(xy 60.494974 -16.756722) (xy 60.440622 -16.760613) (xy 60.386269 -16.756729) (xy 60.333022 -16.745148)
			(xy 60.281965 -16.726108) (xy 60.234137 -16.699995) (xy 60.190513 -16.667342) (xy 60.15198 -16.628812)
			(xy 60.119322 -16.58519) (xy 60.093205 -16.537365) (xy 60.074161 -16.48631) (xy 60.062576 -16.433064)
			(xy 60.058687 -16.378711) (xy 35.770884 -16.378711) (xy 35.838661 -16.397995) (xy 35.919693 -16.429387)
			(xy 35.997482 -16.468121) (xy 36.071366 -16.513868) (xy 36.140713 -16.566237) (xy 36.204933 -16.624781)
			(xy 36.263477 -16.689001) (xy 36.315846 -16.758348) (xy 36.361593 -16.832232) (xy 36.400327 -16.910021)
			(xy 36.431719 -16.991053) (xy 36.4555 -17.074635) (xy 36.471468 -17.160055) (xy 36.479486 -17.246584)
			(xy 36.479988 -17.290034) (xy 36.479815 -17.30502) (xy 40.914826 -17.30502) (xy 40.918897 -17.249398)
			(xy 40.931023 -17.194961) (xy 40.950946 -17.14287) (xy 40.978242 -17.094235) (xy 41.012328 -17.050092)
			(xy 41.052477 -17.011383) (xy 41.097835 -16.978932) (xy 41.147435 -16.953431) (xy 41.200219 -16.935424)
			(xy 41.255062 -16.925294) (xy 41.310796 -16.923257) (xy 41.366233 -16.929357) (xy 41.42019 -16.943463)
			(xy 41.471519 -16.965275) (xy 41.519125 -16.994329) (xy 41.561993 -17.030004) (xy 41.59921 -17.071541)
			(xy 41.629983 -17.118054) (xy 41.653655 -17.168551) (xy 41.669723 -17.221958) (xy 41.677843 -17.277134)
			(xy 41.678352 -17.30502) (xy 41.677843 -17.332906) (xy 41.669723 -17.388082) (xy 41.653655 -17.441489)
			(xy 41.629983 -17.491986) (xy 41.59921 -17.538499) (xy 41.561993 -17.580036) (xy 41.519125 -17.615711)
			(xy 41.471519 -17.644765) (xy 41.42019 -17.666577) (xy 41.366233 -17.680683) (xy 41.310796 -17.686783)
			(xy 41.255062 -17.684746) (xy 41.200219 -17.674616) (xy 41.147435 -17.656609) (xy 41.097835 -17.631108)
			(xy 41.052477 -17.598657) (xy 41.012328 -17.559948) (xy 40.978242 -17.515805) (xy 40.950946 -17.46717)
			(xy 40.931023 -17.415079) (xy 40.918897 -17.360642) (xy 40.914826 -17.30502) (xy 36.479815 -17.30502)
			(xy 36.479486 -17.333484) (xy 36.471468 -17.420013) (xy 36.4555 -17.505433) (xy 36.431719 -17.589015)
			(xy 36.400327 -17.670047) (xy 36.361593 -17.747836) (xy 36.315846 -17.82172) (xy 36.263477 -17.891067)
			(xy 36.204933 -17.955287) (xy 36.140713 -18.013831) (xy 36.071366 -18.0662) (xy 35.997482 -18.111947)
			(xy 35.919693 -18.150681) (xy 35.838661 -18.182073) (xy 35.755079 -18.205854) (xy 35.669659 -18.221822)
			(xy 35.58313 -18.22984) (xy 35.49623 -18.22984) (xy 35.409701 -18.221822) (xy 35.324281 -18.205854)
			(xy 35.240699 -18.182073) (xy 35.159667 -18.150681) (xy 35.081878 -18.111947) (xy 35.007994 -18.0662)
			(xy 34.938647 -18.013831) (xy 34.874427 -17.955287) (xy 34.815883 -17.891067) (xy 34.763514 -17.82172)
			(xy 34.717767 -17.747836) (xy 34.679033 -17.670047) (xy 34.647641 -17.589015) (xy 34.62386 -17.505433)
			(xy 34.607892 -17.420013) (xy 34.599874 -17.333484) (xy 33.47692 -17.333484) (xy 33.40862 -17.401794)
			(xy 33.40862 -18.414238) (xy 40.70045 -18.414238) (xy 40.704521 -18.358616) (xy 40.716647 -18.304179)
			(xy 40.73657 -18.252088) (xy 40.763866 -18.203453) (xy 40.797952 -18.15931) (xy 40.838101 -18.120601)
			(xy 40.883459 -18.08815) (xy 40.933059 -18.062649) (xy 40.985843 -18.044642) (xy 41.040686 -18.034512)
			(xy 41.09642 -18.032475) (xy 41.151857 -18.038575) (xy 41.205814 -18.052681) (xy 41.257143 -18.074493)
			(xy 41.304749 -18.103547) (xy 41.347617 -18.139222) (xy 41.384834 -18.180759) (xy 41.415607 -18.227272)
			(xy 41.439279 -18.277769) (xy 41.455347 -18.331176) (xy 41.463467 -18.386352) (xy 41.463976 -18.414238)
			(xy 41.463467 -18.442124) (xy 41.455347 -18.4973) (xy 41.439279 -18.550707) (xy 41.415607 -18.601204)
			(xy 41.4103 -18.609225) (xy 47.374038 -18.609225) (xy 47.374038 -18.528115) (xy 47.381988 -18.447396)
			(xy 47.397811 -18.367845) (xy 47.421356 -18.290229) (xy 47.452395 -18.215293) (xy 47.49063 -18.143761)
			(xy 47.535692 -18.076321) (xy 47.587147 -18.013622) (xy 47.6445 -17.956269) (xy 47.707199 -17.904814)
			(xy 47.774639 -17.859752) (xy 47.846171 -17.821517) (xy 47.921107 -17.790478) (xy 47.998723 -17.766933)
			(xy 48.078274 -17.75111) (xy 48.158993 -17.74316) (xy 48.240103 -17.74316) (xy 48.320822 -17.75111)
			(xy 48.400373 -17.766933) (xy 48.477989 -17.790478) (xy 48.552925 -17.821517) (xy 48.624457 -17.859752)
			(xy 48.691897 -17.904814) (xy 48.754596 -17.956269) (xy 48.811949 -18.013622) (xy 48.863404 -18.076321)
			(xy 48.908466 -18.143761) (xy 48.946701 -18.215293) (xy 48.97774 -18.290229) (xy 49.001285 -18.367845)
			(xy 49.017108 -18.447396) (xy 49.025058 -18.528115) (xy 49.025556 -18.56867) (xy 49.025058 -18.609225)
			(xy 50.874158 -18.609225) (xy 50.874158 -18.528115) (xy 50.882108 -18.447396) (xy 50.897931 -18.367845)
			(xy 50.921476 -18.290229) (xy 50.952515 -18.215293) (xy 50.99075 -18.143761) (xy 51.035812 -18.076321)
			(xy 51.087267 -18.013622) (xy 51.14462 -17.956269) (xy 51.207319 -17.904814) (xy 51.274759 -17.859752)
			(xy 51.346291 -17.821517) (xy 51.421227 -17.790478) (xy 51.498843 -17.766933) (xy 51.578394 -17.75111)
			(xy 51.659113 -17.74316) (xy 51.740223 -17.74316) (xy 51.820942 -17.75111) (xy 51.900493 -17.766933)
			(xy 51.978109 -17.790478) (xy 52.053045 -17.821517) (xy 52.124577 -17.859752) (xy 52.192017 -17.904814)
			(xy 52.254716 -17.956269) (xy 52.312069 -18.013622) (xy 52.345036 -18.053793) (xy 60.058711 -18.053793)
			(xy 60.062599 -17.999443) (xy 60.074183 -17.946201) (xy 60.093226 -17.895148) (xy 60.119341 -17.847326)
			(xy 60.151996 -17.803707) (xy 60.190526 -17.765179) (xy 60.234147 -17.732527) (xy 60.281971 -17.706415)
			(xy 60.333025 -17.687376) (xy 60.386269 -17.675796) (xy 60.440618 -17.671911) (xy 60.494967 -17.675801)
			(xy 60.54821 -17.687386) (xy 60.599262 -17.70643) (xy 60.647083 -17.732547) (xy 60.66917 -17.748504)
			(xy 60.688182 -17.7621) (xy 60.730065 -17.782832) (xy 60.775033 -17.795558) (xy 60.82157 -17.799848)
			(xy 60.868107 -17.795558) (xy 60.913075 -17.782832) (xy 60.954958 -17.7621) (xy 60.97397 -17.748504)
			(xy 60.996048 -17.732525) (xy 61.043876 -17.706398) (xy 61.094936 -17.687344) (xy 61.148188 -17.675752)
			(xy 61.202548 -17.671856) (xy 61.256909 -17.675737) (xy 61.310164 -17.687315) (xy 61.361229 -17.706355)
			(xy 61.409064 -17.732469) (xy 61.452696 -17.765125) (xy 61.491236 -17.803659) (xy 61.523899 -17.847286)
			(xy 61.55002 -17.895117) (xy 61.569068 -17.946179) (xy 61.580655 -17.999432) (xy 61.584544 -18.053793)
			(xy 61.962721 -18.053793) (xy 61.966609 -17.999446) (xy 61.978192 -17.946205) (xy 61.997234 -17.895155)
			(xy 62.023347 -17.847334) (xy 62.056 -17.803716) (xy 62.094528 -17.765189) (xy 62.138147 -17.732538)
			(xy 62.185969 -17.706427) (xy 62.237021 -17.687387) (xy 62.290262 -17.675806) (xy 62.344609 -17.671921)
			(xy 62.398956 -17.675809) (xy 62.452197 -17.687392) (xy 62.503247 -17.706434) (xy 62.551068 -17.732548)
			(xy 62.573154 -17.748504) (xy 62.592166 -17.7621) (xy 62.634049 -17.782832) (xy 62.679017 -17.795558)
			(xy 62.725554 -17.799848) (xy 62.772091 -17.795558) (xy 62.817059 -17.782832) (xy 62.858942 -17.7621)
			(xy 62.877954 -17.748504) (xy 62.900032 -17.732524) (xy 62.947861 -17.706394) (xy 62.998923 -17.687338)
			(xy 63.052177 -17.675743) (xy 63.106539 -17.671846) (xy 63.160902 -17.675726) (xy 63.214159 -17.687304)
			(xy 63.265227 -17.706343) (xy 63.313065 -17.732458) (xy 63.356699 -17.765115) (xy 63.39524 -17.803649)
			(xy 63.427905 -17.847278) (xy 63.454028 -17.895111) (xy 63.473077 -17.946175) (xy 63.484664 -17.99943)
			(xy 63.488554 -18.053793) (xy 63.484666 -18.108155) (xy 63.473081 -18.161411) (xy 63.454034 -18.212476)
			(xy 63.427913 -18.26031) (xy 63.39525 -18.30394) (xy 63.35671 -18.342476) (xy 63.313077 -18.375135)
			(xy 63.26524 -18.401251) (xy 63.214173 -18.420292) (xy 63.160916 -18.431872) (xy 63.106553 -18.435754)
			(xy 63.052191 -18.431859) (xy 62.998937 -18.420266) (xy 62.947874 -18.401212) (xy 62.900044 -18.375084)
			(xy 62.877954 -18.35912) (xy 62.858942 -18.345524) (xy 62.817059 -18.324792) (xy 62.772091 -18.312066)
			(xy 62.725554 -18.307776) (xy 62.679017 -18.312066) (xy 62.634049 -18.324792) (xy 62.592166 -18.345524)
			(xy 62.573154 -18.35912) (xy 62.551056 -18.37506) (xy 62.503234 -18.401172) (xy 62.452183 -18.420212)
			(xy 62.398942 -18.431793) (xy 62.344595 -18.435679) (xy 62.290247 -18.431792) (xy 62.237007 -18.420209)
			(xy 62.185956 -18.401167) (xy 62.138135 -18.375054) (xy 62.094518 -18.342401) (xy 62.055991 -18.303873)
			(xy 62.023339 -18.260254) (xy 61.997228 -18.212432) (xy 61.978188 -18.161381) (xy 61.966607 -18.10814)
			(xy 61.962721 -18.053793) (xy 61.584544 -18.053793) (xy 61.580657 -18.108153) (xy 61.569072 -18.161407)
			(xy 61.550026 -18.21247) (xy 61.523907 -18.260302) (xy 61.491245 -18.30393) (xy 61.452707 -18.342465)
			(xy 61.409076 -18.375123) (xy 61.361242 -18.401239) (xy 61.310178 -18.420281) (xy 61.256923 -18.431861)
			(xy 61.202562 -18.435744) (xy 61.148202 -18.43185) (xy 61.09495 -18.42026) (xy 61.043889 -18.401208)
			(xy 60.99606 -18.375082) (xy 60.97397 -18.35912) (xy 60.954958 -18.345524) (xy 60.913075 -18.324792)
			(xy 60.868107 -18.312066) (xy 60.82157 -18.307776) (xy 60.775033 -18.312066) (xy 60.730065 -18.324792)
			(xy 60.688182 -18.345524) (xy 60.66917 -18.35912) (xy 60.647071 -18.375061) (xy 60.599249 -18.401176)
			(xy 60.548196 -18.420218) (xy 60.494953 -18.431801) (xy 60.440604 -18.435689) (xy 60.386254 -18.431802)
			(xy 60.333011 -18.42022) (xy 60.281958 -18.401179) (xy 60.234135 -18.375065) (xy 60.190515 -18.342412)
			(xy 60.151986 -18.303882) (xy 60.119333 -18.260262) (xy 60.09322 -18.212439) (xy 60.074179 -18.161386)
			(xy 60.062597 -18.108142) (xy 60.058711 -18.053793) (xy 52.345036 -18.053793) (xy 52.363524 -18.076321)
			(xy 52.408586 -18.143761) (xy 52.446821 -18.215293) (xy 52.47786 -18.290229) (xy 52.501405 -18.367845)
			(xy 52.517228 -18.447396) (xy 52.525178 -18.528115) (xy 52.525676 -18.56867) (xy 52.525178 -18.609225)
			(xy 52.517228 -18.689944) (xy 52.501405 -18.769495) (xy 52.47786 -18.847111) (xy 52.446821 -18.922047)
			(xy 52.408586 -18.993579) (xy 52.363524 -19.061019) (xy 52.312069 -19.123718) (xy 52.254716 -19.181071)
			(xy 52.192017 -19.232526) (xy 52.124577 -19.277588) (xy 52.053045 -19.315823) (xy 51.978109 -19.346862)
			(xy 51.900493 -19.370407) (xy 51.820942 -19.38623) (xy 51.740223 -19.39418) (xy 51.659113 -19.39418)
			(xy 51.578394 -19.38623) (xy 51.498843 -19.370407) (xy 51.421227 -19.346862) (xy 51.346291 -19.315823)
			(xy 51.274759 -19.277588) (xy 51.207319 -19.232526) (xy 51.14462 -19.181071) (xy 51.087267 -19.123718)
			(xy 51.035812 -19.061019) (xy 50.99075 -18.993579) (xy 50.952515 -18.922047) (xy 50.921476 -18.847111)
			(xy 50.897931 -18.769495) (xy 50.882108 -18.689944) (xy 50.874158 -18.609225) (xy 49.025058 -18.609225)
			(xy 49.017108 -18.689944) (xy 49.001285 -18.769495) (xy 48.97774 -18.847111) (xy 48.946701 -18.922047)
			(xy 48.908466 -18.993579) (xy 48.863404 -19.061019) (xy 48.811949 -19.123718) (xy 48.754596 -19.181071)
			(xy 48.691897 -19.232526) (xy 48.624457 -19.277588) (xy 48.552925 -19.315823) (xy 48.477989 -19.346862)
			(xy 48.400373 -19.370407) (xy 48.320822 -19.38623) (xy 48.240103 -19.39418) (xy 48.158993 -19.39418)
			(xy 48.078274 -19.38623) (xy 47.998723 -19.370407) (xy 47.921107 -19.346862) (xy 47.846171 -19.315823)
			(xy 47.774639 -19.277588) (xy 47.707199 -19.232526) (xy 47.6445 -19.181071) (xy 47.587147 -19.123718)
			(xy 47.535692 -19.061019) (xy 47.49063 -18.993579) (xy 47.452395 -18.922047) (xy 47.421356 -18.847111)
			(xy 47.397811 -18.769495) (xy 47.381988 -18.689944) (xy 47.374038 -18.609225) (xy 41.4103 -18.609225)
			(xy 41.384834 -18.647717) (xy 41.347617 -18.689254) (xy 41.304749 -18.724929) (xy 41.257143 -18.753983)
			(xy 41.205814 -18.775795) (xy 41.151857 -18.789901) (xy 41.09642 -18.796001) (xy 41.040686 -18.793964)
			(xy 40.985843 -18.783834) (xy 40.933059 -18.765827) (xy 40.883459 -18.740326) (xy 40.838101 -18.707875)
			(xy 40.797952 -18.669166) (xy 40.763866 -18.625023) (xy 40.73657 -18.576388) (xy 40.716647 -18.524297)
			(xy 40.704521 -18.46986) (xy 40.70045 -18.414238) (xy 33.40862 -18.414238) (xy 33.40862 -19.873484)
			(xy 34.599874 -19.873484) (xy 34.599874 -19.786584) (xy 34.607892 -19.700055) (xy 34.62386 -19.614635)
			(xy 34.647641 -19.531053) (xy 34.679033 -19.450021) (xy 34.717767 -19.372232) (xy 34.763514 -19.298348)
			(xy 34.815883 -19.229001) (xy 34.874427 -19.164781) (xy 34.938647 -19.106237) (xy 35.007994 -19.053868)
			(xy 35.081878 -19.008121) (xy 35.159667 -18.969387) (xy 35.240699 -18.937995) (xy 35.324281 -18.914214)
			(xy 35.409701 -18.898246) (xy 35.49623 -18.890228) (xy 35.58313 -18.890228) (xy 35.669659 -18.898246)
			(xy 35.755079 -18.914214) (xy 35.838661 -18.937995) (xy 35.919693 -18.969387) (xy 35.997482 -19.008121)
			(xy 36.071366 -19.053868) (xy 36.140713 -19.106237) (xy 36.204933 -19.164781) (xy 36.263477 -19.229001)
			(xy 36.315846 -19.298348) (xy 36.361593 -19.372232) (xy 36.400327 -19.450021) (xy 36.431719 -19.531053)
			(xy 36.4555 -19.614635) (xy 36.471468 -19.700055) (xy 36.479486 -19.786584) (xy 36.479988 -19.830034)
			(xy 36.479486 -19.873484) (xy 36.471468 -19.960013) (xy 36.4555 -20.045433) (xy 36.44993 -20.06501)
			(xy 60.015149 -20.06501) (xy 60.019036 -20.010648) (xy 60.030621 -19.957393) (xy 60.049667 -19.906329)
			(xy 60.075787 -19.858495) (xy 60.108449 -19.814866) (xy 60.146988 -19.77633) (xy 60.19062 -19.743671)
			(xy 60.238455 -19.717555) (xy 60.289521 -19.698512) (xy 60.342777 -19.686932) (xy 60.397139 -19.683049)
			(xy 60.4515 -19.686943) (xy 60.504754 -19.698534) (xy 60.555816 -19.717587) (xy 60.603646 -19.743713)
			(xy 60.625736 -19.759676) (xy 60.644748 -19.773272) (xy 60.686631 -19.794004) (xy 60.731599 -19.80673)
			(xy 60.778136 -19.81102) (xy 60.824673 -19.80673) (xy 60.869641 -19.794004) (xy 60.911524 -19.773272)
			(xy 60.930536 -19.759676) (xy 60.952638 -19.743741) (xy 61.00046 -19.717628) (xy 61.051512 -19.698587)
			(xy 61.104754 -19.687005) (xy 61.159102 -19.683118) (xy 61.21345 -19.687005) (xy 61.266692 -19.698588)
			(xy 61.317743 -19.717629) (xy 61.365565 -19.743743) (xy 61.409184 -19.776396) (xy 61.447711 -19.814925)
			(xy 61.480363 -19.858545) (xy 61.506475 -19.906367) (xy 61.525516 -19.957419) (xy 61.537096 -20.010661)
			(xy 61.540982 -20.06501) (xy 61.919159 -20.06501) (xy 61.923045 -20.01065) (xy 61.934629 -19.957397)
			(xy 61.953674 -19.906335) (xy 61.979793 -19.858503) (xy 62.012453 -19.814875) (xy 62.050991 -19.77634)
			(xy 62.09462 -19.743682) (xy 62.142453 -19.717566) (xy 62.193516 -19.698524) (xy 62.24677 -19.686943)
			(xy 62.30113 -19.683059) (xy 62.355489 -19.686951) (xy 62.408741 -19.69854) (xy 62.459801 -19.717591)
			(xy 62.50763 -19.743714) (xy 62.52972 -19.759676) (xy 62.548732 -19.773272) (xy 62.590615 -19.794004)
			(xy 62.635583 -19.80673) (xy 62.68212 -19.81102) (xy 62.728657 -19.80673) (xy 62.773625 -19.794004)
			(xy 62.815508 -19.773272) (xy 62.83452 -19.759676) (xy 62.856623 -19.743739) (xy 62.904446 -19.717624)
			(xy 62.955499 -19.69858) (xy 63.008743 -19.686997) (xy 63.063093 -19.683108) (xy 63.117443 -19.686995)
			(xy 63.170687 -19.698576) (xy 63.221741 -19.717618) (xy 63.269565 -19.743732) (xy 63.313186 -19.776386)
			(xy 63.351716 -19.814916) (xy 63.38437 -19.858537) (xy 63.410483 -19.906361) (xy 63.429524 -19.957415)
			(xy 63.440878 -20.009612) (xy 75.73848 -20.009612) (xy 75.742551 -19.95399) (xy 75.754677 -19.899553)
			(xy 75.7746 -19.847462) (xy 75.801896 -19.798827) (xy 75.835982 -19.754684) (xy 75.876131 -19.715975)
			(xy 75.921489 -19.683524) (xy 75.971089 -19.658023) (xy 76.023873 -19.640016) (xy 76.078716 -19.629886)
			(xy 76.13445 -19.627849) (xy 76.189887 -19.633949) (xy 76.243844 -19.648055) (xy 76.295173 -19.669867)
			(xy 76.342779 -19.698921) (xy 76.385647 -19.734596) (xy 76.422864 -19.776133) (xy 76.453637 -19.822646)
			(xy 76.477309 -19.873143) (xy 76.493377 -19.92655) (xy 76.501497 -19.981726) (xy 76.502006 -20.009612)
			(xy 76.872336 -20.009612) (xy 76.876407 -19.95399) (xy 76.888533 -19.899553) (xy 76.908456 -19.847462)
			(xy 76.935752 -19.798827) (xy 76.969838 -19.754684) (xy 77.009987 -19.715975) (xy 77.055345 -19.683524)
			(xy 77.104945 -19.658023) (xy 77.157729 -19.640016) (xy 77.212572 -19.629886) (xy 77.268306 -19.627849)
			(xy 77.323743 -19.633949) (xy 77.3777 -19.648055) (xy 77.429029 -19.669867) (xy 77.476635 -19.698921)
			(xy 77.519503 -19.734596) (xy 77.55672 -19.776133) (xy 77.587493 -19.822646) (xy 77.611165 -19.873143)
			(xy 77.627233 -19.92655) (xy 77.635353 -19.981726) (xy 77.635862 -20.009612) (xy 78.015336 -20.009612)
			(xy 78.019407 -19.95399) (xy 78.031533 -19.899553) (xy 78.051456 -19.847462) (xy 78.078752 -19.798827)
			(xy 78.112838 -19.754684) (xy 78.152987 -19.715975) (xy 78.198345 -19.683524) (xy 78.247945 -19.658023)
			(xy 78.300729 -19.640016) (xy 78.355572 -19.629886) (xy 78.411306 -19.627849) (xy 78.466743 -19.633949)
			(xy 78.5207 -19.648055) (xy 78.572029 -19.669867) (xy 78.619635 -19.698921) (xy 78.662503 -19.734596)
			(xy 78.69972 -19.776133) (xy 78.730493 -19.822646) (xy 78.754165 -19.873143) (xy 78.770233 -19.92655)
			(xy 78.778353 -19.981726) (xy 78.778862 -20.009612) (xy 79.142588 -20.009612) (xy 79.146659 -19.95399)
			(xy 79.158785 -19.899553) (xy 79.178708 -19.847462) (xy 79.206004 -19.798827) (xy 79.24009 -19.754684)
			(xy 79.280239 -19.715975) (xy 79.325597 -19.683524) (xy 79.375197 -19.658023) (xy 79.427981 -19.640016)
			(xy 79.482824 -19.629886) (xy 79.538558 -19.627849) (xy 79.593995 -19.633949) (xy 79.647952 -19.648055)
			(xy 79.699281 -19.669867) (xy 79.746887 -19.698921) (xy 79.789755 -19.734596) (xy 79.826972 -19.776133)
			(xy 79.857745 -19.822646) (xy 79.881417 -19.873143) (xy 79.897485 -19.92655) (xy 79.905605 -19.981726)
			(xy 79.906114 -20.009612) (xy 80.28 -20.009612) (xy 80.284071 -19.95399) (xy 80.296197 -19.899553)
			(xy 80.31612 -19.847462) (xy 80.343416 -19.798827) (xy 80.377502 -19.754684) (xy 80.417651 -19.715975)
			(xy 80.463009 -19.683524) (xy 80.512609 -19.658023) (xy 80.565393 -19.640016) (xy 80.620236 -19.629886)
			(xy 80.67597 -19.627849) (xy 80.731407 -19.633949) (xy 80.785364 -19.648055) (xy 80.836693 -19.669867)
			(xy 80.884299 -19.698921) (xy 80.927167 -19.734596) (xy 80.964384 -19.776133) (xy 80.995157 -19.822646)
			(xy 81.018829 -19.873143) (xy 81.034897 -19.92655) (xy 81.043017 -19.981726) (xy 81.043526 -20.009612)
			(xy 81.407252 -20.009612) (xy 81.411323 -19.95399) (xy 81.423449 -19.899553) (xy 81.443372 -19.847462)
			(xy 81.470668 -19.798827) (xy 81.504754 -19.754684) (xy 81.544903 -19.715975) (xy 81.590261 -19.683524)
			(xy 81.639861 -19.658023) (xy 81.692645 -19.640016) (xy 81.747488 -19.629886) (xy 81.803222 -19.627849)
			(xy 81.858659 -19.633949) (xy 81.912616 -19.648055) (xy 81.963945 -19.669867) (xy 82.011551 -19.698921)
			(xy 82.054419 -19.734596) (xy 82.091636 -19.776133) (xy 82.122409 -19.822646) (xy 82.146081 -19.873143)
			(xy 82.162149 -19.92655) (xy 82.170269 -19.981726) (xy 82.170778 -20.009612) (xy 82.170269 -20.037498)
			(xy 82.162149 -20.092674) (xy 82.146081 -20.146081) (xy 82.122409 -20.196578) (xy 82.091636 -20.243091)
			(xy 82.054419 -20.284628) (xy 82.011551 -20.320303) (xy 81.963945 -20.349357) (xy 81.912616 -20.371169)
			(xy 81.858659 -20.385275) (xy 81.803222 -20.391375) (xy 81.747488 -20.389338) (xy 81.692645 -20.379208)
			(xy 81.639861 -20.361201) (xy 81.590261 -20.3357) (xy 81.544903 -20.303249) (xy 81.504754 -20.26454)
			(xy 81.470668 -20.220397) (xy 81.443372 -20.171762) (xy 81.423449 -20.119671) (xy 81.411323 -20.065234)
			(xy 81.407252 -20.009612) (xy 81.043526 -20.009612) (xy 81.043017 -20.037498) (xy 81.034897 -20.092674)
			(xy 81.018829 -20.146081) (xy 80.995157 -20.196578) (xy 80.964384 -20.243091) (xy 80.927167 -20.284628)
			(xy 80.884299 -20.320303) (xy 80.836693 -20.349357) (xy 80.785364 -20.371169) (xy 80.731407 -20.385275)
			(xy 80.67597 -20.391375) (xy 80.620236 -20.389338) (xy 80.565393 -20.379208) (xy 80.512609 -20.361201)
			(xy 80.463009 -20.3357) (xy 80.417651 -20.303249) (xy 80.377502 -20.26454) (xy 80.343416 -20.220397)
			(xy 80.31612 -20.171762) (xy 80.296197 -20.119671) (xy 80.284071 -20.065234) (xy 80.28 -20.009612)
			(xy 79.906114 -20.009612) (xy 79.905605 -20.037498) (xy 79.897485 -20.092674) (xy 79.881417 -20.146081)
			(xy 79.857745 -20.196578) (xy 79.826972 -20.243091) (xy 79.789755 -20.284628) (xy 79.746887 -20.320303)
			(xy 79.699281 -20.349357) (xy 79.647952 -20.371169) (xy 79.593995 -20.385275) (xy 79.538558 -20.391375)
			(xy 79.482824 -20.389338) (xy 79.427981 -20.379208) (xy 79.375197 -20.361201) (xy 79.325597 -20.3357)
			(xy 79.280239 -20.303249) (xy 79.24009 -20.26454) (xy 79.206004 -20.220397) (xy 79.178708 -20.171762)
			(xy 79.158785 -20.119671) (xy 79.146659 -20.065234) (xy 79.142588 -20.009612) (xy 78.778862 -20.009612)
			(xy 78.778353 -20.037498) (xy 78.770233 -20.092674) (xy 78.754165 -20.146081) (xy 78.730493 -20.196578)
			(xy 78.69972 -20.243091) (xy 78.662503 -20.284628) (xy 78.619635 -20.320303) (xy 78.572029 -20.349357)
			(xy 78.5207 -20.371169) (xy 78.466743 -20.385275) (xy 78.411306 -20.391375) (xy 78.355572 -20.389338)
			(xy 78.300729 -20.379208) (xy 78.247945 -20.361201) (xy 78.198345 -20.3357) (xy 78.152987 -20.303249)
			(xy 78.112838 -20.26454) (xy 78.078752 -20.220397) (xy 78.051456 -20.171762) (xy 78.031533 -20.119671)
			(xy 78.019407 -20.065234) (xy 78.015336 -20.009612) (xy 77.635862 -20.009612) (xy 77.635353 -20.037498)
			(xy 77.627233 -20.092674) (xy 77.611165 -20.146081) (xy 77.587493 -20.196578) (xy 77.55672 -20.243091)
			(xy 77.519503 -20.284628) (xy 77.476635 -20.320303) (xy 77.429029 -20.349357) (xy 77.3777 -20.371169)
			(xy 77.323743 -20.385275) (xy 77.268306 -20.391375) (xy 77.212572 -20.389338) (xy 77.157729 -20.379208)
			(xy 77.104945 -20.361201) (xy 77.055345 -20.3357) (xy 77.009987 -20.303249) (xy 76.969838 -20.26454)
			(xy 76.935752 -20.220397) (xy 76.908456 -20.171762) (xy 76.888533 -20.119671) (xy 76.876407 -20.065234)
			(xy 76.872336 -20.009612) (xy 76.502006 -20.009612) (xy 76.501497 -20.037498) (xy 76.493377 -20.092674)
			(xy 76.477309 -20.146081) (xy 76.453637 -20.196578) (xy 76.422864 -20.243091) (xy 76.385647 -20.284628)
			(xy 76.342779 -20.320303) (xy 76.295173 -20.349357) (xy 76.243844 -20.371169) (xy 76.189887 -20.385275)
			(xy 76.13445 -20.391375) (xy 76.078716 -20.389338) (xy 76.023873 -20.379208) (xy 75.971089 -20.361201)
			(xy 75.921489 -20.3357) (xy 75.876131 -20.303249) (xy 75.835982 -20.26454) (xy 75.801896 -20.220397)
			(xy 75.7746 -20.171762) (xy 75.754677 -20.119671) (xy 75.742551 -20.065234) (xy 75.73848 -20.009612)
			(xy 63.440878 -20.009612) (xy 63.441106 -20.010659) (xy 63.444992 -20.06501) (xy 63.441103 -20.11936)
			(xy 63.429519 -20.172603) (xy 63.410475 -20.223656) (xy 63.384359 -20.271479) (xy 63.351703 -20.315099)
			(xy 63.313172 -20.353627) (xy 63.269549 -20.386279) (xy 63.221724 -20.41239) (xy 63.170669 -20.431429)
			(xy 63.117424 -20.443008) (xy 63.063074 -20.446892) (xy 63.008724 -20.443001) (xy 62.955481 -20.431414)
			(xy 62.904428 -20.412368) (xy 62.856607 -20.38625) (xy 62.83452 -20.370292) (xy 62.815508 -20.356696)
			(xy 62.773625 -20.335964) (xy 62.728657 -20.323238) (xy 62.68212 -20.318948) (xy 62.635583 -20.323238)
			(xy 62.590615 -20.335964) (xy 62.548732 -20.356696) (xy 62.52972 -20.370292) (xy 62.507646 -20.386275)
			(xy 62.459819 -20.412401) (xy 62.408759 -20.431454) (xy 62.355508 -20.443046) (xy 62.301149 -20.446941)
			(xy 62.246789 -20.44306) (xy 62.193535 -20.431482) (xy 62.142471 -20.412442) (xy 62.094636 -20.386328)
			(xy 62.051005 -20.353672) (xy 62.012466 -20.315139) (xy 61.979803 -20.271513) (xy 61.953682 -20.223683)
			(xy 61.934635 -20.172621) (xy 61.923048 -20.119369) (xy 61.919159 -20.06501) (xy 61.540982 -20.06501)
			(xy 61.537094 -20.119358) (xy 61.52551 -20.172599) (xy 61.506467 -20.22365) (xy 61.480353 -20.271471)
			(xy 61.447699 -20.315089) (xy 61.409169 -20.353616) (xy 61.365549 -20.386267) (xy 61.317726 -20.412378)
			(xy 61.266673 -20.431418) (xy 61.213431 -20.442997) (xy 61.159083 -20.446882) (xy 61.104735 -20.442993)
			(xy 61.051494 -20.431408) (xy 61.000443 -20.412364) (xy 60.952622 -20.386249) (xy 60.930536 -20.370292)
			(xy 60.911524 -20.356696) (xy 60.869641 -20.335964) (xy 60.824673 -20.323238) (xy 60.778136 -20.318948)
			(xy 60.731599 -20.323238) (xy 60.686631 -20.335964) (xy 60.644748 -20.356696) (xy 60.625736 -20.370292)
			(xy 60.603662 -20.386277) (xy 60.555833 -20.412405) (xy 60.504772 -20.43146) (xy 60.451519 -20.443054)
			(xy 60.397158 -20.446951) (xy 60.342796 -20.443071) (xy 60.289539 -20.431493) (xy 60.238473 -20.412453)
			(xy 60.190636 -20.386339) (xy 60.147003 -20.353683) (xy 60.108461 -20.315149) (xy 60.075797 -20.271521)
			(xy 60.049675 -20.223689) (xy 60.030626 -20.172626) (xy 60.019039 -20.119371) (xy 60.015149 -20.06501)
			(xy 36.44993 -20.06501) (xy 36.431719 -20.129015) (xy 36.400327 -20.210047) (xy 36.361593 -20.287836)
			(xy 36.315846 -20.36172) (xy 36.263477 -20.431067) (xy 36.204933 -20.495287) (xy 36.140713 -20.553831)
			(xy 36.071366 -20.6062) (xy 35.997482 -20.651947) (xy 35.919693 -20.690681) (xy 35.838661 -20.722073)
			(xy 35.755079 -20.745854) (xy 35.669659 -20.761822) (xy 35.58313 -20.76984) (xy 35.49623 -20.76984)
			(xy 35.409701 -20.761822) (xy 35.324281 -20.745854) (xy 35.240699 -20.722073) (xy 35.159667 -20.690681)
			(xy 35.081878 -20.651947) (xy 35.007994 -20.6062) (xy 34.938647 -20.553831) (xy 34.874427 -20.495287)
			(xy 34.815883 -20.431067) (xy 34.763514 -20.36172) (xy 34.717767 -20.287836) (xy 34.679033 -20.210047)
			(xy 34.647641 -20.129015) (xy 34.62386 -20.045433) (xy 34.607892 -19.960013) (xy 34.599874 -19.873484)
			(xy 33.40862 -19.873484) (xy 33.40862 -20.371054) (xy 32.765746 -21.013928) (xy 74.416664 -21.013928)
			(xy 74.420735 -20.958306) (xy 74.432861 -20.903869) (xy 74.452784 -20.851778) (xy 74.48008 -20.803143)
			(xy 74.514166 -20.759) (xy 74.554315 -20.720291) (xy 74.599673 -20.68784) (xy 74.649273 -20.662339)
			(xy 74.702057 -20.644332) (xy 74.7569 -20.634202) (xy 74.812634 -20.632165) (xy 74.868071 -20.638265)
			(xy 74.922028 -20.652371) (xy 74.973357 -20.674183) (xy 75.020963 -20.703237) (xy 75.063831 -20.738912)
			(xy 75.101048 -20.780449) (xy 75.131821 -20.826962) (xy 75.155493 -20.877459) (xy 75.171561 -20.930866)
			(xy 75.179681 -20.986042) (xy 75.18019 -21.013928) (xy 75.179681 -21.041814) (xy 75.171561 -21.09699)
			(xy 75.155493 -21.150397) (xy 75.131821 -21.200894) (xy 75.101048 -21.247407) (xy 75.063831 -21.288944)
			(xy 75.020963 -21.324619) (xy 74.973357 -21.353673) (xy 74.922028 -21.375485) (xy 74.868071 -21.389591)
			(xy 74.812634 -21.395691) (xy 74.7569 -21.393654) (xy 74.702057 -21.383524) (xy 74.649273 -21.365517)
			(xy 74.599673 -21.340016) (xy 74.554315 -21.307565) (xy 74.514166 -21.268856) (xy 74.48008 -21.224713)
			(xy 74.452784 -21.176078) (xy 74.432861 -21.123987) (xy 74.420735 -21.06955) (xy 74.416664 -21.013928)
			(xy 32.765746 -21.013928) (xy 32.488886 -21.290788) (xy 31.115508 -21.290788) (xy 31.098212 -21.304613)
			(xy 31.068232 -21.337194) (xy 31.04436 -21.374481) (xy 31.027318 -21.415345) (xy 31.017624 -21.458545)
			(xy 31.015572 -21.502772) (xy 31.021223 -21.546685) (xy 31.034407 -21.588951) (xy 31.054723 -21.628289)
			(xy 31.081556 -21.663507) (xy 31.097474 -21.6789) (xy 31.129148 -21.708789) (xy 31.187425 -21.773513)
			(xy 31.239469 -21.843348) (xy 31.284831 -21.917696) (xy 31.323125 -21.99592) (xy 31.354021 -22.07735)
			(xy 31.377256 -22.161288) (xy 31.392629 -22.247014) (xy 31.400009 -22.333795) (xy 31.399391 -22.413484)
			(xy 34.599874 -22.413484) (xy 34.599874 -22.326584) (xy 34.607892 -22.240055) (xy 34.62386 -22.154635)
			(xy 34.647641 -22.071053) (xy 34.679033 -21.990021) (xy 34.717767 -21.912232) (xy 34.763514 -21.838348)
			(xy 34.815883 -21.769001) (xy 34.874427 -21.704781) (xy 34.938647 -21.646237) (xy 35.007994 -21.593868)
			(xy 35.081878 -21.548121) (xy 35.159667 -21.509387) (xy 35.240699 -21.477995) (xy 35.324281 -21.454214)
			(xy 35.409701 -21.438246) (xy 35.49623 -21.430228) (xy 35.58313 -21.430228) (xy 35.669659 -21.438246)
			(xy 35.755079 -21.454214) (xy 35.838661 -21.477995) (xy 35.919693 -21.509387) (xy 35.997482 -21.548121)
			(xy 36.071366 -21.593868) (xy 36.071962 -21.594318) (xy 39.978836 -21.594318) (xy 39.982907 -21.538696)
			(xy 39.995033 -21.484259) (xy 40.014956 -21.432168) (xy 40.042252 -21.383533) (xy 40.076338 -21.33939)
			(xy 40.116487 -21.300681) (xy 40.161845 -21.26823) (xy 40.211445 -21.242729) (xy 40.264229 -21.224722)
			(xy 40.319072 -21.214592) (xy 40.374806 -21.212555) (xy 40.430243 -21.218655) (xy 40.4842 -21.232761)
			(xy 40.535529 -21.254573) (xy 40.583135 -21.283627) (xy 40.626003 -21.319302) (xy 40.66322 -21.360839)
			(xy 40.693993 -21.407352) (xy 40.717665 -21.457849) (xy 40.733733 -21.511256) (xy 40.741853 -21.566432)
			(xy 40.742362 -21.594318) (xy 40.741853 -21.622204) (xy 40.733733 -21.67738) (xy 40.717665 -21.730787)
			(xy 40.693993 -21.781284) (xy 40.66322 -21.827797) (xy 40.626003 -21.869334) (xy 40.583135 -21.905009)
			(xy 40.535529 -21.934063) (xy 40.485092 -21.955496) (xy 60.015167 -21.955496) (xy 60.019055 -21.901137)
			(xy 60.030641 -21.847885) (xy 60.049688 -21.796824) (xy 60.075809 -21.748993) (xy 60.108471 -21.705367)
			(xy 60.14701 -21.666834) (xy 60.19064 -21.634179) (xy 60.238475 -21.608065) (xy 60.289539 -21.589025)
			(xy 60.342792 -21.577447) (xy 60.397152 -21.573567) (xy 60.451511 -21.577462) (xy 60.504762 -21.589055)
			(xy 60.55582 -21.608108) (xy 60.603647 -21.634235) (xy 60.625736 -21.650198) (xy 60.644748 -21.663794)
			(xy 60.686631 -21.684526) (xy 60.731599 -21.697252) (xy 60.778136 -21.701542) (xy 60.824673 -21.697252)
			(xy 60.869641 -21.684526) (xy 60.911524 -21.663794) (xy 60.930536 -21.650198) (xy 60.952618 -21.634233)
			(xy 61.000441 -21.608117) (xy 61.051494 -21.589073) (xy 61.104738 -21.577489) (xy 61.159089 -21.5736)
			(xy 61.21344 -21.577486) (xy 61.266684 -21.589067) (xy 61.317739 -21.608108) (xy 61.365564 -21.634221)
			(xy 61.409185 -21.666874) (xy 61.447716 -21.705404) (xy 61.480371 -21.749024) (xy 61.506486 -21.796848)
			(xy 61.525529 -21.847902) (xy 61.537112 -21.901146) (xy 61.541 -21.955496) (xy 61.919176 -21.955496)
			(xy 61.923065 -21.901139) (xy 61.93465 -21.847889) (xy 61.953696 -21.79683) (xy 61.979815 -21.749001)
			(xy 62.012475 -21.705377) (xy 62.051012 -21.666845) (xy 62.094641 -21.63419) (xy 62.142473 -21.608077)
			(xy 62.193534 -21.589037) (xy 62.246786 -21.577458) (xy 62.301143 -21.573576) (xy 62.3555 -21.57747)
			(xy 62.408748 -21.589061) (xy 62.459806 -21.608112) (xy 62.507632 -21.634236) (xy 62.52972 -21.650198)
			(xy 62.548732 -21.663794) (xy 62.590615 -21.684526) (xy 62.635583 -21.697252) (xy 62.68212 -21.701542)
			(xy 62.728657 -21.697252) (xy 62.773625 -21.684526) (xy 62.815508 -21.663794) (xy 62.83452 -21.650198)
			(xy 62.856602 -21.634232) (xy 62.904427 -21.608113) (xy 62.955481 -21.589067) (xy 63.008727 -21.577481)
			(xy 63.06308 -21.573591) (xy 63.117433 -21.577475) (xy 63.17068 -21.589056) (xy 63.221737 -21.608097)
			(xy 63.269564 -21.63421) (xy 63.313188 -21.666864) (xy 63.351721 -21.705394) (xy 63.384377 -21.749016)
			(xy 63.410494 -21.796842) (xy 63.429537 -21.847897) (xy 63.441121 -21.901144) (xy 63.445009 -21.955496)
			(xy 63.441122 -22.009849) (xy 63.429539 -22.063096) (xy 63.410497 -22.114152) (xy 63.384381 -22.161978)
			(xy 63.351725 -22.2056) (xy 63.313193 -22.244131) (xy 63.26957 -22.276786) (xy 63.221743 -22.3029)
			(xy 63.170687 -22.321942) (xy 63.11744 -22.333524) (xy 63.063087 -22.337409) (xy 63.008734 -22.33352)
			(xy 62.955488 -22.321935) (xy 62.904433 -22.30289) (xy 62.856608 -22.276772) (xy 62.83452 -22.260814)
			(xy 62.815508 -22.247218) (xy 62.773625 -22.226486) (xy 62.728657 -22.21376) (xy 62.68212 -22.20947)
			(xy 62.635583 -22.21376) (xy 62.590615 -22.226486) (xy 62.548732 -22.247218) (xy 62.52972 -22.260814)
			(xy 62.507626 -22.276768) (xy 62.459799 -22.302891) (xy 62.408742 -22.321941) (xy 62.355492 -22.333531)
			(xy 62.301136 -22.337424) (xy 62.246778 -22.333541) (xy 62.193527 -22.321961) (xy 62.142466 -22.30292)
			(xy 62.094635 -22.276806) (xy 62.051007 -22.24415) (xy 62.012471 -22.205618) (xy 61.979811 -22.161993)
			(xy 61.953693 -22.114163) (xy 61.934648 -22.063104) (xy 61.923064 -22.009853) (xy 61.919176 -21.955496)
			(xy 61.541 -21.955496) (xy 61.537113 -22.009847) (xy 61.525531 -22.063091) (xy 61.506489 -22.114145)
			(xy 61.480375 -22.16197) (xy 61.447721 -22.205591) (xy 61.409191 -22.244121) (xy 61.36557 -22.276775)
			(xy 61.317745 -22.302889) (xy 61.266691 -22.321931) (xy 61.213447 -22.333513) (xy 61.159096 -22.3374)
			(xy 61.104745 -22.333512) (xy 61.051501 -22.321929) (xy 61.000448 -22.302886) (xy 60.952624 -22.276771)
			(xy 60.930536 -22.260814) (xy 60.911524 -22.247218) (xy 60.869641 -22.226486) (xy 60.824673 -22.21376)
			(xy 60.778136 -22.20947) (xy 60.731599 -22.21376) (xy 60.686631 -22.226486) (xy 60.644748 -22.247218)
			(xy 60.625736 -22.260814) (xy 60.603641 -22.276769) (xy 60.555814 -22.302895) (xy 60.504755 -22.321947)
			(xy 60.451504 -22.333539) (xy 60.397145 -22.337433) (xy 60.342785 -22.333552) (xy 60.289532 -22.321972)
			(xy 60.238468 -22.302932) (xy 60.190634 -22.276817) (xy 60.147004 -22.244161) (xy 60.108466 -22.205627)
			(xy 60.075805 -22.162001) (xy 60.049685 -22.11417) (xy 60.030639 -22.063108) (xy 60.019054 -22.009856)
			(xy 60.015167 -21.955496) (xy 40.485092 -21.955496) (xy 40.4842 -21.955875) (xy 40.430243 -21.969981)
			(xy 40.374806 -21.976081) (xy 40.319072 -21.974044) (xy 40.264229 -21.963914) (xy 40.211445 -21.945907)
			(xy 40.161845 -21.920406) (xy 40.116487 -21.887955) (xy 40.076338 -21.849246) (xy 40.042252 -21.805103)
			(xy 40.014956 -21.756468) (xy 39.995033 -21.704377) (xy 39.982907 -21.64994) (xy 39.978836 -21.594318)
			(xy 36.071962 -21.594318) (xy 36.140713 -21.646237) (xy 36.204933 -21.704781) (xy 36.263477 -21.769001)
			(xy 36.315846 -21.838348) (xy 36.361593 -21.912232) (xy 36.400327 -21.990021) (xy 36.431719 -22.071053)
			(xy 36.4555 -22.154635) (xy 36.471468 -22.240055) (xy 36.479486 -22.326584) (xy 36.479988 -22.370034)
			(xy 36.479486 -22.413484) (xy 36.471468 -22.500013) (xy 36.4555 -22.585433) (xy 36.431719 -22.669015)
			(xy 36.400327 -22.750047) (xy 36.361593 -22.827836) (xy 36.315846 -22.90172) (xy 36.263477 -22.971067)
			(xy 36.204933 -23.035287) (xy 36.140713 -23.093831) (xy 36.071366 -23.1462) (xy 36.008098 -23.185374)
			(xy 40.1099 -23.185374) (xy 40.113971 -23.129752) (xy 40.126097 -23.075315) (xy 40.14602 -23.023224)
			(xy 40.173316 -22.974589) (xy 40.207402 -22.930446) (xy 40.247551 -22.891737) (xy 40.292909 -22.859286)
			(xy 40.342509 -22.833785) (xy 40.395293 -22.815778) (xy 40.450136 -22.805648) (xy 40.50587 -22.803611)
			(xy 40.561307 -22.809711) (xy 40.615264 -22.823817) (xy 40.666593 -22.845629) (xy 40.714199 -22.874683)
			(xy 40.757067 -22.910358) (xy 40.794284 -22.951895) (xy 40.825057 -22.998408) (xy 40.848729 -23.048905)
			(xy 40.864797 -23.102312) (xy 40.872917 -23.157488) (xy 40.873426 -23.185374) (xy 40.872917 -23.21326)
			(xy 40.864797 -23.268436) (xy 40.848729 -23.321843) (xy 40.825057 -23.37234) (xy 40.794284 -23.418853)
			(xy 40.757067 -23.46039) (xy 40.714199 -23.496065) (xy 40.666593 -23.525119) (xy 40.615264 -23.546931)
			(xy 40.561307 -23.561037) (xy 40.50587 -23.567137) (xy 40.450136 -23.5651) (xy 40.395293 -23.55497)
			(xy 40.342509 -23.536963) (xy 40.292909 -23.511462) (xy 40.247551 -23.479011) (xy 40.207402 -23.440302)
			(xy 40.173316 -23.396159) (xy 40.14602 -23.347524) (xy 40.126097 -23.295433) (xy 40.113971 -23.240996)
			(xy 40.1099 -23.185374) (xy 36.008098 -23.185374) (xy 35.997482 -23.191947) (xy 35.919693 -23.230681)
			(xy 35.838661 -23.262073) (xy 35.755079 -23.285854) (xy 35.669659 -23.301822) (xy 35.58313 -23.30984)
			(xy 35.49623 -23.30984) (xy 35.409701 -23.301822) (xy 35.324281 -23.285854) (xy 35.240699 -23.262073)
			(xy 35.159667 -23.230681) (xy 35.081878 -23.191947) (xy 35.007994 -23.1462) (xy 34.938647 -23.093831)
			(xy 34.874427 -23.035287) (xy 34.815883 -22.971067) (xy 34.763514 -22.90172) (xy 34.717767 -22.827836)
			(xy 34.679033 -22.750047) (xy 34.647641 -22.669015) (xy 34.62386 -22.585433) (xy 34.607892 -22.500013)
			(xy 34.599874 -22.413484) (xy 31.399391 -22.413484) (xy 31.399334 -22.420887) (xy 31.390608 -22.507543)
			(xy 31.373906 -22.593021) (xy 31.349373 -22.676589) (xy 31.317216 -22.757529) (xy 31.277714 -22.83515)
			(xy 31.231203 -22.908785) (xy 31.178082 -22.977804) (xy 31.118808 -23.041616) (xy 31.053886 -23.099673)
			(xy 30.983874 -23.151478) (xy 30.909372 -23.196587) (xy 30.831018 -23.234614) (xy 30.749483 -23.265233)
			(xy 30.665467 -23.288181) (xy 30.579688 -23.303263) (xy 30.492883 -23.310347) (xy 30.405794 -23.309375)
			(xy 30.319168 -23.300354) (xy 30.233747 -23.283362) (xy 30.150264 -23.258543) (xy 30.109668 -23.242778)
			(xy 30.069795 -23.226258) (xy 29.992966 -23.186918) (xy 29.920066 -23.140703) (xy 29.851708 -23.088001)
			(xy 29.788467 -23.029258) (xy 29.730875 -22.964966) (xy 29.679417 -22.895667) (xy 29.634526 -22.821945)
			(xy 29.596579 -22.744419) (xy 29.565897 -22.663741) (xy 29.542736 -22.580592) (xy 29.527293 -22.49567)
			(xy 29.519697 -22.40969) (xy 29.520011 -22.323375) (xy 29.528235 -22.237453) (xy 29.544297 -22.152646)
			(xy 29.568063 -22.069668) (xy 29.599333 -21.989216) (xy 29.637844 -21.911969) (xy 29.683272 -21.838575)
			(xy 29.735234 -21.769654) (xy 29.793293 -21.705784) (xy 29.856961 -21.647503) (xy 29.925702 -21.595302)
			(xy 29.998937 -21.54962) (xy 30.037278 -21.529802) (xy 30.074108 -21.512276) (xy 30.074362 -21.512276)
			(xy 30.087488 -21.505905) (xy 30.110643 -21.488167) (xy 30.12915 -21.465621) (xy 30.142035 -21.439452)
			(xy 30.148623 -21.411037) (xy 30.149038 -21.396452) (xy 30.149038 -21.34362) (xy 30.07487 -21.269452)
			(xy 29.988002 -21.269452) (xy 29.92501 -21.290788) (xy 29.813504 -21.290788) (xy 26.150621 -24.953484)
			(xy 29.519874 -24.953484) (xy 29.519874 -24.866584) (xy 29.527892 -24.780055) (xy 29.54386 -24.694635)
			(xy 29.567641 -24.611053) (xy 29.599033 -24.530021) (xy 29.637767 -24.452232) (xy 29.683514 -24.378348)
			(xy 29.735883 -24.309001) (xy 29.794427 -24.244781) (xy 29.858647 -24.186237) (xy 29.927994 -24.133868)
			(xy 30.001878 -24.088121) (xy 30.079667 -24.049387) (xy 30.160699 -24.017995) (xy 30.244281 -23.994214)
			(xy 30.329701 -23.978246) (xy 30.41623 -23.970228) (xy 30.50313 -23.970228) (xy 30.589659 -23.978246)
			(xy 30.675079 -23.994214) (xy 30.758661 -24.017995) (xy 30.839693 -24.049387) (xy 30.917482 -24.088121)
			(xy 30.991366 -24.133868) (xy 31.060713 -24.186237) (xy 31.124933 -24.244781) (xy 31.183477 -24.309001)
			(xy 31.235846 -24.378348) (xy 31.281593 -24.452232) (xy 31.320327 -24.530021) (xy 31.351719 -24.611053)
			(xy 31.3755 -24.694635) (xy 31.391468 -24.780055) (xy 31.399486 -24.866584) (xy 31.399988 -24.910034)
			(xy 31.399486 -24.953484) (xy 34.599874 -24.953484) (xy 34.599874 -24.866584) (xy 34.607892 -24.780055)
			(xy 34.62386 -24.694635) (xy 34.647641 -24.611053) (xy 34.679033 -24.530021) (xy 34.717767 -24.452232)
			(xy 34.763514 -24.378348) (xy 34.815883 -24.309001) (xy 34.874427 -24.244781) (xy 34.938647 -24.186237)
			(xy 35.007994 -24.133868) (xy 35.081878 -24.088121) (xy 35.159667 -24.049387) (xy 35.240699 -24.017995)
			(xy 35.324281 -23.994214) (xy 35.409701 -23.978246) (xy 35.49623 -23.970228) (xy 35.58313 -23.970228)
			(xy 35.669659 -23.978246) (xy 35.755079 -23.994214) (xy 35.763922 -23.99673) (xy 60.015122 -23.99673)
			(xy 60.019006 -23.942364) (xy 60.030589 -23.889105) (xy 60.049634 -23.838036) (xy 60.075753 -23.790197)
			(xy 60.108415 -23.746564) (xy 60.146955 -23.708023) (xy 60.190588 -23.675359) (xy 60.238425 -23.649238)
			(xy 60.289494 -23.630192) (xy 60.342753 -23.618608) (xy 60.397119 -23.614722) (xy 60.451484 -23.618613)
			(xy 60.504742 -23.630202) (xy 60.555808 -23.649254) (xy 60.603643 -23.675379) (xy 60.625736 -23.691342)
			(xy 60.644748 -23.704938) (xy 60.686631 -23.72567) (xy 60.731599 -23.738396) (xy 60.778136 -23.742686)
			(xy 60.824673 -23.738396) (xy 60.869641 -23.72567) (xy 60.911524 -23.704938) (xy 60.930536 -23.691342)
			(xy 60.952576 -23.675318) (xy 61.000402 -23.649196) (xy 61.051459 -23.630147) (xy 61.104707 -23.618558)
			(xy 61.159062 -23.614665) (xy 61.213419 -23.618547) (xy 61.266669 -23.630126) (xy 61.317729 -23.649165)
			(xy 61.36556 -23.675277) (xy 61.409188 -23.70793) (xy 61.447725 -23.746461) (xy 61.480386 -23.790083)
			(xy 61.506507 -23.837909) (xy 61.525555 -23.888966) (xy 61.537143 -23.942215) (xy 61.541035 -23.99657)
			(xy 61.541024 -23.99673) (xy 61.919131 -23.99673) (xy 61.923016 -23.942366) (xy 61.934597 -23.889109)
			(xy 61.953641 -23.838042) (xy 61.979759 -23.790205) (xy 62.01242 -23.746573) (xy 62.050957 -23.708033)
			(xy 62.094588 -23.67537) (xy 62.142423 -23.64925) (xy 62.193489 -23.630203) (xy 62.246746 -23.618619)
			(xy 62.301109 -23.614731) (xy 62.355473 -23.618621) (xy 62.408729 -23.630209) (xy 62.459794 -23.649258)
			(xy 62.507628 -23.67538) (xy 62.52972 -23.691342) (xy 62.548732 -23.704938) (xy 62.590615 -23.72567)
			(xy 62.635583 -23.738396) (xy 62.68212 -23.742686) (xy 62.728657 -23.738396) (xy 62.773625 -23.72567)
			(xy 62.815508 -23.704938) (xy 62.83452 -23.691342) (xy 62.856561 -23.675316) (xy 62.904388 -23.649192)
			(xy 62.955446 -23.630141) (xy 63.008696 -23.61855) (xy 63.063053 -23.614655) (xy 63.117412 -23.618537)
			(xy 63.170664 -23.630115) (xy 63.221727 -23.649154) (xy 63.269561 -23.675266) (xy 63.313191 -23.70792)
			(xy 63.35173 -23.746451) (xy 63.384393 -23.790075) (xy 63.410515 -23.837903) (xy 63.429564 -23.888962)
			(xy 63.441152 -23.942212) (xy 63.445045 -23.99657) (xy 63.441161 -24.050928) (xy 63.429581 -24.10418)
			(xy 63.41054 -24.155242) (xy 63.384425 -24.203075) (xy 63.351769 -24.246704) (xy 63.313236 -24.285241)
			(xy 63.269611 -24.317902) (xy 63.221782 -24.344022) (xy 63.170722 -24.363069) (xy 63.117471 -24.374655)
			(xy 63.063113 -24.378545) (xy 63.008755 -24.374659) (xy 62.955504 -24.363076) (xy 62.904442 -24.344033)
			(xy 62.856611 -24.317916) (xy 62.83452 -24.301958) (xy 62.815508 -24.288362) (xy 62.773625 -24.26763)
			(xy 62.728657 -24.254904) (xy 62.68212 -24.250614) (xy 62.635583 -24.254904) (xy 62.590615 -24.26763)
			(xy 62.548732 -24.288362) (xy 62.52972 -24.301958) (xy 62.507678 -24.317987) (xy 62.459848 -24.344117)
			(xy 62.408786 -24.363175) (xy 62.355532 -24.37477) (xy 62.301169 -24.378669) (xy 62.246805 -24.37479)
			(xy 62.193547 -24.363214) (xy 62.142478 -24.344175) (xy 62.094639 -24.318062) (xy 62.051003 -24.285406)
			(xy 62.012459 -24.246872) (xy 61.979792 -24.203245) (xy 61.953666 -24.155413) (xy 61.934614 -24.104349)
			(xy 61.923024 -24.051093) (xy 61.919131 -23.99673) (xy 61.541024 -23.99673) (xy 61.537152 -24.050926)
			(xy 61.525572 -24.104176) (xy 61.506532 -24.155236) (xy 61.480419 -24.203067) (xy 61.447765 -24.246694)
			(xy 61.409234 -24.28523) (xy 61.365611 -24.317891) (xy 61.317784 -24.34401) (xy 61.266726 -24.363057)
			(xy 61.213478 -24.374644) (xy 61.159122 -24.378535) (xy 61.104767 -24.374651) (xy 61.051517 -24.36307)
			(xy 61.000457 -24.344029) (xy 60.952627 -24.317915) (xy 60.930536 -24.301958) (xy 60.911524 -24.288362)
			(xy 60.869641 -24.26763) (xy 60.824673 -24.254904) (xy 60.778136 -24.250614) (xy 60.731599 -24.254904)
			(xy 60.686631 -24.26763) (xy 60.644748 -24.288362) (xy 60.625736 -24.301958) (xy 60.603694 -24.317988)
			(xy 60.555863 -24.344121) (xy 60.504799 -24.363181) (xy 60.451543 -24.374778) (xy 60.397179 -24.378678)
			(xy 60.342812 -24.374801) (xy 60.289551 -24.363225) (xy 60.23848 -24.344187) (xy 60.190638 -24.318073)
			(xy 60.147 -24.285417) (xy 60.108454 -24.246882) (xy 60.075785 -24.203253) (xy 60.049658 -24.155419)
			(xy 60.030606 -24.104353) (xy 60.019015 -24.051095) (xy 60.015122 -23.99673) (xy 35.763922 -23.99673)
			(xy 35.838661 -24.017995) (xy 35.919693 -24.049387) (xy 35.997482 -24.088121) (xy 36.071366 -24.133868)
			(xy 36.140713 -24.186237) (xy 36.204933 -24.244781) (xy 36.263477 -24.309001) (xy 36.315846 -24.378348)
			(xy 36.361593 -24.452232) (xy 36.400327 -24.530021) (xy 36.431719 -24.611053) (xy 36.4555 -24.694635)
			(xy 36.471468 -24.780055) (xy 36.479486 -24.866584) (xy 36.479988 -24.910034) (xy 36.479486 -24.953484)
			(xy 36.471468 -25.040013) (xy 36.4555 -25.125433) (xy 36.431719 -25.209015) (xy 36.400327 -25.290047)
			(xy 36.361593 -25.367836) (xy 36.315846 -25.44172) (xy 36.263477 -25.511067) (xy 36.204933 -25.575287)
			(xy 36.140713 -25.633831) (xy 36.071366 -25.6862) (xy 35.997482 -25.731947) (xy 35.919693 -25.770681)
			(xy 35.838661 -25.802073) (xy 35.755079 -25.825854) (xy 35.669659 -25.841822) (xy 35.58313 -25.84984)
			(xy 35.49623 -25.84984) (xy 35.409701 -25.841822) (xy 35.324281 -25.825854) (xy 35.240699 -25.802073)
			(xy 35.159667 -25.770681) (xy 35.081878 -25.731947) (xy 35.007994 -25.6862) (xy 34.938647 -25.633831)
			(xy 34.874427 -25.575287) (xy 34.815883 -25.511067) (xy 34.763514 -25.44172) (xy 34.717767 -25.367836)
			(xy 34.679033 -25.290047) (xy 34.647641 -25.209015) (xy 34.62386 -25.125433) (xy 34.607892 -25.040013)
			(xy 34.599874 -24.953484) (xy 31.399486 -24.953484) (xy 31.391468 -25.040013) (xy 31.3755 -25.125433)
			(xy 31.351719 -25.209015) (xy 31.320327 -25.290047) (xy 31.281593 -25.367836) (xy 31.235846 -25.44172)
			(xy 31.183477 -25.511067) (xy 31.124933 -25.575287) (xy 31.060713 -25.633831) (xy 30.991366 -25.6862)
			(xy 30.917482 -25.731947) (xy 30.839693 -25.770681) (xy 30.758661 -25.802073) (xy 30.675079 -25.825854)
			(xy 30.589659 -25.841822) (xy 30.50313 -25.84984) (xy 30.41623 -25.84984) (xy 30.329701 -25.841822)
			(xy 30.244281 -25.825854) (xy 30.160699 -25.802073) (xy 30.079667 -25.770681) (xy 30.001878 -25.731947)
			(xy 29.927994 -25.6862) (xy 29.858647 -25.633831) (xy 29.794427 -25.575287) (xy 29.735883 -25.511067)
			(xy 29.683514 -25.44172) (xy 29.637767 -25.367836) (xy 29.599033 -25.290047) (xy 29.567641 -25.209015)
			(xy 29.54386 -25.125433) (xy 29.527892 -25.040013) (xy 29.519874 -24.953484) (xy 26.150621 -24.953484)
			(xy 25.197543 -25.906514) (xy 60.015143 -25.906514) (xy 60.019029 -25.852152) (xy 60.030613 -25.798896)
			(xy 60.049659 -25.74783) (xy 60.075779 -25.699996) (xy 60.108441 -25.656365) (xy 60.14698 -25.617828)
			(xy 60.190612 -25.585168) (xy 60.238448 -25.559051) (xy 60.289514 -25.540008) (xy 60.342771 -25.528426)
			(xy 60.397134 -25.524543) (xy 60.451496 -25.528436) (xy 60.504751 -25.540027) (xy 60.555814 -25.559079)
			(xy 60.603645 -25.585205) (xy 60.625736 -25.601168) (xy 60.644748 -25.614764) (xy 60.686631 -25.635496)
			(xy 60.731599 -25.648222) (xy 60.778136 -25.652512) (xy 60.824673 -25.648222) (xy 60.869641 -25.635496)
			(xy 60.911524 -25.614764) (xy 60.930536 -25.601168) (xy 60.952646 -25.585243) (xy 61.000467 -25.559132)
			(xy 61.051518 -25.540091) (xy 61.10476 -25.52851) (xy 61.159107 -25.524624) (xy 61.213454 -25.528512)
			(xy 61.266695 -25.540095) (xy 61.317745 -25.559137) (xy 61.365566 -25.585251) (xy 61.409183 -25.617904)
			(xy 61.44771 -25.656433) (xy 61.480361 -25.700052) (xy 61.506472 -25.747874) (xy 61.525511 -25.798926)
			(xy 61.537091 -25.852167) (xy 61.540976 -25.906514) (xy 61.919152 -25.906514) (xy 61.923038 -25.852154)
			(xy 61.934622 -25.7989) (xy 61.953667 -25.747837) (xy 61.979785 -25.700004) (xy 62.012445 -25.656375)
			(xy 62.050983 -25.617839) (xy 62.094612 -25.585179) (xy 62.142446 -25.559062) (xy 62.19351 -25.540019)
			(xy 62.246764 -25.528437) (xy 62.301125 -25.524552) (xy 62.355485 -25.528444) (xy 62.408738 -25.540033)
			(xy 62.459799 -25.559083) (xy 62.50763 -25.585206) (xy 62.52972 -25.601168) (xy 62.548732 -25.614764)
			(xy 62.590615 -25.635496) (xy 62.635583 -25.648222) (xy 62.68212 -25.652512) (xy 62.728657 -25.648222)
			(xy 62.773625 -25.635496) (xy 62.815508 -25.614764) (xy 62.83452 -25.601168) (xy 62.85663 -25.585242)
			(xy 62.904453 -25.559128) (xy 62.955505 -25.540085) (xy 63.008748 -25.528502) (xy 63.063098 -25.524615)
			(xy 63.117447 -25.528502) (xy 63.17069 -25.540084) (xy 63.221743 -25.559126) (xy 63.269566 -25.58524)
			(xy 63.313186 -25.617894) (xy 63.351714 -25.656423) (xy 63.384367 -25.700044) (xy 63.410479 -25.747868)
			(xy 63.429519 -25.798921) (xy 63.4411 -25.852165) (xy 63.444985 -25.906514) (xy 63.441096 -25.960864)
			(xy 63.429511 -26.014106) (xy 63.410467 -26.065158) (xy 63.384351 -26.11298) (xy 63.351695 -26.156598)
			(xy 63.313164 -26.195125) (xy 63.269542 -26.227776) (xy 63.221717 -26.253886) (xy 63.170663 -26.272924)
			(xy 63.117419 -26.284502) (xy 63.063069 -26.288385) (xy 63.00872 -26.284494) (xy 62.955478 -26.272907)
			(xy 62.904427 -26.25386) (xy 62.856606 -26.227742) (xy 62.83452 -26.211784) (xy 62.815508 -26.198188)
			(xy 62.773625 -26.177456) (xy 62.728657 -26.16473) (xy 62.68212 -26.16044) (xy 62.635583 -26.16473)
			(xy 62.590615 -26.177456) (xy 62.548732 -26.198188) (xy 62.52972 -26.211784) (xy 62.507654 -26.227778)
			(xy 62.459826 -26.253905) (xy 62.408766 -26.272959) (xy 62.355514 -26.284552) (xy 62.301154 -26.288448)
			(xy 62.246793 -26.284567) (xy 62.193538 -26.272989) (xy 62.142472 -26.25395) (xy 62.094637 -26.227836)
			(xy 62.051005 -26.19518) (xy 62.012464 -26.156647) (xy 61.979801 -26.113021) (xy 61.953679 -26.06519)
			(xy 61.93463 -26.014128) (xy 61.923043 -25.960875) (xy 61.919152 -25.906514) (xy 61.540976 -25.906514)
			(xy 61.537087 -25.960862) (xy 61.525503 -26.014102) (xy 61.50646 -26.065152) (xy 61.480345 -26.112972)
			(xy 61.447691 -26.156589) (xy 61.409161 -26.195115) (xy 61.365541 -26.227765) (xy 61.317719 -26.253875)
			(xy 61.266667 -26.272913) (xy 61.213426 -26.284492) (xy 61.159078 -26.288376) (xy 61.104731 -26.284486)
			(xy 61.051491 -26.272901) (xy 61.000441 -26.253856) (xy 60.952622 -26.227741) (xy 60.930536 -26.211784)
			(xy 60.911524 -26.198188) (xy 60.869641 -26.177456) (xy 60.824673 -26.16473) (xy 60.778136 -26.16044)
			(xy 60.731599 -26.16473) (xy 60.686631 -26.177456) (xy 60.644748 -26.198188) (xy 60.625736 -26.211784)
			(xy 60.603669 -26.227779) (xy 60.55584 -26.253909) (xy 60.504779 -26.272965) (xy 60.451525 -26.28456)
			(xy 60.397163 -26.288457) (xy 60.3428 -26.284578) (xy 60.289542 -26.273001) (xy 60.238474 -26.253961)
			(xy 60.190636 -26.227847) (xy 60.147002 -26.195191) (xy 60.10846 -26.156656) (xy 60.075794 -26.113029)
			(xy 60.049671 -26.065196) (xy 60.030621 -26.014132) (xy 60.019033 -25.960877) (xy 60.015143 -25.906514)
			(xy 25.197543 -25.906514) (xy 24.833072 -26.270966) (xy 24.821722 -26.283114) (xy 24.805132 -26.31191)
			(xy 24.796536 -26.344012) (xy 24.795988 -26.360628) (xy 24.795988 -27.493484) (xy 29.519874 -27.493484)
			(xy 29.519874 -27.406584) (xy 29.527892 -27.320055) (xy 29.54386 -27.234635) (xy 29.567641 -27.151053)
			(xy 29.599033 -27.070021) (xy 29.637767 -26.992232) (xy 29.683514 -26.918348) (xy 29.735883 -26.849001)
			(xy 29.794427 -26.784781) (xy 29.858647 -26.726237) (xy 29.927994 -26.673868) (xy 30.001878 -26.628121)
			(xy 30.079667 -26.589387) (xy 30.160699 -26.557995) (xy 30.244281 -26.534214) (xy 30.329701 -26.518246)
			(xy 30.41623 -26.510228) (xy 30.50313 -26.510228) (xy 30.589659 -26.518246) (xy 30.675079 -26.534214)
			(xy 30.758661 -26.557995) (xy 30.839693 -26.589387) (xy 30.917482 -26.628121) (xy 30.991366 -26.673868)
			(xy 31.060713 -26.726237) (xy 31.124933 -26.784781) (xy 31.183477 -26.849001) (xy 31.235846 -26.918348)
			(xy 31.281593 -26.992232) (xy 31.320327 -27.070021) (xy 31.351719 -27.151053) (xy 31.3755 -27.234635)
			(xy 31.391468 -27.320055) (xy 31.399486 -27.406584) (xy 31.399988 -27.450034) (xy 31.399486 -27.493484)
			(xy 34.599874 -27.493484) (xy 34.599874 -27.406584) (xy 34.607892 -27.320055) (xy 34.62386 -27.234635)
			(xy 34.647641 -27.151053) (xy 34.679033 -27.070021) (xy 34.717767 -26.992232) (xy 34.763514 -26.918348)
			(xy 34.815883 -26.849001) (xy 34.874427 -26.784781) (xy 34.938647 -26.726237) (xy 35.007994 -26.673868)
			(xy 35.081878 -26.628121) (xy 35.159667 -26.589387) (xy 35.240699 -26.557995) (xy 35.324281 -26.534214)
			(xy 35.409701 -26.518246) (xy 35.49623 -26.510228) (xy 35.58313 -26.510228) (xy 35.669659 -26.518246)
			(xy 35.755079 -26.534214) (xy 35.838661 -26.557995) (xy 35.919693 -26.589387) (xy 35.997482 -26.628121)
			(xy 36.071366 -26.673868) (xy 36.140713 -26.726237) (xy 36.204933 -26.784781) (xy 36.263477 -26.849001)
			(xy 36.315846 -26.918348) (xy 36.361593 -26.992232) (xy 36.400327 -27.070021) (xy 36.431719 -27.151053)
			(xy 36.4555 -27.234635) (xy 36.471468 -27.320055) (xy 36.479486 -27.406584) (xy 36.479988 -27.450034)
			(xy 36.479486 -27.493484) (xy 36.471468 -27.580013) (xy 36.4555 -27.665433) (xy 36.431719 -27.749015)
			(xy 36.400327 -27.830047) (xy 36.361593 -27.907836) (xy 36.315846 -27.98172) (xy 36.263477 -28.051067)
			(xy 36.204933 -28.115287) (xy 36.140713 -28.173831) (xy 36.071366 -28.2262) (xy 35.997482 -28.271947)
			(xy 35.946339 -28.297413) (xy 41.909066 -28.297413) (xy 41.912952 -28.243056) (xy 41.924535 -28.189804)
			(xy 41.943578 -28.138744) (xy 41.969695 -28.090913) (xy 42.002353 -28.047287) (xy 42.040888 -28.008752)
			(xy 42.084515 -27.976094) (xy 42.132345 -27.949978) (xy 42.183406 -27.930934) (xy 42.236657 -27.919352)
			(xy 42.291015 -27.915466) (xy 42.345372 -27.919356) (xy 42.398622 -27.930943) (xy 42.449682 -27.94999)
			(xy 42.49751 -27.97611) (xy 42.5196 -27.99207) (xy 42.538612 -28.005666) (xy 42.580495 -28.026398)
			(xy 42.625463 -28.039124) (xy 42.672 -28.043414) (xy 42.718537 -28.039124) (xy 42.763505 -28.026398)
			(xy 42.805388 -28.005666) (xy 42.8244 -27.99207) (xy 42.846509 -27.97614) (xy 42.894333 -27.950022)
			(xy 42.945388 -27.930976) (xy 42.998633 -27.919391) (xy 43.052985 -27.915501) (xy 43.107338 -27.919387)
			(xy 43.160584 -27.930968) (xy 43.21164 -27.95001) (xy 43.259466 -27.976124) (xy 43.303089 -28.008779)
			(xy 43.34162 -28.04731) (xy 43.374275 -28.090932) (xy 43.40039 -28.138759) (xy 43.419432 -28.189814)
			(xy 43.431013 -28.243061) (xy 43.434899 -28.297413) (xy 43.795759 -28.297413) (xy 43.799645 -28.243054)
			(xy 43.811228 -28.189801) (xy 43.830272 -28.138739) (xy 43.85639 -28.090907) (xy 43.88905 -28.04728)
			(xy 43.927586 -28.008744) (xy 43.971214 -27.976086) (xy 44.019047 -27.949969) (xy 44.070109 -27.930926)
			(xy 44.123362 -27.919344) (xy 44.177722 -27.915459) (xy 44.232081 -27.91935) (xy 44.285332 -27.930938)
			(xy 44.336393 -27.949987) (xy 44.384222 -27.976109) (xy 44.406312 -27.99207) (xy 44.425324 -28.005666)
			(xy 44.467207 -28.026398) (xy 44.512175 -28.039124) (xy 44.558712 -28.043414) (xy 44.605249 -28.039124)
			(xy 44.650217 -28.026398) (xy 44.6921 -28.005666) (xy 44.711112 -27.99207) (xy 44.733221 -27.976141)
			(xy 44.781044 -27.950025) (xy 44.832097 -27.930981) (xy 44.885341 -27.919397) (xy 44.939692 -27.915508)
			(xy 44.994043 -27.919395) (xy 45.047287 -27.930976) (xy 45.098342 -27.950018) (xy 45.146166 -27.976132)
			(xy 45.189787 -28.008787) (xy 45.228317 -28.047317) (xy 45.260971 -28.090938) (xy 45.287084 -28.138763)
			(xy 45.306125 -28.189818) (xy 45.317706 -28.243062) (xy 45.321592 -28.297413) (xy 45.317702 -28.351764)
			(xy 45.306118 -28.405008) (xy 45.287073 -28.456061) (xy 45.260956 -28.503884) (xy 45.2283 -28.547503)
			(xy 45.189767 -28.586031) (xy 45.146144 -28.618682) (xy 45.098318 -28.644793) (xy 45.047262 -28.663831)
			(xy 44.994017 -28.675409) (xy 44.939666 -28.679292) (xy 44.885315 -28.675399) (xy 44.832072 -28.663812)
			(xy 44.78102 -28.644764) (xy 44.733198 -28.618645) (xy 44.711112 -28.602686) (xy 44.6921 -28.58909)
			(xy 44.650217 -28.568358) (xy 44.605249 -28.555632) (xy 44.558712 -28.551342) (xy 44.512175 -28.555632)
			(xy 44.467207 -28.568358) (xy 44.425324 -28.58909) (xy 44.406312 -28.602686) (xy 44.384244 -28.618677)
			(xy 44.336417 -28.644802) (xy 44.285358 -28.663855) (xy 44.232107 -28.675446) (xy 44.177748 -28.679341)
			(xy 44.123389 -28.67546) (xy 44.070135 -28.663882) (xy 44.019071 -28.644842) (xy 43.971237 -28.618729)
			(xy 43.927606 -28.586073) (xy 43.889067 -28.54754) (xy 43.856405 -28.503915) (xy 43.830283 -28.456085)
			(xy 43.811235 -28.405024) (xy 43.799649 -28.351772) (xy 43.795759 -28.297413) (xy 43.434899 -28.297413)
			(xy 43.431009 -28.351765) (xy 43.419424 -28.405011) (xy 43.400379 -28.456066) (xy 43.374261 -28.50389)
			(xy 43.341603 -28.54751) (xy 43.303069 -28.586039) (xy 43.259444 -28.618691) (xy 43.211616 -28.644801)
			(xy 43.160559 -28.66384) (xy 43.107312 -28.675417) (xy 43.052959 -28.679299) (xy 42.998607 -28.675405)
			(xy 42.945362 -28.663816) (xy 42.894309 -28.644767) (xy 42.846487 -28.618646) (xy 42.8244 -28.602686)
			(xy 42.805388 -28.58909) (xy 42.763505 -28.568358) (xy 42.718537 -28.555632) (xy 42.672 -28.551342)
			(xy 42.625463 -28.555632) (xy 42.580495 -28.568358) (xy 42.538612 -28.58909) (xy 42.5196 -28.602686)
			(xy 42.497532 -28.618676) (xy 42.449706 -28.644799) (xy 42.398648 -28.66385) (xy 42.345398 -28.67544)
			(xy 42.291041 -28.679334) (xy 42.236683 -28.675452) (xy 42.183431 -28.663873) (xy 42.132369 -28.644833)
			(xy 42.084537 -28.61872) (xy 42.040908 -28.586065) (xy 42.00237 -28.547533) (xy 41.969709 -28.503909)
			(xy 41.943589 -28.45608) (xy 41.924542 -28.405021) (xy 41.912956 -28.35177) (xy 41.909066 -28.297413)
			(xy 35.946339 -28.297413) (xy 35.919693 -28.310681) (xy 35.838661 -28.342073) (xy 35.755079 -28.365854)
			(xy 35.669659 -28.381822) (xy 35.58313 -28.38984) (xy 35.49623 -28.38984) (xy 35.409701 -28.381822)
			(xy 35.324281 -28.365854) (xy 35.240699 -28.342073) (xy 35.159667 -28.310681) (xy 35.081878 -28.271947)
			(xy 35.007994 -28.2262) (xy 34.938647 -28.173831) (xy 34.874427 -28.115287) (xy 34.815883 -28.051067)
			(xy 34.763514 -27.98172) (xy 34.717767 -27.907836) (xy 34.679033 -27.830047) (xy 34.647641 -27.749015)
			(xy 34.62386 -27.665433) (xy 34.607892 -27.580013) (xy 34.599874 -27.493484) (xy 31.399486 -27.493484)
			(xy 31.391468 -27.580013) (xy 31.3755 -27.665433) (xy 31.351719 -27.749015) (xy 31.320327 -27.830047)
			(xy 31.281593 -27.907836) (xy 31.235846 -27.98172) (xy 31.183477 -28.051067) (xy 31.124933 -28.115287)
			(xy 31.060713 -28.173831) (xy 30.991366 -28.2262) (xy 30.917482 -28.271947) (xy 30.839693 -28.310681)
			(xy 30.758661 -28.342073) (xy 30.675079 -28.365854) (xy 30.589659 -28.381822) (xy 30.50313 -28.38984)
			(xy 30.41623 -28.38984) (xy 30.329701 -28.381822) (xy 30.244281 -28.365854) (xy 30.160699 -28.342073)
			(xy 30.079667 -28.310681) (xy 30.001878 -28.271947) (xy 29.927994 -28.2262) (xy 29.858647 -28.173831)
			(xy 29.794427 -28.115287) (xy 29.735883 -28.051067) (xy 29.683514 -27.98172) (xy 29.637767 -27.907836)
			(xy 29.599033 -27.830047) (xy 29.567641 -27.749015) (xy 29.54386 -27.665433) (xy 29.527892 -27.580013)
			(xy 29.519874 -27.493484) (xy 24.795988 -27.493484) (xy 24.795988 -30.033484) (xy 29.519874 -30.033484)
			(xy 29.519874 -29.946584) (xy 29.527892 -29.860055) (xy 29.54386 -29.774635) (xy 29.567641 -29.691053)
			(xy 29.599033 -29.610021) (xy 29.637767 -29.532232) (xy 29.683514 -29.458348) (xy 29.735883 -29.389001)
			(xy 29.794427 -29.324781) (xy 29.858647 -29.266237) (xy 29.927994 -29.213868) (xy 30.001878 -29.168121)
			(xy 30.079667 -29.129387) (xy 30.160699 -29.097995) (xy 30.244281 -29.074214) (xy 30.329701 -29.058246)
			(xy 30.41623 -29.050228) (xy 30.50313 -29.050228) (xy 30.589659 -29.058246) (xy 30.675079 -29.074214)
			(xy 30.758661 -29.097995) (xy 30.839693 -29.129387) (xy 30.917482 -29.168121) (xy 30.991366 -29.213868)
			(xy 31.060713 -29.266237) (xy 31.124933 -29.324781) (xy 31.183477 -29.389001) (xy 31.235846 -29.458348)
			(xy 31.281593 -29.532232) (xy 31.320327 -29.610021) (xy 31.351719 -29.691053) (xy 31.3755 -29.774635)
			(xy 31.391468 -29.860055) (xy 31.399486 -29.946584) (xy 31.399988 -29.990034) (xy 31.399486 -30.033484)
			(xy 34.599874 -30.033484) (xy 34.599874 -29.946584) (xy 34.607892 -29.860055) (xy 34.62386 -29.774635)
			(xy 34.647641 -29.691053) (xy 34.679033 -29.610021) (xy 34.717767 -29.532232) (xy 34.763514 -29.458348)
			(xy 34.815883 -29.389001) (xy 34.874427 -29.324781) (xy 34.938647 -29.266237) (xy 35.007994 -29.213868)
			(xy 35.081878 -29.168121) (xy 35.159667 -29.129387) (xy 35.240699 -29.097995) (xy 35.324281 -29.074214)
			(xy 35.409701 -29.058246) (xy 35.49623 -29.050228) (xy 35.58313 -29.050228) (xy 35.669659 -29.058246)
			(xy 35.755079 -29.074214) (xy 35.838661 -29.097995) (xy 35.919693 -29.129387) (xy 35.997482 -29.168121)
			(xy 36.071366 -29.213868) (xy 36.140713 -29.266237) (xy 36.204933 -29.324781) (xy 36.229734 -29.351986)
			(xy 64.927732 -29.351986) (xy 64.931803 -29.296364) (xy 64.943929 -29.241927) (xy 64.963852 -29.189836)
			(xy 64.991148 -29.141201) (xy 65.025234 -29.097058) (xy 65.065383 -29.058349) (xy 65.110741 -29.025898)
			(xy 65.160341 -29.000397) (xy 65.213125 -28.98239) (xy 65.267968 -28.97226) (xy 65.323702 -28.970223)
			(xy 65.379139 -28.976323) (xy 65.433096 -28.990429) (xy 65.484425 -29.012241) (xy 65.532031 -29.041295)
			(xy 65.574899 -29.07697) (xy 65.612116 -29.118507) (xy 65.642889 -29.16502) (xy 65.666561 -29.215517)
			(xy 65.682629 -29.268924) (xy 65.690749 -29.3241) (xy 65.691258 -29.351986) (xy 67.59524 -29.351986)
			(xy 67.599311 -29.296364) (xy 67.611437 -29.241927) (xy 67.63136 -29.189836) (xy 67.658656 -29.141201)
			(xy 67.692742 -29.097058) (xy 67.732891 -29.058349) (xy 67.778249 -29.025898) (xy 67.827849 -29.000397)
			(xy 67.880633 -28.98239) (xy 67.935476 -28.97226) (xy 67.99121 -28.970223) (xy 68.046647 -28.976323)
			(xy 68.100604 -28.990429) (xy 68.151933 -29.012241) (xy 68.199539 -29.041295) (xy 68.242407 -29.07697)
			(xy 68.279624 -29.118507) (xy 68.310397 -29.16502) (xy 68.334069 -29.215517) (xy 68.350137 -29.268924)
			(xy 68.358257 -29.3241) (xy 68.358766 -29.351986) (xy 68.358257 -29.379872) (xy 68.350137 -29.435048)
			(xy 68.334069 -29.488455) (xy 68.310397 -29.538952) (xy 68.279624 -29.585465) (xy 68.242407 -29.627002)
			(xy 68.199539 -29.662677) (xy 68.151933 -29.691731) (xy 68.100604 -29.713543) (xy 68.046647 -29.727649)
			(xy 67.99121 -29.733749) (xy 67.935476 -29.731712) (xy 67.880633 -29.721582) (xy 67.827849 -29.703575)
			(xy 67.778249 -29.678074) (xy 67.732891 -29.645623) (xy 67.692742 -29.606914) (xy 67.658656 -29.562771)
			(xy 67.63136 -29.514136) (xy 67.611437 -29.462045) (xy 67.599311 -29.407608) (xy 67.59524 -29.351986)
			(xy 65.691258 -29.351986) (xy 65.690749 -29.379872) (xy 65.682629 -29.435048) (xy 65.666561 -29.488455)
			(xy 65.642889 -29.538952) (xy 65.612116 -29.585465) (xy 65.574899 -29.627002) (xy 65.532031 -29.662677)
			(xy 65.484425 -29.691731) (xy 65.433096 -29.713543) (xy 65.379139 -29.727649) (xy 65.323702 -29.733749)
			(xy 65.267968 -29.731712) (xy 65.213125 -29.721582) (xy 65.160341 -29.703575) (xy 65.110741 -29.678074)
			(xy 65.065383 -29.645623) (xy 65.025234 -29.606914) (xy 64.991148 -29.562771) (xy 64.963852 -29.514136)
			(xy 64.943929 -29.462045) (xy 64.931803 -29.407608) (xy 64.927732 -29.351986) (xy 36.229734 -29.351986)
			(xy 36.263477 -29.389001) (xy 36.315846 -29.458348) (xy 36.361593 -29.532232) (xy 36.400327 -29.610021)
			(xy 36.431719 -29.691053) (xy 36.4555 -29.774635) (xy 36.471468 -29.860055) (xy 36.479486 -29.946584)
			(xy 36.479988 -29.990034) (xy 36.479486 -30.033484) (xy 36.471468 -30.120013) (xy 36.469415 -30.130998)
			(xy 41.909087 -30.130998) (xy 41.912975 -30.076643) (xy 41.924559 -30.023395) (xy 41.943604 -29.972338)
			(xy 41.969721 -29.924511) (xy 42.002379 -29.880889) (xy 42.040913 -29.842358) (xy 42.084539 -29.809703)
			(xy 42.132368 -29.78359) (xy 42.183427 -29.76455) (xy 42.236676 -29.75297) (xy 42.29103 -29.749087)
			(xy 42.345385 -29.752979) (xy 42.398632 -29.764567) (xy 42.449687 -29.783615) (xy 42.497512 -29.809736)
			(xy 42.5196 -29.825696) (xy 42.538612 -29.839292) (xy 42.580495 -29.860024) (xy 42.625463 -29.87275)
			(xy 42.672 -29.87704) (xy 42.718537 -29.87275) (xy 42.763505 -29.860024) (xy 42.805388 -29.839292)
			(xy 42.8244 -29.825696) (xy 42.846484 -29.809731) (xy 42.89431 -29.783609) (xy 42.945367 -29.764561)
			(xy 42.998614 -29.752972) (xy 43.05297 -29.74908) (xy 43.107325 -29.752964) (xy 43.160575 -29.764544)
			(xy 43.211634 -29.783584) (xy 43.259464 -29.809698) (xy 43.303091 -29.842353) (xy 43.341626 -29.880884)
			(xy 43.374285 -29.924508) (xy 43.400402 -29.972336) (xy 43.419447 -30.023394) (xy 43.431032 -30.076642)
			(xy 43.43492 -30.130998) (xy 43.795779 -30.130998) (xy 43.799668 -30.076642) (xy 43.811252 -30.023392)
			(xy 43.830298 -29.972334) (xy 43.856416 -29.924505) (xy 43.889076 -29.880881) (xy 43.927611 -29.84235)
			(xy 43.971239 -29.809695) (xy 44.01907 -29.783581) (xy 44.07013 -29.764541) (xy 44.123381 -29.752962)
			(xy 44.177737 -29.749079) (xy 44.232093 -29.752973) (xy 44.285341 -29.764562) (xy 44.336398 -29.783612)
			(xy 44.384224 -29.809735) (xy 44.406312 -29.825696) (xy 44.425324 -29.839292) (xy 44.467207 -29.860024)
			(xy 44.512175 -29.87275) (xy 44.558712 -29.87704) (xy 44.605249 -29.87275) (xy 44.650217 -29.860024)
			(xy 44.6921 -29.839292) (xy 44.711112 -29.825696) (xy 44.733196 -29.809732) (xy 44.781021 -29.783612)
			(xy 44.832076 -29.764565) (xy 44.885323 -29.752978) (xy 44.939676 -29.749087) (xy 44.99403 -29.752972)
			(xy 45.047278 -29.764552) (xy 45.098336 -29.783593) (xy 45.146164 -29.809706) (xy 45.189789 -29.842361)
			(xy 45.228322 -29.880891) (xy 45.26098 -29.924514) (xy 45.287096 -29.97234) (xy 45.306141 -30.023397)
			(xy 45.317725 -30.076644) (xy 45.321613 -30.130998) (xy 45.317725 -30.185351) (xy 45.306142 -30.238599)
			(xy 45.287098 -30.289655) (xy 45.260982 -30.337482) (xy 45.228325 -30.381105) (xy 45.189793 -30.419636)
			(xy 45.146168 -30.452291) (xy 45.09834 -30.478405) (xy 45.047283 -30.497447) (xy 44.994035 -30.509028)
			(xy 44.939681 -30.512913) (xy 44.885328 -30.509022) (xy 44.832081 -30.497436) (xy 44.781025 -30.47839)
			(xy 44.7332 -30.452271) (xy 44.711112 -30.436312) (xy 44.6921 -30.422716) (xy 44.650217 -30.401984)
			(xy 44.605249 -30.389258) (xy 44.558712 -30.384968) (xy 44.512175 -30.389258) (xy 44.467207 -30.401984)
			(xy 44.425324 -30.422716) (xy 44.406312 -30.436312) (xy 44.38422 -30.452268) (xy 44.336394 -30.47839)
			(xy 44.285337 -30.497439) (xy 44.232088 -30.509028) (xy 44.177732 -30.512921) (xy 44.123376 -30.509037)
			(xy 44.070126 -30.497457) (xy 44.019065 -30.478417) (xy 43.971235 -30.452303) (xy 43.927608 -30.419647)
			(xy 43.889073 -30.381115) (xy 43.856414 -30.33749) (xy 43.830296 -30.289662) (xy 43.811251 -30.238603)
			(xy 43.799667 -30.185354) (xy 43.795779 -30.130998) (xy 43.43492 -30.130998) (xy 43.431032 -30.185353)
			(xy 43.419449 -30.238602) (xy 43.400404 -30.28966) (xy 43.374287 -30.337488) (xy 43.341629 -30.381112)
			(xy 43.303094 -30.419644) (xy 43.259468 -30.4523) (xy 43.211639 -30.478414) (xy 43.16058 -30.497455)
			(xy 43.10733 -30.509036) (xy 43.052974 -30.51292) (xy 42.998619 -30.509028) (xy 42.945371 -30.497441)
			(xy 42.894315 -30.478393) (xy 42.846488 -30.452272) (xy 42.8244 -30.436312) (xy 42.805388 -30.422716)
			(xy 42.763505 -30.401984) (xy 42.718537 -30.389258) (xy 42.672 -30.384968) (xy 42.625463 -30.389258)
			(xy 42.580495 -30.401984) (xy 42.538612 -30.422716) (xy 42.5196 -30.436312) (xy 42.497508 -30.452267)
			(xy 42.449683 -30.478387) (xy 42.398627 -30.497434) (xy 42.34538 -30.509022) (xy 42.291026 -30.512913)
			(xy 42.236671 -30.509029) (xy 42.183422 -30.497449) (xy 42.132364 -30.478408) (xy 42.084535 -30.452294)
			(xy 42.04091 -30.419639) (xy 42.002376 -30.381108) (xy 41.969718 -30.337484) (xy 41.943602 -30.289657)
			(xy 41.924558 -30.2386) (xy 41.912974 -30.185352) (xy 41.909087 -30.130998) (xy 36.469415 -30.130998)
			(xy 36.4555 -30.205433) (xy 36.431719 -30.289015) (xy 36.400327 -30.370047) (xy 36.361593 -30.447836)
			(xy 36.315846 -30.52172) (xy 36.263477 -30.591067) (xy 36.204933 -30.655287) (xy 36.140713 -30.713831)
			(xy 36.071366 -30.7662) (xy 35.997482 -30.811947) (xy 35.919693 -30.850681) (xy 35.838661 -30.882073)
			(xy 35.755079 -30.905854) (xy 35.669659 -30.921822) (xy 35.58313 -30.92984) (xy 35.49623 -30.92984)
			(xy 35.409701 -30.921822) (xy 35.324281 -30.905854) (xy 35.240699 -30.882073) (xy 35.159667 -30.850681)
			(xy 35.081878 -30.811947) (xy 35.007994 -30.7662) (xy 34.938647 -30.713831) (xy 34.874427 -30.655287)
			(xy 34.815883 -30.591067) (xy 34.763514 -30.52172) (xy 34.717767 -30.447836) (xy 34.679033 -30.370047)
			(xy 34.647641 -30.289015) (xy 34.62386 -30.205433) (xy 34.607892 -30.120013) (xy 34.599874 -30.033484)
			(xy 31.399486 -30.033484) (xy 31.391468 -30.120013) (xy 31.3755 -30.205433) (xy 31.351719 -30.289015)
			(xy 31.320327 -30.370047) (xy 31.281593 -30.447836) (xy 31.235846 -30.52172) (xy 31.183477 -30.591067)
			(xy 31.124933 -30.655287) (xy 31.060713 -30.713831) (xy 30.991366 -30.7662) (xy 30.917482 -30.811947)
			(xy 30.839693 -30.850681) (xy 30.758661 -30.882073) (xy 30.675079 -30.905854) (xy 30.589659 -30.921822)
			(xy 30.50313 -30.92984) (xy 30.41623 -30.92984) (xy 30.329701 -30.921822) (xy 30.244281 -30.905854)
			(xy 30.160699 -30.882073) (xy 30.079667 -30.850681) (xy 30.001878 -30.811947) (xy 29.927994 -30.7662)
			(xy 29.858647 -30.713831) (xy 29.794427 -30.655287) (xy 29.735883 -30.591067) (xy 29.683514 -30.52172)
			(xy 29.637767 -30.447836) (xy 29.599033 -30.370047) (xy 29.567641 -30.289015) (xy 29.54386 -30.205433)
			(xy 29.527892 -30.120013) (xy 29.519874 -30.033484) (xy 24.795988 -30.033484) (xy 24.795988 -32.573484)
			(xy 29.519874 -32.573484) (xy 29.519874 -32.486584) (xy 29.527892 -32.400055) (xy 29.54386 -32.314635)
			(xy 29.567641 -32.231053) (xy 29.599033 -32.150021) (xy 29.637767 -32.072232) (xy 29.683514 -31.998348)
			(xy 29.735883 -31.929001) (xy 29.794427 -31.864781) (xy 29.858647 -31.806237) (xy 29.927994 -31.753868)
			(xy 30.001878 -31.708121) (xy 30.079667 -31.669387) (xy 30.160699 -31.637995) (xy 30.244281 -31.614214)
			(xy 30.329701 -31.598246) (xy 30.41623 -31.590228) (xy 30.50313 -31.590228) (xy 30.589659 -31.598246)
			(xy 30.675079 -31.614214) (xy 30.758661 -31.637995) (xy 30.839693 -31.669387) (xy 30.917482 -31.708121)
			(xy 30.991366 -31.753868) (xy 31.060713 -31.806237) (xy 31.124933 -31.864781) (xy 31.183477 -31.929001)
			(xy 31.235846 -31.998348) (xy 31.281593 -32.072232) (xy 31.320327 -32.150021) (xy 31.351719 -32.231053)
			(xy 31.3755 -32.314635) (xy 31.391468 -32.400055) (xy 31.399486 -32.486584) (xy 31.399988 -32.530034)
			(xy 31.399486 -32.573484) (xy 34.599874 -32.573484) (xy 34.599874 -32.486584) (xy 34.607892 -32.400055)
			(xy 34.62386 -32.314635) (xy 34.647641 -32.231053) (xy 34.679033 -32.150021) (xy 34.717767 -32.072232)
			(xy 34.763514 -31.998348) (xy 34.815883 -31.929001) (xy 34.874427 -31.864781) (xy 34.938647 -31.806237)
			(xy 35.007994 -31.753868) (xy 35.081878 -31.708121) (xy 35.159667 -31.669387) (xy 35.240699 -31.637995)
			(xy 35.324281 -31.614214) (xy 35.409701 -31.598246) (xy 35.49623 -31.590228) (xy 35.58313 -31.590228)
			(xy 35.669659 -31.598246) (xy 35.755079 -31.614214) (xy 35.838661 -31.637995) (xy 35.919693 -31.669387)
			(xy 35.997482 -31.708121) (xy 36.071366 -31.753868) (xy 36.140713 -31.806237) (xy 36.204933 -31.864781)
			(xy 36.263477 -31.929001) (xy 36.315846 -31.998348) (xy 36.336606 -32.031876) (xy 41.909115 -32.031876)
			(xy 41.913006 -31.977526) (xy 41.924593 -31.924283) (xy 41.943639 -31.873231) (xy 41.969757 -31.825409)
			(xy 42.002415 -31.781791) (xy 42.040949 -31.743265) (xy 42.084573 -31.710616) (xy 42.1324 -31.684507)
			(xy 42.183456 -31.665471) (xy 42.236701 -31.653895) (xy 42.291052 -31.650016) (xy 42.345402 -31.65391)
			(xy 42.398644 -31.665501) (xy 42.449695 -31.68455) (xy 42.497515 -31.710672) (xy 42.5196 -31.726632)
			(xy 42.538612 -31.740228) (xy 42.580495 -31.76096) (xy 42.625463 -31.773686) (xy 42.672 -31.777976)
			(xy 42.718537 -31.773686) (xy 42.763505 -31.76096) (xy 42.805388 -31.740228) (xy 42.8244 -31.726632)
			(xy 42.846451 -31.710618) (xy 42.894279 -31.684492) (xy 42.945338 -31.665439) (xy 42.998589 -31.653847)
			(xy 43.052948 -31.649951) (xy 43.107308 -31.653832) (xy 43.160562 -31.66541) (xy 43.211627 -31.684449)
			(xy 43.259462 -31.710562) (xy 43.303093 -31.743217) (xy 43.341633 -31.781749) (xy 43.374297 -31.825374)
			(xy 43.400419 -31.873204) (xy 43.419469 -31.924265) (xy 43.431057 -31.977517) (xy 43.434949 -32.031876)
			(xy 43.795808 -32.031876) (xy 43.799699 -31.977524) (xy 43.811286 -31.92428) (xy 43.830333 -31.873226)
			(xy 43.856452 -31.825403) (xy 43.889112 -31.781784) (xy 43.927647 -31.743257) (xy 43.971273 -31.710607)
			(xy 44.019101 -31.684499) (xy 44.070159 -31.665463) (xy 44.123406 -31.653887) (xy 44.177759 -31.650008)
			(xy 44.23211 -31.653904) (xy 44.285354 -31.665496) (xy 44.336406 -31.684548) (xy 44.384226 -31.710671)
			(xy 44.406312 -31.726632) (xy 44.425324 -31.740228) (xy 44.467207 -31.76096) (xy 44.512175 -31.773686)
			(xy 44.558712 -31.777976) (xy 44.605249 -31.773686) (xy 44.650217 -31.76096) (xy 44.6921 -31.740228)
			(xy 44.711112 -31.726632) (xy 44.733162 -31.710619) (xy 44.780989 -31.684495) (xy 44.832048 -31.665444)
			(xy 44.885297 -31.653853) (xy 44.939655 -31.649959) (xy 44.994013 -31.65384) (xy 45.047266 -31.665418)
			(xy 45.098328 -31.684458) (xy 45.146162 -31.71057) (xy 45.189792 -31.743225) (xy 45.22833 -31.781756)
			(xy 45.260992 -31.82538) (xy 45.287114 -31.873209) (xy 45.306162 -31.924268) (xy 45.31775 -31.977518)
			(xy 45.321641 -32.031876) (xy 45.317757 -32.086234) (xy 45.306176 -32.139486) (xy 45.287134 -32.190548)
			(xy 45.261018 -32.238379) (xy 45.228361 -32.282008) (xy 45.189828 -32.320544) (xy 45.146202 -32.353204)
			(xy 45.098372 -32.379323) (xy 45.047312 -32.398368) (xy 44.994061 -32.409953) (xy 44.939703 -32.413841)
			(xy 44.885345 -32.409954) (xy 44.832094 -32.39837) (xy 44.781033 -32.379325) (xy 44.733203 -32.353207)
			(xy 44.711112 -32.337248) (xy 44.6921 -32.323652) (xy 44.650217 -32.30292) (xy 44.605249 -32.290194)
			(xy 44.558712 -32.285904) (xy 44.512175 -32.290194) (xy 44.467207 -32.30292) (xy 44.425324 -32.323652)
			(xy 44.406312 -32.337248) (xy 44.384186 -32.353155) (xy 44.336362 -32.379272) (xy 44.285308 -32.398318)
			(xy 44.232063 -32.409903) (xy 44.177711 -32.413792) (xy 44.123359 -32.409906) (xy 44.070113 -32.398324)
			(xy 44.019058 -32.379281) (xy 43.971232 -32.353167) (xy 43.92761 -32.320511) (xy 43.88908 -32.28198)
			(xy 43.856426 -32.238357) (xy 43.830313 -32.19053) (xy 43.811273 -32.139474) (xy 43.799692 -32.086228)
			(xy 43.795808 -32.031876) (xy 43.434949 -32.031876) (xy 43.431064 -32.086236) (xy 43.419482 -32.139489)
			(xy 43.400439 -32.190552) (xy 43.374323 -32.238385) (xy 43.341665 -32.282015) (xy 43.30313 -32.320552)
			(xy 43.259502 -32.353212) (xy 43.21167 -32.379331) (xy 43.160608 -32.398377) (xy 43.107355 -32.409961)
			(xy 43.052996 -32.413849) (xy 42.998637 -32.40996) (xy 42.945384 -32.398374) (xy 42.894322 -32.379328)
			(xy 42.846491 -32.353208) (xy 42.8244 -32.337248) (xy 42.805388 -32.323652) (xy 42.763505 -32.30292)
			(xy 42.718537 -32.290194) (xy 42.672 -32.285904) (xy 42.625463 -32.290194) (xy 42.580495 -32.30292)
			(xy 42.538612 -32.323652) (xy 42.5196 -32.337248) (xy 42.497474 -32.353154) (xy 42.449651 -32.37927)
			(xy 42.398598 -32.398313) (xy 42.345354 -32.409897) (xy 42.291004 -32.413785) (xy 42.236654 -32.409898)
			(xy 42.18341 -32.398315) (xy 42.132356 -32.379273) (xy 42.084532 -32.353158) (xy 42.040912 -32.320503)
			(xy 42.002384 -32.281973) (xy 41.969731 -32.238351) (xy 41.943619 -32.190526) (xy 41.924579 -32.139471)
			(xy 41.912999 -32.086227) (xy 41.909115 -32.031876) (xy 36.336606 -32.031876) (xy 36.361593 -32.072232)
			(xy 36.400327 -32.150021) (xy 36.431719 -32.231053) (xy 36.4555 -32.314635) (xy 36.471468 -32.400055)
			(xy 36.479486 -32.486584) (xy 36.479988 -32.530034) (xy 36.479486 -32.573484) (xy 36.478687 -32.582104)
			(xy 64.88252 -32.582104) (xy 64.886591 -32.526482) (xy 64.898717 -32.472045) (xy 64.91864 -32.419954)
			(xy 64.945936 -32.371319) (xy 64.980022 -32.327176) (xy 65.020171 -32.288467) (xy 65.065529 -32.256016)
			(xy 65.115129 -32.230515) (xy 65.167913 -32.212508) (xy 65.222756 -32.202378) (xy 65.27849 -32.200341)
			(xy 65.333927 -32.206441) (xy 65.387884 -32.220547) (xy 65.439213 -32.242359) (xy 65.486819 -32.271413)
			(xy 65.520757 -32.299656) (xy 72.868035 -32.299656) (xy 72.872042 -32.096906) (xy 72.884055 -31.894472)
			(xy 72.904056 -31.692671) (xy 72.932015 -31.491817) (xy 72.967886 -31.292225) (xy 73.011615 -31.094206)
			(xy 73.063133 -30.898069) (xy 73.122359 -30.704121) (xy 73.189201 -30.512663) (xy 73.263555 -30.323996)
			(xy 73.345304 -30.138414) (xy 73.434322 -29.956206) (xy 73.530468 -29.777657) (xy 73.633593 -29.603046)
			(xy 73.743536 -29.432646) (xy 73.860125 -29.266722) (xy 73.983178 -29.105533) (xy 74.112503 -28.949332)
			(xy 74.247898 -28.798362) (xy 74.389151 -28.652858) (xy 74.536043 -28.513049) (xy 74.688343 -28.379152)
			(xy 74.845814 -28.251377) (xy 75.008211 -28.129922) (xy 75.175278 -28.014978) (xy 75.346757 -27.906724)
			(xy 75.522378 -27.805329) (xy 75.701868 -27.710951) (xy 75.884946 -27.623739) (xy 76.071327 -27.543827)
			(xy 76.26072 -27.47134) (xy 76.452828 -27.406393) (xy 76.647352 -27.349085) (xy 76.843988 -27.299508)
			(xy 77.04243 -27.257737) (xy 77.242367 -27.223839) (xy 77.443486 -27.197867) (xy 77.645475 -27.17986)
			(xy 77.848018 -27.169847) (xy 78.050798 -27.167843) (xy 78.253499 -27.173853) (xy 78.455804 -27.187865)
			(xy 78.657398 -27.20986) (xy 78.857965 -27.239801) (xy 79.057193 -27.277642) (xy 79.254771 -27.323325)
			(xy 79.450389 -27.376778) (xy 79.643743 -27.437917) (xy 79.834531 -27.506648) (xy 80.022454 -27.582862)
			(xy 80.20722 -27.666441) (xy 80.388539 -27.757254) (xy 80.56613 -27.855159) (xy 80.739713 -27.960004)
			(xy 80.909019 -28.071625) (xy 81.073784 -28.189847) (xy 81.233749 -28.314487) (xy 81.388665 -28.445348)
			(xy 81.53829 -28.582228) (xy 81.68239 -28.724912) (xy 81.820742 -28.873178) (xy 81.953127 -29.026794)
			(xy 82.079341 -29.185519) (xy 82.199185 -29.349108) (xy 82.312473 -29.517303) (xy 82.419028 -29.689842)
			(xy 82.518683 -29.866457) (xy 82.611283 -30.04687) (xy 82.696683 -30.230801) (xy 82.77475 -30.417962)
			(xy 82.845362 -30.608062) (xy 82.908408 -30.800802) (xy 82.963791 -30.995883) (xy 83.011423 -31.193)
			(xy 83.051231 -31.391844) (xy 83.083153 -31.592106) (xy 83.107137 -31.793472) (xy 83.123148 -31.995629)
			(xy 83.131159 -32.198261) (xy 83.13166 -32.299656) (xy 83.131159 -32.401051) (xy 83.123148 -32.603683)
			(xy 83.107137 -32.80584) (xy 83.083153 -33.007206) (xy 83.051231 -33.207468) (xy 83.011423 -33.406312)
			(xy 82.963791 -33.603429) (xy 82.908408 -33.79851) (xy 82.845362 -33.99125) (xy 82.77475 -34.18135)
			(xy 82.696683 -34.368511) (xy 82.611283 -34.552442) (xy 82.518683 -34.732855) (xy 82.419028 -34.90947)
			(xy 82.312473 -35.082009) (xy 82.199185 -35.250204) (xy 82.079341 -35.413793) (xy 81.953127 -35.572518)
			(xy 81.820742 -35.726134) (xy 81.68239 -35.8744) (xy 81.53829 -36.017084) (xy 81.388665 -36.153964)
			(xy 81.233749 -36.284825) (xy 81.073784 -36.409465) (xy 80.909019 -36.527687) (xy 80.739713 -36.639308)
			(xy 80.56613 -36.744153) (xy 80.388539 -36.842058) (xy 80.20722 -36.932871) (xy 80.022454 -37.01645)
			(xy 79.834531 -37.092664) (xy 79.643743 -37.161395) (xy 79.450389 -37.222534) (xy 79.254771 -37.275987)
			(xy 79.057193 -37.32167) (xy 78.857965 -37.359511) (xy 78.657398 -37.389452) (xy 78.455804 -37.411447)
			(xy 78.253499 -37.425459) (xy 78.050798 -37.431469) (xy 77.848018 -37.429465) (xy 77.645475 -37.419452)
			(xy 77.443486 -37.401445) (xy 77.242367 -37.375473) (xy 77.04243 -37.341575) (xy 76.843988 -37.299804)
			(xy 76.647352 -37.250227) (xy 76.452828 -37.192919) (xy 76.26072 -37.127972) (xy 76.071327 -37.055485)
			(xy 75.884946 -36.975573) (xy 75.701868 -36.888361) (xy 75.522378 -36.793983) (xy 75.346757 -36.692588)
			(xy 75.175278 -36.584334) (xy 75.008211 -36.46939) (xy 74.845814 -36.347935) (xy 74.688343 -36.22016)
			(xy 74.536043 -36.086263) (xy 74.389151 -35.946454) (xy 74.247898 -35.80095) (xy 74.112503 -35.64998)
			(xy 73.983178 -35.493779) (xy 73.860125 -35.33259) (xy 73.743536 -35.166666) (xy 73.633593 -34.996266)
			(xy 73.530468 -34.821655) (xy 73.434322 -34.643106) (xy 73.345304 -34.460898) (xy 73.263555 -34.275316)
			(xy 73.189201 -34.086649) (xy 73.122359 -33.895191) (xy 73.063133 -33.701243) (xy 73.011615 -33.505106)
			(xy 72.967886 -33.307087) (xy 72.932015 -33.107495) (xy 72.904056 -32.906641) (xy 72.884055 -32.70484)
			(xy 72.872042 -32.502406) (xy 72.868035 -32.299656) (xy 65.520757 -32.299656) (xy 65.529687 -32.307088)
			(xy 65.566904 -32.348625) (xy 65.597677 -32.395138) (xy 65.621349 -32.445635) (xy 65.637417 -32.499042)
			(xy 65.645537 -32.554218) (xy 65.646046 -32.582104) (xy 65.645537 -32.60999) (xy 65.637417 -32.665166)
			(xy 65.621349 -32.718573) (xy 65.597677 -32.76907) (xy 65.566904 -32.815583) (xy 65.529687 -32.85712)
			(xy 65.486819 -32.892795) (xy 65.439213 -32.921849) (xy 65.387884 -32.943661) (xy 65.333927 -32.957767)
			(xy 65.27849 -32.963867) (xy 65.222756 -32.96183) (xy 65.167913 -32.9517) (xy 65.115129 -32.933693)
			(xy 65.065529 -32.908192) (xy 65.020171 -32.875741) (xy 64.980022 -32.837032) (xy 64.945936 -32.792889)
			(xy 64.91864 -32.744254) (xy 64.898717 -32.692163) (xy 64.886591 -32.637726) (xy 64.88252 -32.582104)
			(xy 36.478687 -32.582104) (xy 36.471468 -32.660013) (xy 36.4555 -32.745433) (xy 36.431719 -32.829015)
			(xy 36.400327 -32.910047) (xy 36.361593 -32.987836) (xy 36.315846 -33.06172) (xy 36.263477 -33.131067)
			(xy 36.204933 -33.195287) (xy 36.140713 -33.253831) (xy 36.071366 -33.3062) (xy 35.997482 -33.351947)
			(xy 35.919693 -33.390681) (xy 35.838661 -33.422073) (xy 35.755079 -33.445854) (xy 35.669659 -33.461822)
			(xy 35.58313 -33.46984) (xy 35.49623 -33.46984) (xy 35.409701 -33.461822) (xy 35.324281 -33.445854)
			(xy 35.240699 -33.422073) (xy 35.159667 -33.390681) (xy 35.081878 -33.351947) (xy 35.007994 -33.3062)
			(xy 34.938647 -33.253831) (xy 34.874427 -33.195287) (xy 34.815883 -33.131067) (xy 34.763514 -33.06172)
			(xy 34.717767 -32.987836) (xy 34.679033 -32.910047) (xy 34.647641 -32.829015) (xy 34.62386 -32.745433)
			(xy 34.607892 -32.660013) (xy 34.599874 -32.573484) (xy 31.399486 -32.573484) (xy 31.391468 -32.660013)
			(xy 31.3755 -32.745433) (xy 31.351719 -32.829015) (xy 31.320327 -32.910047) (xy 31.281593 -32.987836)
			(xy 31.235846 -33.06172) (xy 31.183477 -33.131067) (xy 31.124933 -33.195287) (xy 31.060713 -33.253831)
			(xy 30.991366 -33.3062) (xy 30.917482 -33.351947) (xy 30.839693 -33.390681) (xy 30.758661 -33.422073)
			(xy 30.675079 -33.445854) (xy 30.589659 -33.461822) (xy 30.50313 -33.46984) (xy 30.41623 -33.46984)
			(xy 30.329701 -33.461822) (xy 30.244281 -33.445854) (xy 30.160699 -33.422073) (xy 30.079667 -33.390681)
			(xy 30.001878 -33.351947) (xy 29.927994 -33.3062) (xy 29.858647 -33.253831) (xy 29.794427 -33.195287)
			(xy 29.735883 -33.131067) (xy 29.683514 -33.06172) (xy 29.637767 -32.987836) (xy 29.599033 -32.910047)
			(xy 29.567641 -32.829015) (xy 29.54386 -32.745433) (xy 29.527892 -32.660013) (xy 29.519874 -32.573484)
			(xy 24.795988 -32.573484) (xy 24.795988 -33.707118) (xy 41.909059 -33.707118) (xy 41.912945 -33.652759)
			(xy 41.924527 -33.599507) (xy 41.94357 -33.548446) (xy 41.969687 -33.500614) (xy 42.002345 -33.456986)
			(xy 42.04088 -33.41845) (xy 42.084507 -33.385791) (xy 42.132338 -33.359674) (xy 42.1834 -33.340629)
			(xy 42.236652 -33.329046) (xy 42.29101 -33.325159) (xy 42.345368 -33.329049) (xy 42.39862 -33.340635)
			(xy 42.44968 -33.359682) (xy 42.49751 -33.385802) (xy 42.5196 -33.401762) (xy 42.538612 -33.415358)
			(xy 42.580495 -33.43609) (xy 42.625463 -33.448816) (xy 42.672 -33.453106) (xy 42.718537 -33.448816)
			(xy 42.763505 -33.43609) (xy 42.805388 -33.415358) (xy 42.8244 -33.401762) (xy 42.846516 -33.385843)
			(xy 42.89434 -33.359726) (xy 42.945394 -33.340681) (xy 42.998639 -33.329096) (xy 43.05299 -33.325207)
			(xy 43.107342 -33.329094) (xy 43.160587 -33.340675) (xy 43.211642 -33.359717) (xy 43.259467 -33.385832)
			(xy 43.303088 -33.418487) (xy 43.341619 -33.457018) (xy 43.374273 -33.50064) (xy 43.400386 -33.548466)
			(xy 43.419427 -33.599521) (xy 43.431008 -33.652766) (xy 43.434893 -33.707118) (xy 43.795752 -33.707118)
			(xy 43.799638 -33.652758) (xy 43.811221 -33.599504) (xy 43.830265 -33.548441) (xy 43.856382 -33.500608)
			(xy 43.889042 -33.456979) (xy 43.927578 -33.418443) (xy 43.971207 -33.385783) (xy 44.01904 -33.359665)
			(xy 44.070103 -33.340621) (xy 44.123357 -33.329038) (xy 44.177717 -33.325152) (xy 44.232077 -33.329043)
			(xy 44.285329 -33.34063) (xy 44.336391 -33.359679) (xy 44.384221 -33.385801) (xy 44.406312 -33.401762)
			(xy 44.425324 -33.415358) (xy 44.467207 -33.43609) (xy 44.512175 -33.448816) (xy 44.558712 -33.453106)
			(xy 44.605249 -33.448816) (xy 44.650217 -33.43609) (xy 44.6921 -33.415358) (xy 44.711112 -33.401762)
			(xy 44.733228 -33.385844) (xy 44.781051 -33.359729) (xy 44.832104 -33.340686) (xy 44.885347 -33.329102)
			(xy 44.939697 -33.325215) (xy 44.994047 -33.329102) (xy 45.04729 -33.340684) (xy 45.098343 -33.359726)
			(xy 45.146167 -33.38584) (xy 45.189787 -33.418495) (xy 45.228315 -33.457025) (xy 45.260968 -33.500646)
			(xy 45.28708 -33.54847) (xy 45.30612 -33.599524) (xy 45.317701 -33.652768) (xy 45.321585 -33.707118)
			(xy 45.317695 -33.761468) (xy 45.30611 -33.814711) (xy 45.287065 -33.865763) (xy 45.260948 -33.913584)
			(xy 45.228292 -33.957203) (xy 45.189759 -33.995729) (xy 45.146136 -34.028379) (xy 45.09831 -34.054489)
			(xy 45.047256 -34.073526) (xy 44.994011 -34.085104) (xy 44.939661 -34.088985) (xy 44.885311 -34.085092)
			(xy 44.832069 -34.073504) (xy 44.781018 -34.054456) (xy 44.733198 -34.028337) (xy 44.711112 -34.012378)
			(xy 44.6921 -33.998782) (xy 44.650217 -33.97805) (xy 44.605249 -33.965324) (xy 44.558712 -33.961034)
			(xy 44.512175 -33.965324) (xy 44.467207 -33.97805) (xy 44.425324 -33.998782) (xy 44.406312 -34.012378)
			(xy 44.384252 -34.028379) (xy 44.336424 -34.054506) (xy 44.285364 -34.073559) (xy 44.232112 -34.085152)
			(xy 44.177753 -34.089048) (xy 44.123392 -34.085167) (xy 44.070138 -34.073589) (xy 44.019073 -34.05455)
			(xy 43.971237 -34.028437) (xy 43.927605 -33.995781) (xy 43.889065 -33.957248) (xy 43.856402 -33.913622)
			(xy 43.83028 -33.865792) (xy 43.811231 -33.81473) (xy 43.799643 -33.761478) (xy 43.795752 -33.707118)
			(xy 43.434893 -33.707118) (xy 43.431002 -33.761469) (xy 43.419417 -33.814714) (xy 43.400371 -33.865767)
			(xy 43.374253 -33.91359) (xy 43.341595 -33.95721) (xy 43.303061 -33.995737) (xy 43.259437 -34.028388)
			(xy 43.211609 -34.054498) (xy 43.160552 -34.073535) (xy 43.107306 -34.085112) (xy 43.052954 -34.088993)
			(xy 42.998603 -34.085098) (xy 42.945359 -34.073509) (xy 42.894307 -34.054459) (xy 42.846486 -34.028338)
			(xy 42.8244 -34.012378) (xy 42.805388 -33.998782) (xy 42.763505 -33.97805) (xy 42.718537 -33.965324)
			(xy 42.672 -33.961034) (xy 42.625463 -33.965324) (xy 42.580495 -33.97805) (xy 42.538612 -33.998782)
			(xy 42.5196 -34.012378) (xy 42.49754 -34.028378) (xy 42.449713 -34.054503) (xy 42.398654 -34.073555)
			(xy 42.345404 -34.085146) (xy 42.291046 -34.089041) (xy 42.236687 -34.085159) (xy 42.183434 -34.073581)
			(xy 42.132371 -34.054541) (xy 42.084538 -34.028428) (xy 42.040907 -33.995773) (xy 42.002369 -33.957241)
			(xy 41.969706 -33.913616) (xy 41.943585 -33.865787) (xy 41.924537 -33.814727) (xy 41.91295 -33.761476)
			(xy 41.909059 -33.707118) (xy 24.795988 -33.707118) (xy 24.795988 -35.113484) (xy 29.519874 -35.113484)
			(xy 29.519874 -35.026584) (xy 29.527892 -34.940055) (xy 29.54386 -34.854635) (xy 29.567641 -34.771053)
			(xy 29.599033 -34.690021) (xy 29.637767 -34.612232) (xy 29.683514 -34.538348) (xy 29.735883 -34.469001)
			(xy 29.794427 -34.404781) (xy 29.858647 -34.346237) (xy 29.927994 -34.293868) (xy 30.001878 -34.248121)
			(xy 30.079667 -34.209387) (xy 30.160699 -34.177995) (xy 30.244281 -34.154214) (xy 30.329701 -34.138246)
			(xy 30.41623 -34.130228) (xy 30.50313 -34.130228) (xy 30.589659 -34.138246) (xy 30.675079 -34.154214)
			(xy 30.758661 -34.177995) (xy 30.839693 -34.209387) (xy 30.917482 -34.248121) (xy 30.991366 -34.293868)
			(xy 31.060713 -34.346237) (xy 31.124933 -34.404781) (xy 31.183477 -34.469001) (xy 31.235846 -34.538348)
			(xy 31.281593 -34.612232) (xy 31.320327 -34.690021) (xy 31.351719 -34.771053) (xy 31.3755 -34.854635)
			(xy 31.391468 -34.940055) (xy 31.399486 -35.026584) (xy 31.399988 -35.070034) (xy 31.399486 -35.113484)
			(xy 34.599874 -35.113484) (xy 34.599874 -35.026584) (xy 34.607892 -34.940055) (xy 34.62386 -34.854635)
			(xy 34.647641 -34.771053) (xy 34.679033 -34.690021) (xy 34.717767 -34.612232) (xy 34.763514 -34.538348)
			(xy 34.815883 -34.469001) (xy 34.874427 -34.404781) (xy 34.938647 -34.346237) (xy 35.007994 -34.293868)
			(xy 35.081878 -34.248121) (xy 35.159667 -34.209387) (xy 35.240699 -34.177995) (xy 35.324281 -34.154214)
			(xy 35.409701 -34.138246) (xy 35.49623 -34.130228) (xy 35.58313 -34.130228) (xy 35.669659 -34.138246)
			(xy 35.755079 -34.154214) (xy 35.838661 -34.177995) (xy 35.919693 -34.209387) (xy 35.997482 -34.248121)
			(xy 36.071366 -34.293868) (xy 36.140713 -34.346237) (xy 36.204933 -34.404781) (xy 36.263477 -34.469001)
			(xy 36.315846 -34.538348) (xy 36.361593 -34.612232) (xy 36.400327 -34.690021) (xy 36.431719 -34.771053)
			(xy 36.4555 -34.854635) (xy 36.471468 -34.940055) (xy 36.479486 -35.026584) (xy 36.479988 -35.070034)
			(xy 36.479486 -35.113484) (xy 36.471468 -35.200013) (xy 36.4555 -35.285433) (xy 36.431719 -35.369015)
			(xy 36.400327 -35.450047) (xy 36.361593 -35.527836) (xy 36.315846 -35.60172) (xy 36.263477 -35.671067)
			(xy 36.220533 -35.718175) (xy 41.865737 -35.718175) (xy 41.869628 -35.66383) (xy 41.881213 -35.610591)
			(xy 41.900257 -35.559543) (xy 41.926372 -35.511726) (xy 41.959027 -35.468111) (xy 41.997556 -35.429588)
			(xy 42.041175 -35.39694) (xy 42.088997 -35.370833) (xy 42.140048 -35.351796) (xy 42.193288 -35.34022)
			(xy 42.247634 -35.336337) (xy 42.301979 -35.340229) (xy 42.355217 -35.351816) (xy 42.406264 -35.370861)
			(xy 42.454082 -35.396977) (xy 42.476166 -35.412934) (xy 42.495178 -35.42653) (xy 42.537061 -35.447262)
			(xy 42.582029 -35.459988) (xy 42.628566 -35.464278) (xy 42.675103 -35.459988) (xy 42.720071 -35.447262)
			(xy 42.761954 -35.42653) (xy 42.780966 -35.412934) (xy 42.803016 -35.396915) (xy 42.850846 -35.370783)
			(xy 42.901909 -35.351725) (xy 42.955164 -35.340128) (xy 43.009527 -35.336229) (xy 43.063892 -35.340108)
			(xy 43.117152 -35.351684) (xy 43.168222 -35.370723) (xy 43.216062 -35.396836) (xy 43.259699 -35.429493)
			(xy 43.298243 -35.468027) (xy 43.330911 -35.511655) (xy 43.357037 -35.559489) (xy 43.376088 -35.610554)
			(xy 43.387678 -35.663811) (xy 43.391571 -35.718175) (xy 43.75243 -35.718175) (xy 43.756321 -35.663828)
			(xy 43.767907 -35.610588) (xy 43.786951 -35.559539) (xy 43.813067 -35.51172) (xy 43.845723 -35.468104)
			(xy 43.884254 -35.42958) (xy 43.927875 -35.396932) (xy 43.975699 -35.370824) (xy 44.026751 -35.351788)
			(xy 44.079993 -35.340212) (xy 44.134341 -35.33633) (xy 44.188687 -35.340223) (xy 44.241927 -35.351811)
			(xy 44.292975 -35.370858) (xy 44.340793 -35.396976) (xy 44.362878 -35.412934) (xy 44.38189 -35.42653)
			(xy 44.423773 -35.447262) (xy 44.468741 -35.459988) (xy 44.515278 -35.464278) (xy 44.561815 -35.459988)
			(xy 44.606783 -35.447262) (xy 44.648666 -35.42653) (xy 44.667678 -35.412934) (xy 44.689727 -35.396916)
			(xy 44.737557 -35.370786) (xy 44.788618 -35.351729) (xy 44.841872 -35.340134) (xy 44.896234 -35.336237)
			(xy 44.950598 -35.340116) (xy 45.003855 -35.351692) (xy 45.054924 -35.370731) (xy 45.102762 -35.396844)
			(xy 45.146397 -35.4295) (xy 45.18494 -35.468034) (xy 45.217606 -35.511661) (xy 45.243731 -35.559494)
			(xy 45.262782 -35.610557) (xy 45.274371 -35.663812) (xy 45.278263 -35.718175) (xy 45.274379 -35.772538)
			(xy 45.262796 -35.825794) (xy 45.243752 -35.87686) (xy 45.217634 -35.924696) (xy 45.184973 -35.968328)
			(xy 45.146435 -36.006867) (xy 45.102804 -36.039528) (xy 45.054969 -36.065648) (xy 45.003904 -36.084693)
			(xy 44.950648 -36.096277) (xy 44.896285 -36.100163) (xy 44.841922 -36.096273) (xy 44.788667 -36.084685)
			(xy 44.737603 -36.065635) (xy 44.68977 -36.039512) (xy 44.667678 -36.02355) (xy 44.648666 -36.009954)
			(xy 44.606783 -35.989222) (xy 44.561815 -35.976496) (xy 44.515278 -35.972206) (xy 44.468741 -35.976496)
			(xy 44.423773 -35.989222) (xy 44.38189 -36.009954) (xy 44.362878 -36.02355) (xy 44.340751 -36.039451)
			(xy 44.292929 -36.065563) (xy 44.241879 -36.084603) (xy 44.188638 -36.096184) (xy 44.13429 -36.10007)
			(xy 44.079943 -36.096181) (xy 44.026703 -36.084598) (xy 43.975653 -36.065555) (xy 43.927833 -36.039441)
			(xy 43.884216 -36.006787) (xy 43.84569 -35.968258) (xy 43.81304 -35.924638) (xy 43.78693 -35.876815)
			(xy 43.767892 -35.825764) (xy 43.756314 -35.772522) (xy 43.75243 -35.718175) (xy 43.391571 -35.718175)
			(xy 43.387686 -35.772539) (xy 43.376103 -35.825798) (xy 43.357058 -35.876865) (xy 43.330938 -35.924702)
			(xy 43.298276 -35.968335) (xy 43.259737 -36.006874) (xy 43.216105 -36.039537) (xy 43.168268 -36.065656)
			(xy 43.117201 -36.084702) (xy 43.063942 -36.096285) (xy 43.009578 -36.100171) (xy 42.955214 -36.096279)
			(xy 42.901957 -36.084689) (xy 42.850892 -36.065638) (xy 42.803058 -36.039513) (xy 42.780966 -36.02355)
			(xy 42.761954 -36.009954) (xy 42.720071 -35.989222) (xy 42.675103 -35.976496) (xy 42.628566 -35.972206)
			(xy 42.582029 -35.976496) (xy 42.537061 -35.989222) (xy 42.495178 -36.009954) (xy 42.476166 -36.02355)
			(xy 42.454039 -36.03945) (xy 42.406219 -36.06556) (xy 42.355169 -36.084599) (xy 42.301929 -36.096178)
			(xy 42.247583 -36.100063) (xy 42.193238 -36.096173) (xy 42.14 -36.084589) (xy 42.088951 -36.065547)
			(xy 42.041133 -36.039433) (xy 41.997518 -36.006779) (xy 41.958994 -35.968251) (xy 41.926345 -35.924632)
			(xy 41.900236 -35.876811) (xy 41.881199 -35.82576) (xy 41.869621 -35.772521) (xy 41.865737 -35.718175)
			(xy 36.220533 -35.718175) (xy 36.204933 -35.735287) (xy 36.140713 -35.793831) (xy 36.071366 -35.8462)
			(xy 35.997482 -35.891947) (xy 35.919693 -35.930681) (xy 35.838661 -35.962073) (xy 35.755079 -35.985854)
			(xy 35.669659 -36.001822) (xy 35.58313 -36.00984) (xy 35.49623 -36.00984) (xy 35.409701 -36.001822)
			(xy 35.324281 -35.985854) (xy 35.240699 -35.962073) (xy 35.159667 -35.930681) (xy 35.081878 -35.891947)
			(xy 35.007994 -35.8462) (xy 34.938647 -35.793831) (xy 34.874427 -35.735287) (xy 34.815883 -35.671067)
			(xy 34.763514 -35.60172) (xy 34.717767 -35.527836) (xy 34.679033 -35.450047) (xy 34.647641 -35.369015)
			(xy 34.62386 -35.285433) (xy 34.607892 -35.200013) (xy 34.599874 -35.113484) (xy 31.399486 -35.113484)
			(xy 31.391468 -35.200013) (xy 31.3755 -35.285433) (xy 31.351719 -35.369015) (xy 31.320327 -35.450047)
			(xy 31.281593 -35.527836) (xy 31.235846 -35.60172) (xy 31.183477 -35.671067) (xy 31.124933 -35.735287)
			(xy 31.060713 -35.793831) (xy 30.991366 -35.8462) (xy 30.917482 -35.891947) (xy 30.839693 -35.930681)
			(xy 30.758661 -35.962073) (xy 30.675079 -35.985854) (xy 30.589659 -36.001822) (xy 30.50313 -36.00984)
			(xy 30.41623 -36.00984) (xy 30.329701 -36.001822) (xy 30.244281 -35.985854) (xy 30.160699 -35.962073)
			(xy 30.079667 -35.930681) (xy 30.001878 -35.891947) (xy 29.927994 -35.8462) (xy 29.858647 -35.793831)
			(xy 29.794427 -35.735287) (xy 29.735883 -35.671067) (xy 29.683514 -35.60172) (xy 29.637767 -35.527836)
			(xy 29.599033 -35.450047) (xy 29.567641 -35.369015) (xy 29.54386 -35.285433) (xy 29.527892 -35.200013)
			(xy 29.519874 -35.113484) (xy 24.795988 -35.113484) (xy 24.795988 -37.653484) (xy 29.519874 -37.653484)
			(xy 29.519874 -37.566584) (xy 29.527892 -37.480055) (xy 29.54386 -37.394635) (xy 29.567641 -37.311053)
			(xy 29.599033 -37.230021) (xy 29.637767 -37.152232) (xy 29.683514 -37.078348) (xy 29.735883 -37.009001)
			(xy 29.794427 -36.944781) (xy 29.858647 -36.886237) (xy 29.927994 -36.833868) (xy 30.001878 -36.788121)
			(xy 30.079667 -36.749387) (xy 30.160699 -36.717995) (xy 30.244281 -36.694214) (xy 30.329701 -36.678246)
			(xy 30.41623 -36.670228) (xy 30.50313 -36.670228) (xy 30.589659 -36.678246) (xy 30.675079 -36.694214)
			(xy 30.758661 -36.717995) (xy 30.839693 -36.749387) (xy 30.917482 -36.788121) (xy 30.991366 -36.833868)
			(xy 31.060713 -36.886237) (xy 31.124933 -36.944781) (xy 31.183477 -37.009001) (xy 31.235846 -37.078348)
			(xy 31.281593 -37.152232) (xy 31.320327 -37.230021) (xy 31.351719 -37.311053) (xy 31.3755 -37.394635)
			(xy 31.391468 -37.480055) (xy 31.399486 -37.566584) (xy 31.399988 -37.610034) (xy 31.399486 -37.653484)
			(xy 34.599874 -37.653484) (xy 34.599874 -37.566584) (xy 34.607892 -37.480055) (xy 34.62386 -37.394635)
			(xy 34.647641 -37.311053) (xy 34.679033 -37.230021) (xy 34.717767 -37.152232) (xy 34.763514 -37.078348)
			(xy 34.815883 -37.009001) (xy 34.874427 -36.944781) (xy 34.938647 -36.886237) (xy 35.007994 -36.833868)
			(xy 35.081878 -36.788121) (xy 35.159667 -36.749387) (xy 35.240699 -36.717995) (xy 35.324281 -36.694214)
			(xy 35.409701 -36.678246) (xy 35.49623 -36.670228) (xy 35.58313 -36.670228) (xy 35.669659 -36.678246)
			(xy 35.755079 -36.694214) (xy 35.838661 -36.717995) (xy 35.919693 -36.749387) (xy 35.997482 -36.788121)
			(xy 36.071366 -36.833868) (xy 36.140713 -36.886237) (xy 36.204933 -36.944781) (xy 36.263477 -37.009001)
			(xy 36.315846 -37.078348) (xy 36.361593 -37.152232) (xy 36.400327 -37.230021) (xy 36.431719 -37.311053)
			(xy 36.4555 -37.394635) (xy 36.471468 -37.480055) (xy 36.479486 -37.566584) (xy 36.479974 -37.608822)
			(xy 41.865675 -37.608822) (xy 41.86956 -37.554467) (xy 41.88114 -37.501219) (xy 41.900181 -37.45016)
			(xy 41.926294 -37.402331) (xy 41.958949 -37.358706) (xy 41.99748 -37.320171) (xy 42.041102 -37.287513)
			(xy 42.088929 -37.261395) (xy 42.139985 -37.24235) (xy 42.193233 -37.230764) (xy 42.247587 -37.226875)
			(xy 42.301942 -37.230761) (xy 42.35519 -37.242342) (xy 42.406248 -37.261384) (xy 42.454076 -37.287499)
			(xy 42.476166 -37.303456) (xy 42.495178 -37.317052) (xy 42.537061 -37.337784) (xy 42.582029 -37.35051)
			(xy 42.628566 -37.3548) (xy 42.675103 -37.35051) (xy 42.720071 -37.337784) (xy 42.761954 -37.317052)
			(xy 42.780966 -37.303456) (xy 42.803089 -37.287542) (xy 42.850914 -37.26142) (xy 42.901971 -37.242372)
			(xy 42.955219 -37.230783) (xy 43.009574 -37.226892) (xy 43.06393 -37.230776) (xy 43.117179 -37.242357)
			(xy 43.168239 -37.261399) (xy 43.216068 -37.287514) (xy 43.259693 -37.32017) (xy 43.298227 -37.358703)
			(xy 43.330884 -37.402329) (xy 43.356999 -37.450158) (xy 43.376042 -37.501217) (xy 43.387623 -37.554466)
			(xy 43.391508 -37.608822) (xy 43.752368 -37.608822) (xy 43.756252 -37.554465) (xy 43.767833 -37.501215)
			(xy 43.786875 -37.450155) (xy 43.81299 -37.402325) (xy 43.845645 -37.358699) (xy 43.884178 -37.320164)
			(xy 43.927802 -37.287505) (xy 43.97563 -37.261387) (xy 44.026689 -37.242341) (xy 44.079938 -37.230756)
			(xy 44.134294 -37.226868) (xy 44.18865 -37.230755) (xy 44.2419 -37.242338) (xy 44.292959 -37.261382)
			(xy 44.340788 -37.287498) (xy 44.362878 -37.303456) (xy 44.38189 -37.317052) (xy 44.423773 -37.337784)
			(xy 44.468741 -37.35051) (xy 44.515278 -37.3548) (xy 44.561815 -37.35051) (xy 44.606783 -37.337784)
			(xy 44.648666 -37.317052) (xy 44.667678 -37.303456) (xy 44.6898 -37.287543) (xy 44.737625 -37.261423)
			(xy 44.788681 -37.242376) (xy 44.841927 -37.23079) (xy 44.896281 -37.226899) (xy 44.950635 -37.230784)
			(xy 45.003883 -37.242366) (xy 45.05494 -37.261407) (xy 45.102768 -37.287522) (xy 45.146392 -37.320178)
			(xy 45.184924 -37.35871) (xy 45.217579 -37.402335) (xy 45.243694 -37.450162) (xy 45.262735 -37.50122)
			(xy 45.264525 -37.50945) (xy 66.441826 -37.50945) (xy 66.445897 -37.453828) (xy 66.458023 -37.399391)
			(xy 66.477946 -37.3473) (xy 66.505242 -37.298665) (xy 66.539328 -37.254522) (xy 66.579477 -37.215813)
			(xy 66.624835 -37.183362) (xy 66.674435 -37.157861) (xy 66.727219 -37.139854) (xy 66.782062 -37.129724)
			(xy 66.837796 -37.127687) (xy 66.893233 -37.133787) (xy 66.94719 -37.147893) (xy 66.998519 -37.169705)
			(xy 67.046125 -37.198759) (xy 67.088993 -37.234434) (xy 67.12621 -37.275971) (xy 67.156983 -37.322484)
			(xy 67.180655 -37.372981) (xy 67.196723 -37.426388) (xy 67.203901 -37.47516) (xy 67.542662 -37.47516)
			(xy 67.546733 -37.419538) (xy 67.558859 -37.365101) (xy 67.578782 -37.31301) (xy 67.606078 -37.264375)
			(xy 67.640164 -37.220232) (xy 67.680313 -37.181523) (xy 67.725671 -37.149072) (xy 67.775271 -37.123571)
			(xy 67.828055 -37.105564) (xy 67.882898 -37.095434) (xy 67.938632 -37.093397) (xy 67.994069 -37.099497)
			(xy 68.048026 -37.113603) (xy 68.099355 -37.135415) (xy 68.146961 -37.164469) (xy 68.189829 -37.200144)
			(xy 68.227046 -37.241681) (xy 68.257819 -37.288194) (xy 68.281491 -37.338691) (xy 68.297559 -37.392098)
			(xy 68.305679 -37.447274) (xy 68.306188 -37.47516) (xy 68.305771 -37.49802) (xy 68.691504 -37.49802)
			(xy 68.695575 -37.442398) (xy 68.707701 -37.387961) (xy 68.727624 -37.33587) (xy 68.75492 -37.287235)
			(xy 68.789006 -37.243092) (xy 68.829155 -37.204383) (xy 68.874513 -37.171932) (xy 68.924113 -37.146431)
			(xy 68.976897 -37.128424) (xy 69.03174 -37.118294) (xy 69.087474 -37.116257) (xy 69.142911 -37.122357)
			(xy 69.196868 -37.136463) (xy 69.248197 -37.158275) (xy 69.295803 -37.187329) (xy 69.338671 -37.223004)
			(xy 69.375888 -37.264541) (xy 69.406661 -37.311054) (xy 69.430333 -37.361551) (xy 69.446401 -37.414958)
			(xy 69.454521 -37.470134) (xy 69.454821 -37.48659) (xy 69.854824 -37.48659) (xy 69.858895 -37.430968)
			(xy 69.871021 -37.376531) (xy 69.890944 -37.32444) (xy 69.91824 -37.275805) (xy 69.952326 -37.231662)
			(xy 69.992475 -37.192953) (xy 70.037833 -37.160502) (xy 70.087433 -37.135001) (xy 70.140217 -37.116994)
			(xy 70.19506 -37.106864) (xy 70.250794 -37.104827) (xy 70.306231 -37.110927) (xy 70.360188 -37.125033)
			(xy 70.411517 -37.146845) (xy 70.459123 -37.175899) (xy 70.501991 -37.211574) (xy 70.539208 -37.253111)
			(xy 70.569981 -37.299624) (xy 70.593653 -37.350121) (xy 70.609721 -37.403528) (xy 70.617841 -37.458704)
			(xy 70.61835 -37.48659) (xy 70.617841 -37.514476) (xy 70.609721 -37.569652) (xy 70.593653 -37.623059)
			(xy 70.569981 -37.673556) (xy 70.539208 -37.720069) (xy 70.501991 -37.761606) (xy 70.459123 -37.797281)
			(xy 70.411517 -37.826335) (xy 70.360188 -37.848147) (xy 70.306231 -37.862253) (xy 70.250794 -37.868353)
			(xy 70.19506 -37.866316) (xy 70.140217 -37.856186) (xy 70.087433 -37.838179) (xy 70.037833 -37.812678)
			(xy 69.992475 -37.780227) (xy 69.952326 -37.741518) (xy 69.91824 -37.697375) (xy 69.890944 -37.64874)
			(xy 69.871021 -37.596649) (xy 69.858895 -37.542212) (xy 69.854824 -37.48659) (xy 69.454821 -37.48659)
			(xy 69.45503 -37.49802) (xy 69.454521 -37.525906) (xy 69.446401 -37.581082) (xy 69.430333 -37.634489)
			(xy 69.406661 -37.684986) (xy 69.375888 -37.731499) (xy 69.338671 -37.773036) (xy 69.295803 -37.808711)
			(xy 69.248197 -37.837765) (xy 69.196868 -37.859577) (xy 69.142911 -37.873683) (xy 69.087474 -37.879783)
			(xy 69.03174 -37.877746) (xy 68.976897 -37.867616) (xy 68.924113 -37.849609) (xy 68.874513 -37.824108)
			(xy 68.829155 -37.791657) (xy 68.789006 -37.752948) (xy 68.75492 -37.708805) (xy 68.727624 -37.66017)
			(xy 68.707701 -37.608079) (xy 68.695575 -37.553642) (xy 68.691504 -37.49802) (xy 68.305771 -37.49802)
			(xy 68.305679 -37.503046) (xy 68.297559 -37.558222) (xy 68.281491 -37.611629) (xy 68.257819 -37.662126)
			(xy 68.227046 -37.708639) (xy 68.189829 -37.750176) (xy 68.146961 -37.785851) (xy 68.099355 -37.814905)
			(xy 68.048026 -37.836717) (xy 67.994069 -37.850823) (xy 67.938632 -37.856923) (xy 67.882898 -37.854886)
			(xy 67.828055 -37.844756) (xy 67.775271 -37.826749) (xy 67.725671 -37.801248) (xy 67.680313 -37.768797)
			(xy 67.640164 -37.730088) (xy 67.606078 -37.685945) (xy 67.578782 -37.63731) (xy 67.558859 -37.585219)
			(xy 67.546733 -37.530782) (xy 67.542662 -37.47516) (xy 67.203901 -37.47516) (xy 67.204843 -37.481564)
			(xy 67.205352 -37.50945) (xy 67.204843 -37.537336) (xy 67.196723 -37.592512) (xy 67.180655 -37.645919)
			(xy 67.156983 -37.696416) (xy 67.12621 -37.742929) (xy 67.088993 -37.784466) (xy 67.046125 -37.820141)
			(xy 66.998519 -37.849195) (xy 66.94719 -37.871007) (xy 66.893233 -37.885113) (xy 66.837796 -37.891213)
			(xy 66.782062 -37.889176) (xy 66.727219 -37.879046) (xy 66.674435 -37.861039) (xy 66.624835 -37.835538)
			(xy 66.579477 -37.803087) (xy 66.539328 -37.764378) (xy 66.505242 -37.720235) (xy 66.477946 -37.6716)
			(xy 66.458023 -37.619509) (xy 66.445897 -37.565072) (xy 66.441826 -37.50945) (xy 45.264525 -37.50945)
			(xy 45.274316 -37.554468) (xy 45.278201 -37.608822) (xy 45.27431 -37.663175) (xy 45.262723 -37.716422)
			(xy 45.243676 -37.767477) (xy 45.217556 -37.815302) (xy 45.184895 -37.858922) (xy 45.146359 -37.89745)
			(xy 45.102731 -37.930101) (xy 45.054901 -37.95621) (xy 45.003841 -37.975247) (xy 44.950592 -37.986822)
			(xy 44.896238 -37.990701) (xy 44.841885 -37.986804) (xy 44.788639 -37.975212) (xy 44.737586 -37.956159)
			(xy 44.689764 -37.930034) (xy 44.667678 -37.914072) (xy 44.648666 -37.900476) (xy 44.606783 -37.879744)
			(xy 44.561815 -37.867018) (xy 44.515278 -37.862728) (xy 44.468741 -37.867018) (xy 44.423773 -37.879744)
			(xy 44.38189 -37.900476) (xy 44.362878 -37.914072) (xy 44.340824 -37.930079) (xy 44.292998 -37.956201)
			(xy 44.241941 -37.97525) (xy 44.188693 -37.986839) (xy 44.134337 -37.990732) (xy 44.079981 -37.98685)
			(xy 44.02673 -37.975271) (xy 43.97567 -37.956231) (xy 43.927838 -37.930119) (xy 43.88421 -37.897465)
			(xy 43.845674 -37.858934) (xy 43.813013 -37.815311) (xy 43.786893 -37.767484) (xy 43.767846 -37.716426)
			(xy 43.756259 -37.663177) (xy 43.752368 -37.608822) (xy 43.391508 -37.608822) (xy 43.387617 -37.663177)
			(xy 43.37603 -37.716425) (xy 43.356981 -37.767482) (xy 43.330861 -37.815308) (xy 43.298199 -37.858929)
			(xy 43.259661 -37.897458) (xy 43.216032 -37.93011) (xy 43.168199 -37.956219) (xy 43.117138 -37.975255)
			(xy 43.063887 -37.98683) (xy 43.009531 -37.990708) (xy 42.955176 -37.98681) (xy 42.90193 -37.975216)
			(xy 42.850875 -37.956162) (xy 42.803052 -37.930035) (xy 42.780966 -37.914072) (xy 42.761954 -37.900476)
			(xy 42.720071 -37.879744) (xy 42.675103 -37.867018) (xy 42.628566 -37.862728) (xy 42.582029 -37.867018)
			(xy 42.537061 -37.879744) (xy 42.495178 -37.900476) (xy 42.476166 -37.914072) (xy 42.454112 -37.930078)
			(xy 42.406287 -37.956198) (xy 42.355231 -37.975245) (xy 42.301984 -37.986833) (xy 42.24763 -37.990725)
			(xy 42.193276 -37.986842) (xy 42.140027 -37.975262) (xy 42.088968 -37.956223) (xy 42.041139 -37.93011)
			(xy 41.997512 -37.897457) (xy 41.958977 -37.858927) (xy 41.926318 -37.815305) (xy 41.900199 -37.767479)
			(xy 41.881152 -37.716423) (xy 41.869566 -37.663176) (xy 41.865675 -37.608822) (xy 36.479974 -37.608822)
			(xy 36.479988 -37.610034) (xy 36.479486 -37.653484) (xy 36.471468 -37.740013) (xy 36.4555 -37.825433)
			(xy 36.431719 -37.909015) (xy 36.400327 -37.990047) (xy 36.361593 -38.067836) (xy 36.315846 -38.14172)
			(xy 36.263477 -38.211067) (xy 36.204933 -38.275287) (xy 36.140713 -38.333831) (xy 36.071366 -38.3862)
			(xy 35.997482 -38.431947) (xy 35.919693 -38.470681) (xy 35.838661 -38.502073) (xy 35.755079 -38.525854)
			(xy 35.669659 -38.541822) (xy 35.58313 -38.54984) (xy 35.49623 -38.54984) (xy 35.409701 -38.541822)
			(xy 35.324281 -38.525854) (xy 35.240699 -38.502073) (xy 35.159667 -38.470681) (xy 35.081878 -38.431947)
			(xy 35.007994 -38.3862) (xy 34.938647 -38.333831) (xy 34.874427 -38.275287) (xy 34.815883 -38.211067)
			(xy 34.763514 -38.14172) (xy 34.717767 -38.067836) (xy 34.679033 -37.990047) (xy 34.647641 -37.909015)
			(xy 34.62386 -37.825433) (xy 34.607892 -37.740013) (xy 34.599874 -37.653484) (xy 31.399486 -37.653484)
			(xy 31.391468 -37.740013) (xy 31.3755 -37.825433) (xy 31.351719 -37.909015) (xy 31.320327 -37.990047)
			(xy 31.281593 -38.067836) (xy 31.235846 -38.14172) (xy 31.183477 -38.211067) (xy 31.124933 -38.275287)
			(xy 31.060713 -38.333831) (xy 30.991366 -38.3862) (xy 30.917482 -38.431947) (xy 30.839693 -38.470681)
			(xy 30.758661 -38.502073) (xy 30.675079 -38.525854) (xy 30.589659 -38.541822) (xy 30.50313 -38.54984)
			(xy 30.41623 -38.54984) (xy 30.329701 -38.541822) (xy 30.244281 -38.525854) (xy 30.160699 -38.502073)
			(xy 30.079667 -38.470681) (xy 30.001878 -38.431947) (xy 29.927994 -38.3862) (xy 29.858647 -38.333831)
			(xy 29.794427 -38.275287) (xy 29.735883 -38.211067) (xy 29.683514 -38.14172) (xy 29.637767 -38.067836)
			(xy 29.599033 -37.990047) (xy 29.567641 -37.909015) (xy 29.54386 -37.825433) (xy 29.527892 -37.740013)
			(xy 29.519874 -37.653484) (xy 24.795988 -37.653484) (xy 24.795988 -38.661255) (xy 47.507896 -38.661255)
			(xy 47.507896 -38.580145) (xy 47.515846 -38.499426) (xy 47.531669 -38.419875) (xy 47.555214 -38.342259)
			(xy 47.586253 -38.267323) (xy 47.624488 -38.195791) (xy 47.66955 -38.128351) (xy 47.721005 -38.065652)
			(xy 47.778358 -38.008299) (xy 47.841057 -37.956844) (xy 47.908497 -37.911782) (xy 47.980029 -37.873547)
			(xy 48.054965 -37.842508) (xy 48.132581 -37.818963) (xy 48.212132 -37.80314) (xy 48.292851 -37.79519)
			(xy 48.373961 -37.79519) (xy 48.45468 -37.80314) (xy 48.534231 -37.818963) (xy 48.611847 -37.842508)
			(xy 48.686783 -37.873547) (xy 48.758315 -37.911782) (xy 48.825755 -37.956844) (xy 48.888454 -38.008299)
			(xy 48.945807 -38.065652) (xy 48.997262 -38.128351) (xy 49.042324 -38.195791) (xy 49.080559 -38.267323)
			(xy 49.111598 -38.342259) (xy 49.135143 -38.419875) (xy 49.150966 -38.499426) (xy 49.158916 -38.580145)
			(xy 49.159414 -38.6207) (xy 49.158916 -38.661255) (xy 51.008016 -38.661255) (xy 51.008016 -38.580145)
			(xy 51.015966 -38.499426) (xy 51.031789 -38.419875) (xy 51.055334 -38.342259) (xy 51.086373 -38.267323)
			(xy 51.124608 -38.195791) (xy 51.16967 -38.128351) (xy 51.221125 -38.065652) (xy 51.278478 -38.008299)
			(xy 51.341177 -37.956844) (xy 51.408617 -37.911782) (xy 51.480149 -37.873547) (xy 51.555085 -37.842508)
			(xy 51.632701 -37.818963) (xy 51.712252 -37.80314) (xy 51.792971 -37.79519) (xy 51.874081 -37.79519)
			(xy 51.9548 -37.80314) (xy 52.034351 -37.818963) (xy 52.111967 -37.842508) (xy 52.186903 -37.873547)
			(xy 52.258435 -37.911782) (xy 52.325875 -37.956844) (xy 52.388574 -38.008299) (xy 52.445927 -38.065652)
			(xy 52.497382 -38.128351) (xy 52.542444 -38.195791) (xy 52.580679 -38.267323) (xy 52.611718 -38.342259)
			(xy 52.635263 -38.419875) (xy 52.651086 -38.499426) (xy 52.659036 -38.580145) (xy 52.659534 -38.6207)
			(xy 52.659036 -38.661255) (xy 52.651086 -38.741974) (xy 52.635263 -38.821525) (xy 52.611718 -38.899141)
			(xy 52.580679 -38.974077) (xy 52.542444 -39.045609) (xy 52.497382 -39.113049) (xy 52.445927 -39.175748)
			(xy 52.388574 -39.233101) (xy 52.325875 -39.284556) (xy 52.258435 -39.329618) (xy 52.186903 -39.367853)
			(xy 52.111967 -39.398892) (xy 52.034351 -39.422437) (xy 51.9548 -39.43826) (xy 51.874081 -39.44621)
			(xy 51.792971 -39.44621) (xy 51.712252 -39.43826) (xy 51.632701 -39.422437) (xy 51.555085 -39.398892)
			(xy 51.480149 -39.367853) (xy 51.408617 -39.329618) (xy 51.341177 -39.284556) (xy 51.278478 -39.233101)
			(xy 51.221125 -39.175748) (xy 51.16967 -39.113049) (xy 51.124608 -39.045609) (xy 51.086373 -38.974077)
			(xy 51.055334 -38.899141) (xy 51.031789 -38.821525) (xy 51.015966 -38.741974) (xy 51.008016 -38.661255)
			(xy 49.158916 -38.661255) (xy 49.150966 -38.741974) (xy 49.135143 -38.821525) (xy 49.111598 -38.899141)
			(xy 49.080559 -38.974077) (xy 49.042324 -39.045609) (xy 48.997262 -39.113049) (xy 48.945807 -39.175748)
			(xy 48.888454 -39.233101) (xy 48.825755 -39.284556) (xy 48.758315 -39.329618) (xy 48.686783 -39.367853)
			(xy 48.611847 -39.398892) (xy 48.534231 -39.422437) (xy 48.45468 -39.43826) (xy 48.373961 -39.44621)
			(xy 48.292851 -39.44621) (xy 48.212132 -39.43826) (xy 48.132581 -39.422437) (xy 48.054965 -39.398892)
			(xy 47.980029 -39.367853) (xy 47.908497 -39.329618) (xy 47.841057 -39.284556) (xy 47.778358 -39.233101)
			(xy 47.721005 -39.175748) (xy 47.66955 -39.113049) (xy 47.624488 -39.045609) (xy 47.586253 -38.974077)
			(xy 47.555214 -38.899141) (xy 47.531669 -38.821525) (xy 47.515846 -38.741974) (xy 47.507896 -38.661255)
			(xy 24.795988 -38.661255) (xy 24.795988 -40.193484) (xy 29.519874 -40.193484) (xy 29.519874 -40.106584)
			(xy 29.527892 -40.020055) (xy 29.54386 -39.934635) (xy 29.567641 -39.851053) (xy 29.599033 -39.770021)
			(xy 29.637767 -39.692232) (xy 29.683514 -39.618348) (xy 29.735883 -39.549001) (xy 29.794427 -39.484781)
			(xy 29.858647 -39.426237) (xy 29.927994 -39.373868) (xy 30.001878 -39.328121) (xy 30.079667 -39.289387)
			(xy 30.160699 -39.257995) (xy 30.244281 -39.234214) (xy 30.329701 -39.218246) (xy 30.41623 -39.210228)
			(xy 30.50313 -39.210228) (xy 30.589659 -39.218246) (xy 30.675079 -39.234214) (xy 30.758661 -39.257995)
			(xy 30.839693 -39.289387) (xy 30.917482 -39.328121) (xy 30.991366 -39.373868) (xy 31.060713 -39.426237)
			(xy 31.124933 -39.484781) (xy 31.183477 -39.549001) (xy 31.235846 -39.618348) (xy 31.281593 -39.692232)
			(xy 31.320327 -39.770021) (xy 31.351719 -39.851053) (xy 31.3755 -39.934635) (xy 31.391468 -40.020055)
			(xy 31.399486 -40.106584) (xy 31.399988 -40.150034) (xy 31.399486 -40.193484) (xy 34.599874 -40.193484)
			(xy 34.599874 -40.106584) (xy 34.607892 -40.020055) (xy 34.62386 -39.934635) (xy 34.647641 -39.851053)
			(xy 34.679033 -39.770021) (xy 34.717767 -39.692232) (xy 34.763514 -39.618348) (xy 34.815883 -39.549001)
			(xy 34.874427 -39.484781) (xy 34.938647 -39.426237) (xy 35.007994 -39.373868) (xy 35.081878 -39.328121)
			(xy 35.159667 -39.289387) (xy 35.240699 -39.257995) (xy 35.324281 -39.234214) (xy 35.409701 -39.218246)
			(xy 35.49623 -39.210228) (xy 35.58313 -39.210228) (xy 35.669659 -39.218246) (xy 35.755079 -39.234214)
			(xy 35.838661 -39.257995) (xy 35.919693 -39.289387) (xy 35.997482 -39.328121) (xy 36.071366 -39.373868)
			(xy 36.140713 -39.426237) (xy 36.204933 -39.484781) (xy 36.263477 -39.549001) (xy 36.315846 -39.618348)
			(xy 36.335379 -39.649895) (xy 41.86571 -39.649895) (xy 41.869598 -39.595546) (xy 41.881181 -39.542303)
			(xy 41.900224 -39.491251) (xy 41.926338 -39.443428) (xy 41.958993 -39.399809) (xy 41.997523 -39.361281)
			(xy 42.041144 -39.328628) (xy 42.088967 -39.302516) (xy 42.140021 -39.283476) (xy 42.193264 -39.271896)
			(xy 42.247614 -39.26801) (xy 42.301963 -39.271899) (xy 42.355205 -39.283484) (xy 42.406257 -39.302527)
			(xy 42.454079 -39.328643) (xy 42.476166 -39.3446) (xy 42.495178 -39.358196) (xy 42.537061 -39.378928)
			(xy 42.582029 -39.391654) (xy 42.628566 -39.395944) (xy 42.675103 -39.391654) (xy 42.720071 -39.378928)
			(xy 42.761954 -39.358196) (xy 42.780966 -39.3446) (xy 42.803047 -39.328626) (xy 42.850876 -39.302499)
			(xy 42.901936 -39.283445) (xy 42.955188 -39.271852) (xy 43.009548 -39.267957) (xy 43.063909 -39.271838)
			(xy 43.117164 -39.283416) (xy 43.168229 -39.302456) (xy 43.216065 -39.32857) (xy 43.259697 -39.361226)
			(xy 43.298236 -39.39976) (xy 43.330899 -39.443387) (xy 43.35702 -39.491219) (xy 43.376068 -39.542281)
			(xy 43.387654 -39.595535) (xy 43.391543 -39.649895) (xy 43.752403 -39.649895) (xy 43.756291 -39.595544)
			(xy 43.767875 -39.5423) (xy 43.786918 -39.491246) (xy 43.813034 -39.443422) (xy 43.845689 -39.399802)
			(xy 43.884221 -39.361273) (xy 43.927843 -39.32862) (xy 43.975669 -39.302508) (xy 44.026724 -39.283468)
			(xy 44.079969 -39.271888) (xy 44.13432 -39.268003) (xy 44.188671 -39.271893) (xy 44.241915 -39.283479)
			(xy 44.292968 -39.302525) (xy 44.340791 -39.328642) (xy 44.362878 -39.3446) (xy 44.38189 -39.358196)
			(xy 44.423773 -39.378928) (xy 44.468741 -39.391654) (xy 44.515278 -39.395944) (xy 44.561815 -39.391654)
			(xy 44.606783 -39.378928) (xy 44.648666 -39.358196) (xy 44.667678 -39.3446) (xy 44.689759 -39.328627)
			(xy 44.737587 -39.302502) (xy 44.788646 -39.28345) (xy 44.841896 -39.271858) (xy 44.896255 -39.267964)
			(xy 44.950614 -39.271846) (xy 45.003867 -39.283424) (xy 45.054931 -39.302464) (xy 45.102764 -39.328578)
			(xy 45.146395 -39.361234) (xy 45.184933 -39.399767) (xy 45.217595 -39.443393) (xy 45.243715 -39.491224)
			(xy 45.262762 -39.542284) (xy 45.274347 -39.595536) (xy 45.278236 -39.649895) (xy 45.274349 -39.704254)
			(xy 45.262764 -39.757506) (xy 45.243719 -39.808568) (xy 45.2176 -39.856399) (xy 45.184939 -39.900025)
			(xy 45.146402 -39.938559) (xy 45.102773 -39.971216) (xy 45.05494 -39.997332) (xy 45.003877 -40.016373)
			(xy 44.950623 -40.027953) (xy 44.896264 -40.031836) (xy 44.841906 -40.027943) (xy 44.788655 -40.016353)
			(xy 44.737595 -39.997302) (xy 44.689767 -39.971178) (xy 44.667678 -39.955216) (xy 44.648666 -39.94162)
			(xy 44.606783 -39.920888) (xy 44.561815 -39.908162) (xy 44.515278 -39.903872) (xy 44.468741 -39.908162)
			(xy 44.423773 -39.920888) (xy 44.38189 -39.94162) (xy 44.362878 -39.955216) (xy 44.340783 -39.971163)
			(xy 44.292959 -39.997279) (xy 44.241906 -40.016324) (xy 44.188662 -40.027908) (xy 44.134311 -40.031797)
			(xy 44.07996 -40.027911) (xy 44.026715 -40.01633) (xy 43.97566 -39.997288) (xy 43.927835 -39.971175)
			(xy 43.884213 -39.938521) (xy 43.845683 -39.899991) (xy 43.813028 -39.85637) (xy 43.786914 -39.808545)
			(xy 43.767872 -39.757491) (xy 43.75629 -39.704246) (xy 43.752403 -39.649895) (xy 43.391543 -39.649895)
			(xy 43.387656 -39.704256) (xy 43.376071 -39.75751) (xy 43.357024 -39.808572) (xy 43.330904 -39.856405)
			(xy 43.298243 -39.900032) (xy 43.259704 -39.938567) (xy 43.216073 -39.971225) (xy 43.168238 -39.99734)
			(xy 43.117173 -40.016381) (xy 43.063918 -40.027961) (xy 43.009557 -40.031843) (xy 42.955197 -40.027949)
			(xy 42.901945 -40.016357) (xy 42.850885 -39.997305) (xy 42.803056 -39.971179) (xy 42.780966 -39.955216)
			(xy 42.761954 -39.94162) (xy 42.720071 -39.920888) (xy 42.675103 -39.908162) (xy 42.628566 -39.903872)
			(xy 42.582029 -39.908162) (xy 42.537061 -39.920888) (xy 42.495178 -39.94162) (xy 42.476166 -39.955216)
			(xy 42.454071 -39.971162) (xy 42.406248 -39.997277) (xy 42.355196 -40.016319) (xy 42.301953 -40.027902)
			(xy 42.247604 -40.03179) (xy 42.193255 -40.027903) (xy 42.140011 -40.016321) (xy 42.088959 -39.99728)
			(xy 42.041135 -39.971166) (xy 41.997515 -39.938513) (xy 41.958986 -39.899984) (xy 41.926333 -39.856364)
			(xy 41.90022 -39.808541) (xy 41.881179 -39.757488) (xy 41.869597 -39.704245) (xy 41.86571 -39.649895)
			(xy 36.335379 -39.649895) (xy 36.361593 -39.692232) (xy 36.400327 -39.770021) (xy 36.431719 -39.851053)
			(xy 36.4555 -39.934635) (xy 36.471468 -40.020055) (xy 36.479486 -40.106584) (xy 36.479988 -40.150034)
			(xy 36.479486 -40.193484) (xy 36.471468 -40.280013) (xy 36.4555 -40.365433) (xy 36.431719 -40.449015)
			(xy 36.400327 -40.530047) (xy 36.361593 -40.607836) (xy 36.315846 -40.68172) (xy 36.263477 -40.751067)
			(xy 36.204933 -40.815287) (xy 36.140713 -40.873831) (xy 36.071366 -40.9262) (xy 35.997482 -40.971947)
			(xy 35.919693 -41.010681) (xy 35.838661 -41.042073) (xy 35.755079 -41.065854) (xy 35.669659 -41.081822)
			(xy 35.58313 -41.08984) (xy 35.49623 -41.08984) (xy 35.409701 -41.081822) (xy 35.324281 -41.065854)
			(xy 35.240699 -41.042073) (xy 35.159667 -41.010681) (xy 35.081878 -40.971947) (xy 35.007994 -40.9262)
			(xy 34.938647 -40.873831) (xy 34.874427 -40.815287) (xy 34.815883 -40.751067) (xy 34.763514 -40.68172)
			(xy 34.717767 -40.607836) (xy 34.679033 -40.530047) (xy 34.647641 -40.449015) (xy 34.62386 -40.365433)
			(xy 34.607892 -40.280013) (xy 34.599874 -40.193484) (xy 31.399486 -40.193484) (xy 31.391468 -40.280013)
			(xy 31.3755 -40.365433) (xy 31.351719 -40.449015) (xy 31.320327 -40.530047) (xy 31.281593 -40.607836)
			(xy 31.235846 -40.68172) (xy 31.183477 -40.751067) (xy 31.124933 -40.815287) (xy 31.060713 -40.873831)
			(xy 30.991366 -40.9262) (xy 30.917482 -40.971947) (xy 30.839693 -41.010681) (xy 30.758661 -41.042073)
			(xy 30.675079 -41.065854) (xy 30.589659 -41.081822) (xy 30.50313 -41.08984) (xy 30.41623 -41.08984)
			(xy 30.329701 -41.081822) (xy 30.244281 -41.065854) (xy 30.160699 -41.042073) (xy 30.079667 -41.010681)
			(xy 30.001878 -40.971947) (xy 29.927994 -40.9262) (xy 29.858647 -40.873831) (xy 29.794427 -40.815287)
			(xy 29.735883 -40.751067) (xy 29.683514 -40.68172) (xy 29.637767 -40.607836) (xy 29.599033 -40.530047)
			(xy 29.567641 -40.449015) (xy 29.54386 -40.365433) (xy 29.527892 -40.280013) (xy 29.519874 -40.193484)
			(xy 24.795988 -40.193484) (xy 24.795988 -41.55968) (xy 41.865731 -41.55968) (xy 41.869621 -41.505333)
			(xy 41.881206 -41.452094) (xy 41.900249 -41.401045) (xy 41.926364 -41.353226) (xy 41.959019 -41.309611)
			(xy 41.997548 -41.271086) (xy 42.041168 -41.238437) (xy 42.08899 -41.212329) (xy 42.140041 -41.193292)
			(xy 42.193282 -41.181714) (xy 42.247629 -41.177831) (xy 42.301975 -41.181722) (xy 42.355214 -41.193308)
			(xy 42.406263 -41.212353) (xy 42.454081 -41.238469) (xy 42.476166 -41.254426) (xy 42.495178 -41.268022)
			(xy 42.537061 -41.288754) (xy 42.582029 -41.30148) (xy 42.628566 -41.30577) (xy 42.675103 -41.30148)
			(xy 42.720071 -41.288754) (xy 42.761954 -41.268022) (xy 42.780966 -41.254426) (xy 42.803023 -41.238417)
			(xy 42.850853 -41.212287) (xy 42.901915 -41.19323) (xy 42.955169 -41.181634) (xy 43.009532 -41.177736)
			(xy 43.063896 -41.181615) (xy 43.117155 -41.193191) (xy 43.168224 -41.21223) (xy 43.216063 -41.238344)
			(xy 43.259698 -41.271) (xy 43.298242 -41.309535) (xy 43.330908 -41.353163) (xy 43.357033 -41.400996)
			(xy 43.376084 -41.45206) (xy 43.387673 -41.505316) (xy 43.391564 -41.55968) (xy 43.752424 -41.55968)
			(xy 43.756314 -41.505332) (xy 43.767899 -41.452091) (xy 43.786943 -41.401041) (xy 43.813059 -41.35322)
			(xy 43.845715 -41.309604) (xy 43.884246 -41.271078) (xy 43.927868 -41.238429) (xy 43.975692 -41.21232)
			(xy 44.026745 -41.193283) (xy 44.079988 -41.181706) (xy 44.134336 -41.177824) (xy 44.188684 -41.181716)
			(xy 44.241924 -41.193303) (xy 44.292974 -41.21235) (xy 44.340793 -41.238468) (xy 44.362878 -41.254426)
			(xy 44.38189 -41.268022) (xy 44.423773 -41.288754) (xy 44.468741 -41.30148) (xy 44.515278 -41.30577)
			(xy 44.561815 -41.30148) (xy 44.606783 -41.288754) (xy 44.648666 -41.268022) (xy 44.667678 -41.254426)
			(xy 44.689735 -41.238418) (xy 44.737564 -41.21229) (xy 44.788625 -41.193234) (xy 44.841878 -41.18164)
			(xy 44.896239 -41.177743) (xy 44.950601 -41.181623) (xy 45.003858 -41.1932) (xy 45.054925 -41.212239)
			(xy 45.102763 -41.238352) (xy 45.146396 -41.271008) (xy 45.184938 -41.309542) (xy 45.217604 -41.353169)
			(xy 45.243727 -41.401001) (xy 45.262777 -41.452064) (xy 45.274366 -41.505318) (xy 45.278257 -41.55968)
			(xy 45.274372 -41.614042) (xy 45.262789 -41.667297) (xy 45.243744 -41.718362) (xy 45.217626 -41.766197)
			(xy 45.184965 -41.809827) (xy 45.146427 -41.848365) (xy 45.102797 -41.881026) (xy 45.054962 -41.907144)
			(xy 45.003897 -41.926189) (xy 44.950642 -41.937771) (xy 44.89628 -41.941657) (xy 44.841918 -41.937766)
			(xy 44.788664 -41.926177) (xy 44.737601 -41.907127) (xy 44.689769 -41.881004) (xy 44.667678 -41.865042)
			(xy 44.648666 -41.851446) (xy 44.606783 -41.830714) (xy 44.561815 -41.817988) (xy 44.515278 -41.813698)
			(xy 44.468741 -41.817988) (xy 44.423773 -41.830714) (xy 44.38189 -41.851446) (xy 44.362878 -41.865042)
			(xy 44.340758 -41.880954) (xy 44.292936 -41.907067) (xy 44.241885 -41.926108) (xy 44.188643 -41.93769)
			(xy 44.134295 -41.941576) (xy 44.079947 -41.937688) (xy 44.026706 -41.926105) (xy 43.975655 -41.907063)
			(xy 43.927833 -41.880949) (xy 43.884215 -41.848295) (xy 43.845689 -41.809766) (xy 43.813037 -41.766145)
			(xy 43.786927 -41.718322) (xy 43.767888 -41.66727) (xy 43.756308 -41.614028) (xy 43.752424 -41.55968)
			(xy 43.391564 -41.55968) (xy 43.387679 -41.614043) (xy 43.376095 -41.6673) (xy 43.35705 -41.718367)
			(xy 43.33093 -41.766203) (xy 43.298268 -41.809834) (xy 43.259729 -41.848373) (xy 43.216097 -41.881034)
			(xy 43.168261 -41.907153) (xy 43.117194 -41.926197) (xy 43.063937 -41.937779) (xy 43.009573 -41.941664)
			(xy 42.95521 -41.937772) (xy 42.901954 -41.926182) (xy 42.85089 -41.90713) (xy 42.803057 -41.881005)
			(xy 42.780966 -41.865042) (xy 42.761954 -41.851446) (xy 42.720071 -41.830714) (xy 42.675103 -41.817988)
			(xy 42.628566 -41.813698) (xy 42.582029 -41.817988) (xy 42.537061 -41.830714) (xy 42.495178 -41.851446)
			(xy 42.476166 -41.865042) (xy 42.454047 -41.880953) (xy 42.406226 -41.907064) (xy 42.355175 -41.926103)
			(xy 42.301935 -41.937684) (xy 42.247588 -41.941569) (xy 42.193242 -41.93768) (xy 42.140002 -41.926097)
			(xy 42.088953 -41.907054) (xy 42.041134 -41.880941) (xy 41.997517 -41.848287) (xy 41.958992 -41.809759)
			(xy 41.926342 -41.766139) (xy 41.900232 -41.718318) (xy 41.881194 -41.667267) (xy 41.869615 -41.614026)
			(xy 41.865731 -41.55968) (xy 24.795988 -41.55968) (xy 24.795988 -42.733484) (xy 29.519874 -42.733484)
			(xy 29.519874 -42.646584) (xy 29.527892 -42.560055) (xy 29.54386 -42.474635) (xy 29.567641 -42.391053)
			(xy 29.599033 -42.310021) (xy 29.637767 -42.232232) (xy 29.683514 -42.158348) (xy 29.735883 -42.089001)
			(xy 29.794427 -42.024781) (xy 29.858647 -41.966237) (xy 29.927994 -41.913868) (xy 30.001878 -41.868121)
			(xy 30.079667 -41.829387) (xy 30.160699 -41.797995) (xy 30.244281 -41.774214) (xy 30.329701 -41.758246)
			(xy 30.41623 -41.750228) (xy 30.50313 -41.750228) (xy 30.589659 -41.758246) (xy 30.675079 -41.774214)
			(xy 30.758661 -41.797995) (xy 30.839693 -41.829387) (xy 30.917482 -41.868121) (xy 30.991366 -41.913868)
			(xy 31.060713 -41.966237) (xy 31.124933 -42.024781) (xy 31.183477 -42.089001) (xy 31.235846 -42.158348)
			(xy 31.281593 -42.232232) (xy 31.320327 -42.310021) (xy 31.351719 -42.391053) (xy 31.3755 -42.474635)
			(xy 31.391468 -42.560055) (xy 31.399486 -42.646584) (xy 31.399988 -42.690034) (xy 31.399486 -42.733484)
			(xy 34.599874 -42.733484) (xy 34.599874 -42.646584) (xy 34.607892 -42.560055) (xy 34.62386 -42.474635)
			(xy 34.647641 -42.391053) (xy 34.679033 -42.310021) (xy 34.717767 -42.232232) (xy 34.763514 -42.158348)
			(xy 34.815883 -42.089001) (xy 34.874427 -42.024781) (xy 34.938647 -41.966237) (xy 35.007994 -41.913868)
			(xy 35.081878 -41.868121) (xy 35.159667 -41.829387) (xy 35.240699 -41.797995) (xy 35.324281 -41.774214)
			(xy 35.409701 -41.758246) (xy 35.49623 -41.750228) (xy 35.58313 -41.750228) (xy 35.669659 -41.758246)
			(xy 35.755079 -41.774214) (xy 35.838661 -41.797995) (xy 35.919693 -41.829387) (xy 35.997482 -41.868121)
			(xy 36.071366 -41.913868) (xy 36.140713 -41.966237) (xy 36.204933 -42.024781) (xy 36.263477 -42.089001)
			(xy 36.315846 -42.158348) (xy 36.361593 -42.232232) (xy 36.400327 -42.310021) (xy 36.431719 -42.391053)
			(xy 36.4555 -42.474635) (xy 36.471468 -42.560055) (xy 36.479486 -42.646584) (xy 36.479988 -42.690034)
			(xy 36.479486 -42.733484) (xy 36.471468 -42.820013) (xy 36.4555 -42.905433) (xy 36.431719 -42.989015)
			(xy 36.400327 -43.070047) (xy 36.361593 -43.147836) (xy 36.315846 -43.22172) (xy 36.263477 -43.291067)
			(xy 36.204933 -43.355287) (xy 36.140713 -43.413831) (xy 36.071366 -43.4662) (xy 35.997482 -43.511947)
			(xy 35.919693 -43.550681) (xy 35.838661 -43.582073) (xy 35.755079 -43.605854) (xy 35.669659 -43.621822)
			(xy 35.58313 -43.62984) (xy 35.49623 -43.62984) (xy 35.409701 -43.621822) (xy 35.324281 -43.605854)
			(xy 35.240699 -43.582073) (xy 35.159667 -43.550681) (xy 35.081878 -43.511947) (xy 35.007994 -43.4662)
			(xy 34.938647 -43.413831) (xy 34.874427 -43.355287) (xy 34.815883 -43.291067) (xy 34.763514 -43.22172)
			(xy 34.717767 -43.147836) (xy 34.679033 -43.070047) (xy 34.647641 -42.989015) (xy 34.62386 -42.905433)
			(xy 34.607892 -42.820013) (xy 34.599874 -42.733484) (xy 31.399486 -42.733484) (xy 31.391468 -42.820013)
			(xy 31.3755 -42.905433) (xy 31.351719 -42.989015) (xy 31.320327 -43.070047) (xy 31.281593 -43.147836)
			(xy 31.235846 -43.22172) (xy 31.183477 -43.291067) (xy 31.124933 -43.355287) (xy 31.060713 -43.413831)
			(xy 30.991366 -43.4662) (xy 30.917482 -43.511947) (xy 30.839693 -43.550681) (xy 30.758661 -43.582073)
			(xy 30.675079 -43.605854) (xy 30.589659 -43.621822) (xy 30.50313 -43.62984) (xy 30.41623 -43.62984)
			(xy 30.329701 -43.621822) (xy 30.244281 -43.605854) (xy 30.160699 -43.582073) (xy 30.079667 -43.550681)
			(xy 30.001878 -43.511947) (xy 29.927994 -43.4662) (xy 29.858647 -43.413831) (xy 29.794427 -43.355287)
			(xy 29.735883 -43.291067) (xy 29.683514 -43.22172) (xy 29.637767 -43.147836) (xy 29.599033 -43.070047)
			(xy 29.567641 -42.989015) (xy 29.54386 -42.905433) (xy 29.527892 -42.820013) (xy 29.519874 -42.733484)
			(xy 24.795988 -42.733484) (xy 24.795988 -45.273484) (xy 29.519874 -45.273484) (xy 29.519874 -45.186584)
			(xy 29.527892 -45.100055) (xy 29.54386 -45.014635) (xy 29.567641 -44.931053) (xy 29.599033 -44.850021)
			(xy 29.637767 -44.772232) (xy 29.683514 -44.698348) (xy 29.735883 -44.629001) (xy 29.794427 -44.564781)
			(xy 29.858647 -44.506237) (xy 29.927994 -44.453868) (xy 30.001878 -44.408121) (xy 30.079667 -44.369387)
			(xy 30.160699 -44.337995) (xy 30.244281 -44.314214) (xy 30.329701 -44.298246) (xy 30.41623 -44.290228)
			(xy 30.50313 -44.290228) (xy 30.589659 -44.298246) (xy 30.675079 -44.314214) (xy 30.758661 -44.337995)
			(xy 30.839693 -44.369387) (xy 30.917482 -44.408121) (xy 30.991366 -44.453868) (xy 31.060713 -44.506237)
			(xy 31.124933 -44.564781) (xy 31.183477 -44.629001) (xy 31.235846 -44.698348) (xy 31.281593 -44.772232)
			(xy 31.320327 -44.850021) (xy 31.351719 -44.931053) (xy 31.3755 -45.014635) (xy 31.391468 -45.100055)
			(xy 31.399486 -45.186584) (xy 31.399988 -45.230034) (xy 31.399486 -45.273484) (xy 34.599874 -45.273484)
			(xy 34.599874 -45.186584) (xy 34.607892 -45.100055) (xy 34.62386 -45.014635) (xy 34.647641 -44.931053)
			(xy 34.679033 -44.850021) (xy 34.717767 -44.772232) (xy 34.763514 -44.698348) (xy 34.815883 -44.629001)
			(xy 34.874427 -44.564781) (xy 34.938647 -44.506237) (xy 35.007994 -44.453868) (xy 35.081878 -44.408121)
			(xy 35.159667 -44.369387) (xy 35.240699 -44.337995) (xy 35.324281 -44.314214) (xy 35.409701 -44.298246)
			(xy 35.49623 -44.290228) (xy 35.58313 -44.290228) (xy 35.669659 -44.298246) (xy 35.755079 -44.314214)
			(xy 35.838661 -44.337995) (xy 35.919693 -44.369387) (xy 35.997482 -44.408121) (xy 36.071366 -44.453868)
			(xy 36.140713 -44.506237) (xy 36.204933 -44.564781) (xy 36.263477 -44.629001) (xy 36.315846 -44.698348)
			(xy 36.361593 -44.772232) (xy 36.400327 -44.850021) (xy 36.431719 -44.931053) (xy 36.4555 -45.014635)
			(xy 36.471468 -45.100055) (xy 36.479486 -45.186584) (xy 36.479988 -45.230034) (xy 36.479486 -45.273484)
			(xy 36.471468 -45.360013) (xy 36.4555 -45.445433) (xy 36.431719 -45.529015) (xy 36.400327 -45.610047)
			(xy 36.361593 -45.687836) (xy 36.315846 -45.76172) (xy 36.263477 -45.831067) (xy 36.204933 -45.895287)
			(xy 36.140713 -45.953831) (xy 36.071366 -46.0062) (xy 35.997482 -46.051947) (xy 35.919693 -46.090681)
			(xy 35.838661 -46.122073) (xy 35.755079 -46.145854) (xy 35.669659 -46.161822) (xy 35.58313 -46.16984)
			(xy 35.49623 -46.16984) (xy 35.409701 -46.161822) (xy 35.324281 -46.145854) (xy 35.240699 -46.122073)
			(xy 35.159667 -46.090681) (xy 35.081878 -46.051947) (xy 35.007994 -46.0062) (xy 34.938647 -45.953831)
			(xy 34.874427 -45.895287) (xy 34.815883 -45.831067) (xy 34.763514 -45.76172) (xy 34.717767 -45.687836)
			(xy 34.679033 -45.610047) (xy 34.647641 -45.529015) (xy 34.62386 -45.445433) (xy 34.607892 -45.360013)
			(xy 34.599874 -45.273484) (xy 31.399486 -45.273484) (xy 31.391468 -45.360013) (xy 31.3755 -45.445433)
			(xy 31.351719 -45.529015) (xy 31.320327 -45.610047) (xy 31.281593 -45.687836) (xy 31.235846 -45.76172)
			(xy 31.183477 -45.831067) (xy 31.124933 -45.895287) (xy 31.060713 -45.953831) (xy 30.991366 -46.0062)
			(xy 30.917482 -46.051947) (xy 30.839693 -46.090681) (xy 30.758661 -46.122073) (xy 30.675079 -46.145854)
			(xy 30.589659 -46.161822) (xy 30.50313 -46.16984) (xy 30.41623 -46.16984) (xy 30.329701 -46.161822)
			(xy 30.244281 -46.145854) (xy 30.160699 -46.122073) (xy 30.079667 -46.090681) (xy 30.001878 -46.051947)
			(xy 29.927994 -46.0062) (xy 29.858647 -45.953831) (xy 29.794427 -45.895287) (xy 29.735883 -45.831067)
			(xy 29.683514 -45.76172) (xy 29.637767 -45.687836) (xy 29.599033 -45.610047) (xy 29.567641 -45.529015)
			(xy 29.54386 -45.445433) (xy 29.527892 -45.360013) (xy 29.519874 -45.273484) (xy 24.795988 -45.273484)
			(xy 24.795988 -47.813484) (xy 29.519874 -47.813484) (xy 29.519874 -47.726584) (xy 29.527892 -47.640055)
			(xy 29.54386 -47.554635) (xy 29.567641 -47.471053) (xy 29.599033 -47.390021) (xy 29.637767 -47.312232)
			(xy 29.683514 -47.238348) (xy 29.735883 -47.169001) (xy 29.794427 -47.104781) (xy 29.858647 -47.046237)
			(xy 29.927994 -46.993868) (xy 30.001878 -46.948121) (xy 30.079667 -46.909387) (xy 30.160699 -46.877995)
			(xy 30.244281 -46.854214) (xy 30.329701 -46.838246) (xy 30.41623 -46.830228) (xy 30.50313 -46.830228)
			(xy 30.589659 -46.838246) (xy 30.675079 -46.854214) (xy 30.758661 -46.877995) (xy 30.839693 -46.909387)
			(xy 30.917482 -46.948121) (xy 30.991366 -46.993868) (xy 31.060713 -47.046237) (xy 31.124933 -47.104781)
			(xy 31.183477 -47.169001) (xy 31.235846 -47.238348) (xy 31.281593 -47.312232) (xy 31.320327 -47.390021)
			(xy 31.351719 -47.471053) (xy 31.3755 -47.554635) (xy 31.391468 -47.640055) (xy 31.399486 -47.726584)
			(xy 31.399988 -47.770034) (xy 31.399486 -47.813484) (xy 34.599874 -47.813484) (xy 34.599874 -47.726584)
			(xy 34.607892 -47.640055) (xy 34.62386 -47.554635) (xy 34.647641 -47.471053) (xy 34.679033 -47.390021)
			(xy 34.717767 -47.312232) (xy 34.763514 -47.238348) (xy 34.815883 -47.169001) (xy 34.874427 -47.104781)
			(xy 34.938647 -47.046237) (xy 35.007994 -46.993868) (xy 35.081878 -46.948121) (xy 35.159667 -46.909387)
			(xy 35.240699 -46.877995) (xy 35.324281 -46.854214) (xy 35.409701 -46.838246) (xy 35.49623 -46.830228)
			(xy 35.58313 -46.830228) (xy 35.669659 -46.838246) (xy 35.755079 -46.854214) (xy 35.838661 -46.877995)
			(xy 35.919693 -46.909387) (xy 35.997482 -46.948121) (xy 36.071366 -46.993868) (xy 36.140713 -47.046237)
			(xy 36.204933 -47.104781) (xy 36.263477 -47.169001) (xy 36.315846 -47.238348) (xy 36.361593 -47.312232)
			(xy 36.400327 -47.390021) (xy 36.431719 -47.471053) (xy 36.4555 -47.554635) (xy 36.471468 -47.640055)
			(xy 36.479486 -47.726584) (xy 36.479988 -47.770034) (xy 36.479486 -47.813484) (xy 36.471468 -47.900013)
			(xy 36.4555 -47.985433) (xy 36.431719 -48.069015) (xy 36.400327 -48.150047) (xy 36.361593 -48.227836)
			(xy 36.315846 -48.30172) (xy 36.263477 -48.371067) (xy 36.204933 -48.435287) (xy 36.140713 -48.493831)
			(xy 36.071366 -48.5462) (xy 35.997482 -48.591947) (xy 35.919693 -48.630681) (xy 35.838661 -48.662073)
			(xy 35.755079 -48.685854) (xy 35.669659 -48.701822) (xy 35.58313 -48.70984) (xy 35.49623 -48.70984)
			(xy 35.409701 -48.701822) (xy 35.324281 -48.685854) (xy 35.240699 -48.662073) (xy 35.159667 -48.630681)
			(xy 35.081878 -48.591947) (xy 35.007994 -48.5462) (xy 34.938647 -48.493831) (xy 34.874427 -48.435287)
			(xy 34.815883 -48.371067) (xy 34.763514 -48.30172) (xy 34.717767 -48.227836) (xy 34.679033 -48.150047)
			(xy 34.647641 -48.069015) (xy 34.62386 -47.985433) (xy 34.607892 -47.900013) (xy 34.599874 -47.813484)
			(xy 31.399486 -47.813484) (xy 31.391468 -47.900013) (xy 31.3755 -47.985433) (xy 31.351719 -48.069015)
			(xy 31.320327 -48.150047) (xy 31.281593 -48.227836) (xy 31.235846 -48.30172) (xy 31.183477 -48.371067)
			(xy 31.124933 -48.435287) (xy 31.060713 -48.493831) (xy 30.991366 -48.5462) (xy 30.917482 -48.591947)
			(xy 30.839693 -48.630681) (xy 30.758661 -48.662073) (xy 30.675079 -48.685854) (xy 30.589659 -48.701822)
			(xy 30.50313 -48.70984) (xy 30.41623 -48.70984) (xy 30.329701 -48.701822) (xy 30.244281 -48.685854)
			(xy 30.160699 -48.662073) (xy 30.079667 -48.630681) (xy 30.001878 -48.591947) (xy 29.927994 -48.5462)
			(xy 29.858647 -48.493831) (xy 29.794427 -48.435287) (xy 29.735883 -48.371067) (xy 29.683514 -48.30172)
			(xy 29.637767 -48.227836) (xy 29.599033 -48.150047) (xy 29.567641 -48.069015) (xy 29.54386 -47.985433)
			(xy 29.527892 -47.900013) (xy 29.519874 -47.813484) (xy 24.795988 -47.813484) (xy 24.795988 -50.353484)
			(xy 29.519874 -50.353484) (xy 29.519874 -50.266584) (xy 29.527892 -50.180055) (xy 29.54386 -50.094635)
			(xy 29.567641 -50.011053) (xy 29.599033 -49.930021) (xy 29.637767 -49.852232) (xy 29.683514 -49.778348)
			(xy 29.735883 -49.709001) (xy 29.794427 -49.644781) (xy 29.858647 -49.586237) (xy 29.927994 -49.533868)
			(xy 30.001878 -49.488121) (xy 30.079667 -49.449387) (xy 30.160699 -49.417995) (xy 30.244281 -49.394214)
			(xy 30.329701 -49.378246) (xy 30.41623 -49.370228) (xy 30.50313 -49.370228) (xy 30.589659 -49.378246)
			(xy 30.675079 -49.394214) (xy 30.758661 -49.417995) (xy 30.839693 -49.449387) (xy 30.917482 -49.488121)
			(xy 30.991366 -49.533868) (xy 31.060713 -49.586237) (xy 31.124933 -49.644781) (xy 31.183477 -49.709001)
			(xy 31.235846 -49.778348) (xy 31.281593 -49.852232) (xy 31.320327 -49.930021) (xy 31.351719 -50.011053)
			(xy 31.3755 -50.094635) (xy 31.391468 -50.180055) (xy 31.399486 -50.266584) (xy 31.399988 -50.310034)
			(xy 31.399486 -50.353484) (xy 34.599874 -50.353484) (xy 34.599874 -50.266584) (xy 34.607892 -50.180055)
			(xy 34.62386 -50.094635) (xy 34.647641 -50.011053) (xy 34.679033 -49.930021) (xy 34.717767 -49.852232)
			(xy 34.763514 -49.778348) (xy 34.815883 -49.709001) (xy 34.874427 -49.644781) (xy 34.938647 -49.586237)
			(xy 35.007994 -49.533868) (xy 35.081878 -49.488121) (xy 35.159667 -49.449387) (xy 35.240699 -49.417995)
			(xy 35.324281 -49.394214) (xy 35.409701 -49.378246) (xy 35.49623 -49.370228) (xy 35.58313 -49.370228)
			(xy 35.669659 -49.378246) (xy 35.755079 -49.394214) (xy 35.838661 -49.417995) (xy 35.919693 -49.449387)
			(xy 35.997482 -49.488121) (xy 36.071366 -49.533868) (xy 36.140713 -49.586237) (xy 36.204933 -49.644781)
			(xy 36.263477 -49.709001) (xy 36.315846 -49.778348) (xy 36.361593 -49.852232) (xy 36.400327 -49.930021)
			(xy 36.431719 -50.011053) (xy 36.4555 -50.094635) (xy 36.471468 -50.180055) (xy 36.479486 -50.266584)
			(xy 36.479988 -50.310034) (xy 36.479486 -50.353484) (xy 36.471468 -50.440013) (xy 36.4555 -50.525433)
			(xy 36.431719 -50.609015) (xy 36.400327 -50.690047) (xy 36.361593 -50.767836) (xy 36.315846 -50.84172)
			(xy 36.263477 -50.911067) (xy 36.204933 -50.975287) (xy 36.140713 -51.033831) (xy 36.071366 -51.0862)
			(xy 35.997482 -51.131947) (xy 35.919693 -51.170681) (xy 35.838661 -51.202073) (xy 35.755079 -51.225854)
			(xy 35.669659 -51.241822) (xy 35.58313 -51.24984) (xy 35.49623 -51.24984) (xy 35.409701 -51.241822)
			(xy 35.324281 -51.225854) (xy 35.240699 -51.202073) (xy 35.159667 -51.170681) (xy 35.081878 -51.131947)
			(xy 35.007994 -51.0862) (xy 34.938647 -51.033831) (xy 34.874427 -50.975287) (xy 34.815883 -50.911067)
			(xy 34.763514 -50.84172) (xy 34.717767 -50.767836) (xy 34.679033 -50.690047) (xy 34.647641 -50.609015)
			(xy 34.62386 -50.525433) (xy 34.607892 -50.440013) (xy 34.599874 -50.353484) (xy 31.399486 -50.353484)
			(xy 31.391468 -50.440013) (xy 31.3755 -50.525433) (xy 31.351719 -50.609015) (xy 31.320327 -50.690047)
			(xy 31.281593 -50.767836) (xy 31.235846 -50.84172) (xy 31.183477 -50.911067) (xy 31.124933 -50.975287)
			(xy 31.060713 -51.033831) (xy 30.991366 -51.0862) (xy 30.917482 -51.131947) (xy 30.839693 -51.170681)
			(xy 30.758661 -51.202073) (xy 30.675079 -51.225854) (xy 30.589659 -51.241822) (xy 30.50313 -51.24984)
			(xy 30.41623 -51.24984) (xy 30.329701 -51.241822) (xy 30.244281 -51.225854) (xy 30.160699 -51.202073)
			(xy 30.079667 -51.170681) (xy 30.001878 -51.131947) (xy 29.927994 -51.0862) (xy 29.858647 -51.033831)
			(xy 29.794427 -50.975287) (xy 29.735883 -50.911067) (xy 29.683514 -50.84172) (xy 29.637767 -50.767836)
			(xy 29.599033 -50.690047) (xy 29.567641 -50.609015) (xy 29.54386 -50.525433) (xy 29.527892 -50.440013)
			(xy 29.519874 -50.353484) (xy 24.795988 -50.353484) (xy 24.795988 -51.36007) (xy 39.818564 -51.36007)
			(xy 39.819054 -51.302663) (xy 39.826889 -51.188117) (xy 39.842523 -51.074372) (xy 39.865882 -50.96196)
			(xy 39.896859 -50.851403) (xy 39.935308 -50.743218) (xy 39.98105 -50.63791) (xy 40.033872 -50.535968)
			(xy 40.093527 -50.437869) (xy 40.159738 -50.344069) (xy 40.232196 -50.255007) (xy 40.310562 -50.171096)
			(xy 40.394473 -50.09273) (xy 40.483535 -50.020272) (xy 40.577335 -49.954061) (xy 40.675434 -49.894406)
			(xy 40.777376 -49.841584) (xy 40.882684 -49.795842) (xy 40.990869 -49.757393) (xy 41.101426 -49.726416)
			(xy 41.213838 -49.703057) (xy 41.327583 -49.687423) (xy 41.442129 -49.679588) (xy 41.556943 -49.679588)
			(xy 41.671489 -49.687423) (xy 41.785234 -49.703057) (xy 41.897646 -49.726416) (xy 42.008203 -49.757393)
			(xy 42.116388 -49.795842) (xy 42.221696 -49.841584) (xy 42.323638 -49.894406) (xy 42.421737 -49.954061)
			(xy 42.50107 -50.01006) (xy 43.327577 -50.01006) (xy 43.331612 -49.934356) (xy 43.343671 -49.859511)
			(xy 43.363617 -49.78637) (xy 43.391224 -49.715765) (xy 43.42618 -49.648494) (xy 43.468088 -49.585319)
			(xy 43.516474 -49.526957) (xy 43.57079 -49.474069) (xy 43.630419 -49.427254) (xy 43.694687 -49.387042)
			(xy 43.762864 -49.35389) (xy 43.83418 -49.328172) (xy 43.907825 -49.31018) (xy 43.982965 -49.300118)
			(xy 44.058749 -49.298099) (xy 44.134319 -49.304148) (xy 44.208817 -49.318195) (xy 44.2814 -49.340081)
			(xy 44.351246 -49.369558) (xy 44.417563 -49.406293) (xy 44.479599 -49.449868) (xy 44.536652 -49.49979)
			(xy 44.588076 -49.555494) (xy 44.633287 -49.616349) (xy 44.671774 -49.681664) (xy 44.7031 -49.7507)
			(xy 44.72691 -49.822675) (xy 44.742935 -49.896773) (xy 44.750994 -49.972154) (xy 44.751498 -50.01006)
			(xy 45.867577 -50.01006) (xy 45.871612 -49.934356) (xy 45.883671 -49.859511) (xy 45.903617 -49.78637)
			(xy 45.931224 -49.715765) (xy 45.96618 -49.648494) (xy 46.008088 -49.585319) (xy 46.056474 -49.526957)
			(xy 46.11079 -49.474069) (xy 46.170419 -49.427254) (xy 46.234687 -49.387042) (xy 46.302864 -49.35389)
			(xy 46.37418 -49.328172) (xy 46.447825 -49.31018) (xy 46.522965 -49.300118) (xy 46.598749 -49.298099)
			(xy 46.674319 -49.304148) (xy 46.748817 -49.318195) (xy 46.8214 -49.340081) (xy 46.891246 -49.369558)
			(xy 46.957563 -49.406293) (xy 47.019599 -49.449868) (xy 47.076652 -49.49979) (xy 47.128076 -49.555494)
			(xy 47.173287 -49.616349) (xy 47.211774 -49.681664) (xy 47.2431 -49.7507) (xy 47.26691 -49.822675)
			(xy 47.282935 -49.896773) (xy 47.290994 -49.972154) (xy 47.291498 -50.01006) (xy 48.407577 -50.01006)
			(xy 48.411612 -49.934356) (xy 48.423671 -49.859511) (xy 48.443617 -49.78637) (xy 48.471224 -49.715765)
			(xy 48.50618 -49.648494) (xy 48.548088 -49.585319) (xy 48.596474 -49.526957) (xy 48.65079 -49.474069)
			(xy 48.710419 -49.427254) (xy 48.774687 -49.387042) (xy 48.842864 -49.35389) (xy 48.91418 -49.328172)
			(xy 48.987825 -49.31018) (xy 49.062965 -49.300118) (xy 49.138749 -49.298099) (xy 49.214319 -49.304148)
			(xy 49.288817 -49.318195) (xy 49.3614 -49.340081) (xy 49.431246 -49.369558) (xy 49.497563 -49.406293)
			(xy 49.559599 -49.449868) (xy 49.616652 -49.49979) (xy 49.668076 -49.555494) (xy 49.713287 -49.616349)
			(xy 49.751774 -49.681664) (xy 49.7831 -49.7507) (xy 49.80691 -49.822675) (xy 49.822935 -49.896773)
			(xy 49.830994 -49.972154) (xy 49.831498 -50.01006) (xy 50.947577 -50.01006) (xy 50.951612 -49.934356)
			(xy 50.963671 -49.859511) (xy 50.983617 -49.78637) (xy 51.011224 -49.715765) (xy 51.04618 -49.648494)
			(xy 51.088088 -49.585319) (xy 51.136474 -49.526957) (xy 51.19079 -49.474069) (xy 51.250419 -49.427254)
			(xy 51.314687 -49.387042) (xy 51.382864 -49.35389) (xy 51.45418 -49.328172) (xy 51.527825 -49.31018)
			(xy 51.602965 -49.300118) (xy 51.678749 -49.298099) (xy 51.754319 -49.304148) (xy 51.828817 -49.318195)
			(xy 51.9014 -49.340081) (xy 51.971246 -49.369558) (xy 52.037563 -49.406293) (xy 52.099599 -49.449868)
			(xy 52.156652 -49.49979) (xy 52.208076 -49.555494) (xy 52.253287 -49.616349) (xy 52.291774 -49.681664)
			(xy 52.3231 -49.7507) (xy 52.34691 -49.822675) (xy 52.362935 -49.896773) (xy 52.370994 -49.972154)
			(xy 52.371498 -50.01006) (xy 53.487577 -50.01006) (xy 53.491612 -49.934356) (xy 53.503671 -49.859511)
			(xy 53.523617 -49.78637) (xy 53.551224 -49.715765) (xy 53.58618 -49.648494) (xy 53.628088 -49.585319)
			(xy 53.676474 -49.526957) (xy 53.73079 -49.474069) (xy 53.790419 -49.427254) (xy 53.854687 -49.387042)
			(xy 53.922864 -49.35389) (xy 53.99418 -49.328172) (xy 54.067825 -49.31018) (xy 54.142965 -49.300118)
			(xy 54.218749 -49.298099) (xy 54.294319 -49.304148) (xy 54.368817 -49.318195) (xy 54.4414 -49.340081)
			(xy 54.511246 -49.369558) (xy 54.577563 -49.406293) (xy 54.639599 -49.449868) (xy 54.696652 -49.49979)
			(xy 54.748076 -49.555494) (xy 54.793287 -49.616349) (xy 54.831774 -49.681664) (xy 54.8631 -49.7507)
			(xy 54.88691 -49.822675) (xy 54.902935 -49.896773) (xy 54.910994 -49.972154) (xy 54.911498 -50.01006)
			(xy 56.027577 -50.01006) (xy 56.031612 -49.934356) (xy 56.043671 -49.859511) (xy 56.063617 -49.78637)
			(xy 56.091224 -49.715765) (xy 56.12618 -49.648494) (xy 56.168088 -49.585319) (xy 56.216474 -49.526957)
			(xy 56.27079 -49.474069) (xy 56.330419 -49.427254) (xy 56.394687 -49.387042) (xy 56.462864 -49.35389)
			(xy 56.53418 -49.328172) (xy 56.607825 -49.31018) (xy 56.682965 -49.300118) (xy 56.758749 -49.298099)
			(xy 56.834319 -49.304148) (xy 56.908817 -49.318195) (xy 56.9814 -49.340081) (xy 57.051246 -49.369558)
			(xy 57.117563 -49.406293) (xy 57.179599 -49.449868) (xy 57.236652 -49.49979) (xy 57.288076 -49.555494)
			(xy 57.333287 -49.616349) (xy 57.371774 -49.681664) (xy 57.4031 -49.7507) (xy 57.42691 -49.822675)
			(xy 57.442935 -49.896773) (xy 57.450994 -49.972154) (xy 57.451498 -50.01006) (xy 58.567577 -50.01006)
			(xy 58.571612 -49.934356) (xy 58.583671 -49.859511) (xy 58.603617 -49.78637) (xy 58.631224 -49.715765)
			(xy 58.66618 -49.648494) (xy 58.708088 -49.585319) (xy 58.756474 -49.526957) (xy 58.81079 -49.474069)
			(xy 58.870419 -49.427254) (xy 58.934687 -49.387042) (xy 59.002864 -49.35389) (xy 59.07418 -49.328172)
			(xy 59.147825 -49.31018) (xy 59.222965 -49.300118) (xy 59.298749 -49.298099) (xy 59.374319 -49.304148)
			(xy 59.448817 -49.318195) (xy 59.5214 -49.340081) (xy 59.591246 -49.369558) (xy 59.657563 -49.406293)
			(xy 59.719599 -49.449868) (xy 59.776652 -49.49979) (xy 59.828076 -49.555494) (xy 59.873287 -49.616349)
			(xy 59.911774 -49.681664) (xy 59.9431 -49.7507) (xy 59.96691 -49.822675) (xy 59.982935 -49.896773)
			(xy 59.990994 -49.972154) (xy 59.991498 -50.01006) (xy 61.107577 -50.01006) (xy 61.111612 -49.934356)
			(xy 61.123671 -49.859511) (xy 61.143617 -49.78637) (xy 61.171224 -49.715765) (xy 61.20618 -49.648494)
			(xy 61.248088 -49.585319) (xy 61.296474 -49.526957) (xy 61.35079 -49.474069) (xy 61.410419 -49.427254)
			(xy 61.474687 -49.387042) (xy 61.542864 -49.35389) (xy 61.61418 -49.328172) (xy 61.687825 -49.31018)
			(xy 61.762965 -49.300118) (xy 61.838749 -49.298099) (xy 61.914319 -49.304148) (xy 61.988817 -49.318195)
			(xy 62.0614 -49.340081) (xy 62.131246 -49.369558) (xy 62.197563 -49.406293) (xy 62.259599 -49.449868)
			(xy 62.316652 -49.49979) (xy 62.368076 -49.555494) (xy 62.413287 -49.616349) (xy 62.451774 -49.681664)
			(xy 62.4831 -49.7507) (xy 62.50691 -49.822675) (xy 62.522935 -49.896773) (xy 62.530994 -49.972154)
			(xy 62.531498 -50.01006) (xy 62.530994 -50.047966) (xy 62.522935 -50.123347) (xy 62.50691 -50.197445)
			(xy 62.4831 -50.26942) (xy 62.451774 -50.338456) (xy 62.413287 -50.403771) (xy 62.368076 -50.464626)
			(xy 62.316652 -50.52033) (xy 62.259599 -50.570252) (xy 62.197563 -50.613827) (xy 62.131246 -50.650562)
			(xy 62.0614 -50.680039) (xy 61.988817 -50.701925) (xy 61.914319 -50.715972) (xy 61.838749 -50.722021)
			(xy 61.762965 -50.720002) (xy 61.687825 -50.70994) (xy 61.61418 -50.691948) (xy 61.542864 -50.66623)
			(xy 61.474687 -50.633078) (xy 61.410419 -50.592866) (xy 61.35079 -50.546051) (xy 61.296474 -50.493163)
			(xy 61.248088 -50.434801) (xy 61.20618 -50.371626) (xy 61.171224 -50.304355) (xy 61.143617 -50.23375)
			(xy 61.123671 -50.160609) (xy 61.111612 -50.085764) (xy 61.107577 -50.01006) (xy 59.991498 -50.01006)
			(xy 59.990994 -50.047966) (xy 59.982935 -50.123347) (xy 59.96691 -50.197445) (xy 59.9431 -50.26942)
			(xy 59.911774 -50.338456) (xy 59.873287 -50.403771) (xy 59.828076 -50.464626) (xy 59.776652 -50.52033)
			(xy 59.719599 -50.570252) (xy 59.657563 -50.613827) (xy 59.591246 -50.650562) (xy 59.5214 -50.680039)
			(xy 59.448817 -50.701925) (xy 59.374319 -50.715972) (xy 59.298749 -50.722021) (xy 59.222965 -50.720002)
			(xy 59.147825 -50.70994) (xy 59.07418 -50.691948) (xy 59.002864 -50.66623) (xy 58.934687 -50.633078)
			(xy 58.870419 -50.592866) (xy 58.81079 -50.546051) (xy 58.756474 -50.493163) (xy 58.708088 -50.434801)
			(xy 58.66618 -50.371626) (xy 58.631224 -50.304355) (xy 58.603617 -50.23375) (xy 58.583671 -50.160609)
			(xy 58.571612 -50.085764) (xy 58.567577 -50.01006) (xy 57.451498 -50.01006) (xy 57.450994 -50.047966)
			(xy 57.442935 -50.123347) (xy 57.42691 -50.197445) (xy 57.4031 -50.26942) (xy 57.371774 -50.338456)
			(xy 57.333287 -50.403771) (xy 57.288076 -50.464626) (xy 57.236652 -50.52033) (xy 57.179599 -50.570252)
			(xy 57.117563 -50.613827) (xy 57.051246 -50.650562) (xy 56.9814 -50.680039) (xy 56.908817 -50.701925)
			(xy 56.834319 -50.715972) (xy 56.758749 -50.722021) (xy 56.682965 -50.720002) (xy 56.607825 -50.70994)
			(xy 56.53418 -50.691948) (xy 56.462864 -50.66623) (xy 56.394687 -50.633078) (xy 56.330419 -50.592866)
			(xy 56.27079 -50.546051) (xy 56.216474 -50.493163) (xy 56.168088 -50.434801) (xy 56.12618 -50.371626)
			(xy 56.091224 -50.304355) (xy 56.063617 -50.23375) (xy 56.043671 -50.160609) (xy 56.031612 -50.085764)
			(xy 56.027577 -50.01006) (xy 54.911498 -50.01006) (xy 54.910994 -50.047966) (xy 54.902935 -50.123347)
			(xy 54.88691 -50.197445) (xy 54.8631 -50.26942) (xy 54.831774 -50.338456) (xy 54.793287 -50.403771)
			(xy 54.748076 -50.464626) (xy 54.696652 -50.52033) (xy 54.639599 -50.570252) (xy 54.577563 -50.613827)
			(xy 54.511246 -50.650562) (xy 54.4414 -50.680039) (xy 54.368817 -50.701925) (xy 54.294319 -50.715972)
			(xy 54.218749 -50.722021) (xy 54.142965 -50.720002) (xy 54.067825 -50.70994) (xy 53.99418 -50.691948)
			(xy 53.922864 -50.66623) (xy 53.854687 -50.633078) (xy 53.790419 -50.592866) (xy 53.73079 -50.546051)
			(xy 53.676474 -50.493163) (xy 53.628088 -50.434801) (xy 53.58618 -50.371626) (xy 53.551224 -50.304355)
			(xy 53.523617 -50.23375) (xy 53.503671 -50.160609) (xy 53.491612 -50.085764) (xy 53.487577 -50.01006)
			(xy 52.371498 -50.01006) (xy 52.370994 -50.047966) (xy 52.362935 -50.123347) (xy 52.34691 -50.197445)
			(xy 52.3231 -50.26942) (xy 52.291774 -50.338456) (xy 52.253287 -50.403771) (xy 52.208076 -50.464626)
			(xy 52.156652 -50.52033) (xy 52.099599 -50.570252) (xy 52.037563 -50.613827) (xy 51.971246 -50.650562)
			(xy 51.9014 -50.680039) (xy 51.828817 -50.701925) (xy 51.754319 -50.715972) (xy 51.678749 -50.722021)
			(xy 51.602965 -50.720002) (xy 51.527825 -50.70994) (xy 51.45418 -50.691948) (xy 51.382864 -50.66623)
			(xy 51.314687 -50.633078) (xy 51.250419 -50.592866) (xy 51.19079 -50.546051) (xy 51.136474 -50.493163)
			(xy 51.088088 -50.434801) (xy 51.04618 -50.371626) (xy 51.011224 -50.304355) (xy 50.983617 -50.23375)
			(xy 50.963671 -50.160609) (xy 50.951612 -50.085764) (xy 50.947577 -50.01006) (xy 49.831498 -50.01006)
			(xy 49.830994 -50.047966) (xy 49.822935 -50.123347) (xy 49.80691 -50.197445) (xy 49.7831 -50.26942)
			(xy 49.751774 -50.338456) (xy 49.713287 -50.403771) (xy 49.668076 -50.464626) (xy 49.616652 -50.52033)
			(xy 49.559599 -50.570252) (xy 49.497563 -50.613827) (xy 49.431246 -50.650562) (xy 49.3614 -50.680039)
			(xy 49.288817 -50.701925) (xy 49.214319 -50.715972) (xy 49.138749 -50.722021) (xy 49.062965 -50.720002)
			(xy 48.987825 -50.70994) (xy 48.91418 -50.691948) (xy 48.842864 -50.66623) (xy 48.774687 -50.633078)
			(xy 48.710419 -50.592866) (xy 48.65079 -50.546051) (xy 48.596474 -50.493163) (xy 48.548088 -50.434801)
			(xy 48.50618 -50.371626) (xy 48.471224 -50.304355) (xy 48.443617 -50.23375) (xy 48.423671 -50.160609)
			(xy 48.411612 -50.085764) (xy 48.407577 -50.01006) (xy 47.291498 -50.01006) (xy 47.290994 -50.047966)
			(xy 47.282935 -50.123347) (xy 47.26691 -50.197445) (xy 47.2431 -50.26942) (xy 47.211774 -50.338456)
			(xy 47.173287 -50.403771) (xy 47.128076 -50.464626) (xy 47.076652 -50.52033) (xy 47.019599 -50.570252)
			(xy 46.957563 -50.613827) (xy 46.891246 -50.650562) (xy 46.8214 -50.680039) (xy 46.748817 -50.701925)
			(xy 46.674319 -50.715972) (xy 46.598749 -50.722021) (xy 46.522965 -50.720002) (xy 46.447825 -50.70994)
			(xy 46.37418 -50.691948) (xy 46.302864 -50.66623) (xy 46.234687 -50.633078) (xy 46.170419 -50.592866)
			(xy 46.11079 -50.546051) (xy 46.056474 -50.493163) (xy 46.008088 -50.434801) (xy 45.96618 -50.371626)
			(xy 45.931224 -50.304355) (xy 45.903617 -50.23375) (xy 45.883671 -50.160609) (xy 45.871612 -50.085764)
			(xy 45.867577 -50.01006) (xy 44.751498 -50.01006) (xy 44.750994 -50.047966) (xy 44.742935 -50.123347)
			(xy 44.72691 -50.197445) (xy 44.7031 -50.26942) (xy 44.671774 -50.338456) (xy 44.633287 -50.403771)
			(xy 44.588076 -50.464626) (xy 44.536652 -50.52033) (xy 44.479599 -50.570252) (xy 44.417563 -50.613827)
			(xy 44.351246 -50.650562) (xy 44.2814 -50.680039) (xy 44.208817 -50.701925) (xy 44.134319 -50.715972)
			(xy 44.058749 -50.722021) (xy 43.982965 -50.720002) (xy 43.907825 -50.70994) (xy 43.83418 -50.691948)
			(xy 43.762864 -50.66623) (xy 43.694687 -50.633078) (xy 43.630419 -50.592866) (xy 43.57079 -50.546051)
			(xy 43.516474 -50.493163) (xy 43.468088 -50.434801) (xy 43.42618 -50.371626) (xy 43.391224 -50.304355)
			(xy 43.363617 -50.23375) (xy 43.343671 -50.160609) (xy 43.331612 -50.085764) (xy 43.327577 -50.01006)
			(xy 42.50107 -50.01006) (xy 42.515537 -50.020272) (xy 42.604599 -50.09273) (xy 42.68851 -50.171096)
			(xy 42.766876 -50.255007) (xy 42.839334 -50.344069) (xy 42.905545 -50.437869) (xy 42.9652 -50.535968)
			(xy 43.018022 -50.63791) (xy 43.063764 -50.743218) (xy 43.102213 -50.851403) (xy 43.13319 -50.96196)
			(xy 43.156549 -51.074372) (xy 43.172183 -51.188117) (xy 43.180018 -51.302663) (xy 43.180508 -51.36007)
			(xy 43.180381 -51.393251) (xy 43.177842 -51.459565) (xy 43.175428 -51.492658) (xy 43.170272 -51.550942)
			(xy 43.152948 -51.666671) (xy 43.127616 -51.780914) (xy 43.094401 -51.893119) (xy 43.053462 -52.002742)
			(xy 43.004999 -52.109253) (xy 42.949245 -52.212135) (xy 42.886471 -52.310891) (xy 42.816981 -52.405042)
			(xy 42.741111 -52.494132) (xy 42.659229 -52.577729) (xy 42.571732 -52.65543) (xy 42.500813 -52.71008)
			(xy 43.327577 -52.71008) (xy 43.331612 -52.634376) (xy 43.343671 -52.559531) (xy 43.363617 -52.48639)
			(xy 43.391224 -52.415785) (xy 43.42618 -52.348514) (xy 43.468088 -52.285339) (xy 43.516474 -52.226977)
			(xy 43.57079 -52.174089) (xy 43.630419 -52.127274) (xy 43.694687 -52.087062) (xy 43.762864 -52.05391)
			(xy 43.83418 -52.028192) (xy 43.907825 -52.0102) (xy 43.982965 -52.000138) (xy 44.058749 -51.998119)
			(xy 44.134319 -52.004168) (xy 44.208817 -52.018215) (xy 44.2814 -52.040101) (xy 44.351246 -52.069578)
			(xy 44.417563 -52.106313) (xy 44.479599 -52.149888) (xy 44.536652 -52.19981) (xy 44.588076 -52.255514)
			(xy 44.633287 -52.316369) (xy 44.671774 -52.381684) (xy 44.7031 -52.45072) (xy 44.72691 -52.522695)
			(xy 44.742935 -52.596793) (xy 44.750994 -52.672174) (xy 44.751498 -52.71008) (xy 45.867577 -52.71008)
			(xy 45.871612 -52.634376) (xy 45.883671 -52.559531) (xy 45.903617 -52.48639) (xy 45.931224 -52.415785)
			(xy 45.96618 -52.348514) (xy 46.008088 -52.285339) (xy 46.056474 -52.226977) (xy 46.11079 -52.174089)
			(xy 46.170419 -52.127274) (xy 46.234687 -52.087062) (xy 46.302864 -52.05391) (xy 46.37418 -52.028192)
			(xy 46.447825 -52.0102) (xy 46.522965 -52.000138) (xy 46.598749 -51.998119) (xy 46.674319 -52.004168)
			(xy 46.748817 -52.018215) (xy 46.8214 -52.040101) (xy 46.891246 -52.069578) (xy 46.957563 -52.106313)
			(xy 47.019599 -52.149888) (xy 47.076652 -52.19981) (xy 47.128076 -52.255514) (xy 47.173287 -52.316369)
			(xy 47.211774 -52.381684) (xy 47.2431 -52.45072) (xy 47.26691 -52.522695) (xy 47.282935 -52.596793)
			(xy 47.290994 -52.672174) (xy 47.291498 -52.71008) (xy 48.407577 -52.71008) (xy 48.411612 -52.634376)
			(xy 48.423671 -52.559531) (xy 48.443617 -52.48639) (xy 48.471224 -52.415785) (xy 48.50618 -52.348514)
			(xy 48.548088 -52.285339) (xy 48.596474 -52.226977) (xy 48.65079 -52.174089) (xy 48.710419 -52.127274)
			(xy 48.774687 -52.087062) (xy 48.842864 -52.05391) (xy 48.91418 -52.028192) (xy 48.987825 -52.0102)
			(xy 49.062965 -52.000138) (xy 49.138749 -51.998119) (xy 49.214319 -52.004168) (xy 49.288817 -52.018215)
			(xy 49.3614 -52.040101) (xy 49.431246 -52.069578) (xy 49.497563 -52.106313) (xy 49.559599 -52.149888)
			(xy 49.616652 -52.19981) (xy 49.668076 -52.255514) (xy 49.713287 -52.316369) (xy 49.751774 -52.381684)
			(xy 49.7831 -52.45072) (xy 49.80691 -52.522695) (xy 49.822935 -52.596793) (xy 49.830994 -52.672174)
			(xy 49.831498 -52.71008) (xy 50.947577 -52.71008) (xy 50.951612 -52.634376) (xy 50.963671 -52.559531)
			(xy 50.983617 -52.48639) (xy 51.011224 -52.415785) (xy 51.04618 -52.348514) (xy 51.088088 -52.285339)
			(xy 51.136474 -52.226977) (xy 51.19079 -52.174089) (xy 51.250419 -52.127274) (xy 51.314687 -52.087062)
			(xy 51.382864 -52.05391) (xy 51.45418 -52.028192) (xy 51.527825 -52.0102) (xy 51.602965 -52.000138)
			(xy 51.678749 -51.998119) (xy 51.754319 -52.004168) (xy 51.828817 -52.018215) (xy 51.9014 -52.040101)
			(xy 51.971246 -52.069578) (xy 52.037563 -52.106313) (xy 52.099599 -52.149888) (xy 52.156652 -52.19981)
			(xy 52.208076 -52.255514) (xy 52.253287 -52.316369) (xy 52.291774 -52.381684) (xy 52.3231 -52.45072)
			(xy 52.34691 -52.522695) (xy 52.362935 -52.596793) (xy 52.370994 -52.672174) (xy 52.371498 -52.71008)
			(xy 53.487577 -52.71008) (xy 53.491612 -52.634376) (xy 53.503671 -52.559531) (xy 53.523617 -52.48639)
			(xy 53.551224 -52.415785) (xy 53.58618 -52.348514) (xy 53.628088 -52.285339) (xy 53.676474 -52.226977)
			(xy 53.73079 -52.174089) (xy 53.790419 -52.127274) (xy 53.854687 -52.087062) (xy 53.922864 -52.05391)
			(xy 53.99418 -52.028192) (xy 54.067825 -52.0102) (xy 54.142965 -52.000138) (xy 54.218749 -51.998119)
			(xy 54.294319 -52.004168) (xy 54.368817 -52.018215) (xy 54.4414 -52.040101) (xy 54.511246 -52.069578)
			(xy 54.577563 -52.106313) (xy 54.639599 -52.149888) (xy 54.696652 -52.19981) (xy 54.748076 -52.255514)
			(xy 54.793287 -52.316369) (xy 54.831774 -52.381684) (xy 54.8631 -52.45072) (xy 54.88691 -52.522695)
			(xy 54.902935 -52.596793) (xy 54.910994 -52.672174) (xy 54.911498 -52.71008) (xy 56.027577 -52.71008)
			(xy 56.031612 -52.634376) (xy 56.043671 -52.559531) (xy 56.063617 -52.48639) (xy 56.091224 -52.415785)
			(xy 56.12618 -52.348514) (xy 56.168088 -52.285339) (xy 56.216474 -52.226977) (xy 56.27079 -52.174089)
			(xy 56.330419 -52.127274) (xy 56.394687 -52.087062) (xy 56.462864 -52.05391) (xy 56.53418 -52.028192)
			(xy 56.607825 -52.0102) (xy 56.682965 -52.000138) (xy 56.758749 -51.998119) (xy 56.834319 -52.004168)
			(xy 56.908817 -52.018215) (xy 56.9814 -52.040101) (xy 57.051246 -52.069578) (xy 57.117563 -52.106313)
			(xy 57.179599 -52.149888) (xy 57.236652 -52.19981) (xy 57.288076 -52.255514) (xy 57.333287 -52.316369)
			(xy 57.371774 -52.381684) (xy 57.4031 -52.45072) (xy 57.42691 -52.522695) (xy 57.442935 -52.596793)
			(xy 57.450994 -52.672174) (xy 57.451498 -52.71008) (xy 58.567577 -52.71008) (xy 58.571612 -52.634376)
			(xy 58.583671 -52.559531) (xy 58.603617 -52.48639) (xy 58.631224 -52.415785) (xy 58.66618 -52.348514)
			(xy 58.708088 -52.285339) (xy 58.756474 -52.226977) (xy 58.81079 -52.174089) (xy 58.870419 -52.127274)
			(xy 58.934687 -52.087062) (xy 59.002864 -52.05391) (xy 59.07418 -52.028192) (xy 59.147825 -52.0102)
			(xy 59.222965 -52.000138) (xy 59.298749 -51.998119) (xy 59.374319 -52.004168) (xy 59.448817 -52.018215)
			(xy 59.5214 -52.040101) (xy 59.591246 -52.069578) (xy 59.657563 -52.106313) (xy 59.719599 -52.149888)
			(xy 59.776652 -52.19981) (xy 59.828076 -52.255514) (xy 59.873287 -52.316369) (xy 59.911774 -52.381684)
			(xy 59.9431 -52.45072) (xy 59.96691 -52.522695) (xy 59.982935 -52.596793) (xy 59.990994 -52.672174)
			(xy 59.991498 -52.71008) (xy 61.107577 -52.71008) (xy 61.111612 -52.634376) (xy 61.123671 -52.559531)
			(xy 61.143617 -52.48639) (xy 61.171224 -52.415785) (xy 61.20618 -52.348514) (xy 61.248088 -52.285339)
			(xy 61.296474 -52.226977) (xy 61.35079 -52.174089) (xy 61.410419 -52.127274) (xy 61.474687 -52.087062)
			(xy 61.542864 -52.05391) (xy 61.61418 -52.028192) (xy 61.687825 -52.0102) (xy 61.762965 -52.000138)
			(xy 61.838749 -51.998119) (xy 61.914319 -52.004168) (xy 61.988817 -52.018215) (xy 62.0614 -52.040101)
			(xy 62.131246 -52.069578) (xy 62.197563 -52.106313) (xy 62.259599 -52.149888) (xy 62.316652 -52.19981)
			(xy 62.368076 -52.255514) (xy 62.413287 -52.316369) (xy 62.451774 -52.381684) (xy 62.4831 -52.45072)
			(xy 62.50691 -52.522695) (xy 62.522935 -52.596793) (xy 62.530994 -52.672174) (xy 62.531498 -52.71008)
			(xy 62.530994 -52.747986) (xy 62.522935 -52.823367) (xy 62.50691 -52.897465) (xy 62.4831 -52.96944)
			(xy 62.451774 -53.038476) (xy 62.413287 -53.103791) (xy 62.368076 -53.164646) (xy 62.316652 -53.22035)
			(xy 62.259599 -53.270272) (xy 62.197563 -53.313847) (xy 62.131246 -53.350582) (xy 62.0614 -53.380059)
			(xy 61.988817 -53.401945) (xy 61.914319 -53.415992) (xy 61.838749 -53.422041) (xy 61.762965 -53.420022)
			(xy 61.687825 -53.40996) (xy 61.61418 -53.391968) (xy 61.542864 -53.36625) (xy 61.474687 -53.333098)
			(xy 61.410419 -53.292886) (xy 61.35079 -53.246071) (xy 61.296474 -53.193183) (xy 61.248088 -53.134821)
			(xy 61.20618 -53.071646) (xy 61.171224 -53.004375) (xy 61.143617 -52.93377) (xy 61.123671 -52.860629)
			(xy 61.111612 -52.785784) (xy 61.107577 -52.71008) (xy 59.991498 -52.71008) (xy 59.990994 -52.747986)
			(xy 59.982935 -52.823367) (xy 59.96691 -52.897465) (xy 59.9431 -52.96944) (xy 59.911774 -53.038476)
			(xy 59.873287 -53.103791) (xy 59.828076 -53.164646) (xy 59.776652 -53.22035) (xy 59.719599 -53.270272)
			(xy 59.657563 -53.313847) (xy 59.591246 -53.350582) (xy 59.5214 -53.380059) (xy 59.448817 -53.401945)
			(xy 59.374319 -53.415992) (xy 59.298749 -53.422041) (xy 59.222965 -53.420022) (xy 59.147825 -53.40996)
			(xy 59.07418 -53.391968) (xy 59.002864 -53.36625) (xy 58.934687 -53.333098) (xy 58.870419 -53.292886)
			(xy 58.81079 -53.246071) (xy 58.756474 -53.193183) (xy 58.708088 -53.134821) (xy 58.66618 -53.071646)
			(xy 58.631224 -53.004375) (xy 58.603617 -52.93377) (xy 58.583671 -52.860629) (xy 58.571612 -52.785784)
			(xy 58.567577 -52.71008) (xy 57.451498 -52.71008) (xy 57.450994 -52.747986) (xy 57.442935 -52.823367)
			(xy 57.42691 -52.897465) (xy 57.4031 -52.96944) (xy 57.371774 -53.038476) (xy 57.333287 -53.103791)
			(xy 57.288076 -53.164646) (xy 57.236652 -53.22035) (xy 57.179599 -53.270272) (xy 57.117563 -53.313847)
			(xy 57.051246 -53.350582) (xy 56.9814 -53.380059) (xy 56.908817 -53.401945) (xy 56.834319 -53.415992)
			(xy 56.758749 -53.422041) (xy 56.682965 -53.420022) (xy 56.607825 -53.40996) (xy 56.53418 -53.391968)
			(xy 56.462864 -53.36625) (xy 56.394687 -53.333098) (xy 56.330419 -53.292886) (xy 56.27079 -53.246071)
			(xy 56.216474 -53.193183) (xy 56.168088 -53.134821) (xy 56.12618 -53.071646) (xy 56.091224 -53.004375)
			(xy 56.063617 -52.93377) (xy 56.043671 -52.860629) (xy 56.031612 -52.785784) (xy 56.027577 -52.71008)
			(xy 54.911498 -52.71008) (xy 54.910994 -52.747986) (xy 54.902935 -52.823367) (xy 54.88691 -52.897465)
			(xy 54.8631 -52.96944) (xy 54.831774 -53.038476) (xy 54.793287 -53.103791) (xy 54.748076 -53.164646)
			(xy 54.696652 -53.22035) (xy 54.639599 -53.270272) (xy 54.577563 -53.313847) (xy 54.511246 -53.350582)
			(xy 54.4414 -53.380059) (xy 54.368817 -53.401945) (xy 54.294319 -53.415992) (xy 54.218749 -53.422041)
			(xy 54.142965 -53.420022) (xy 54.067825 -53.40996) (xy 53.99418 -53.391968) (xy 53.922864 -53.36625)
			(xy 53.854687 -53.333098) (xy 53.790419 -53.292886) (xy 53.73079 -53.246071) (xy 53.676474 -53.193183)
			(xy 53.628088 -53.134821) (xy 53.58618 -53.071646) (xy 53.551224 -53.004375) (xy 53.523617 -52.93377)
			(xy 53.503671 -52.860629) (xy 53.491612 -52.785784) (xy 53.487577 -52.71008) (xy 52.371498 -52.71008)
			(xy 52.370994 -52.747986) (xy 52.362935 -52.823367) (xy 52.34691 -52.897465) (xy 52.3231 -52.96944)
			(xy 52.291774 -53.038476) (xy 52.253287 -53.103791) (xy 52.208076 -53.164646) (xy 52.156652 -53.22035)
			(xy 52.099599 -53.270272) (xy 52.037563 -53.313847) (xy 51.971246 -53.350582) (xy 51.9014 -53.380059)
			(xy 51.828817 -53.401945) (xy 51.754319 -53.415992) (xy 51.678749 -53.422041) (xy 51.602965 -53.420022)
			(xy 51.527825 -53.40996) (xy 51.45418 -53.391968) (xy 51.382864 -53.36625) (xy 51.314687 -53.333098)
			(xy 51.250419 -53.292886) (xy 51.19079 -53.246071) (xy 51.136474 -53.193183) (xy 51.088088 -53.134821)
			(xy 51.04618 -53.071646) (xy 51.011224 -53.004375) (xy 50.983617 -52.93377) (xy 50.963671 -52.860629)
			(xy 50.951612 -52.785784) (xy 50.947577 -52.71008) (xy 49.831498 -52.71008) (xy 49.830994 -52.747986)
			(xy 49.822935 -52.823367) (xy 49.80691 -52.897465) (xy 49.7831 -52.96944) (xy 49.751774 -53.038476)
			(xy 49.713287 -53.103791) (xy 49.668076 -53.164646) (xy 49.616652 -53.22035) (xy 49.559599 -53.270272)
			(xy 49.497563 -53.313847) (xy 49.431246 -53.350582) (xy 49.3614 -53.380059) (xy 49.288817 -53.401945)
			(xy 49.214319 -53.415992) (xy 49.138749 -53.422041) (xy 49.062965 -53.420022) (xy 48.987825 -53.40996)
			(xy 48.91418 -53.391968) (xy 48.842864 -53.36625) (xy 48.774687 -53.333098) (xy 48.710419 -53.292886)
			(xy 48.65079 -53.246071) (xy 48.596474 -53.193183) (xy 48.548088 -53.134821) (xy 48.50618 -53.071646)
			(xy 48.471224 -53.004375) (xy 48.443617 -52.93377) (xy 48.423671 -52.860629) (xy 48.411612 -52.785784)
			(xy 48.407577 -52.71008) (xy 47.291498 -52.71008) (xy 47.290994 -52.747986) (xy 47.282935 -52.823367)
			(xy 47.26691 -52.897465) (xy 47.2431 -52.96944) (xy 47.211774 -53.038476) (xy 47.173287 -53.103791)
			(xy 47.128076 -53.164646) (xy 47.076652 -53.22035) (xy 47.019599 -53.270272) (xy 46.957563 -53.313847)
			(xy 46.891246 -53.350582) (xy 46.8214 -53.380059) (xy 46.748817 -53.401945) (xy 46.674319 -53.415992)
			(xy 46.598749 -53.422041) (xy 46.522965 -53.420022) (xy 46.447825 -53.40996) (xy 46.37418 -53.391968)
			(xy 46.302864 -53.36625) (xy 46.234687 -53.333098) (xy 46.170419 -53.292886) (xy 46.11079 -53.246071)
			(xy 46.056474 -53.193183) (xy 46.008088 -53.134821) (xy 45.96618 -53.071646) (xy 45.931224 -53.004375)
			(xy 45.903617 -52.93377) (xy 45.883671 -52.860629) (xy 45.871612 -52.785784) (xy 45.867577 -52.71008)
			(xy 44.751498 -52.71008) (xy 44.750994 -52.747986) (xy 44.742935 -52.823367) (xy 44.72691 -52.897465)
			(xy 44.7031 -52.96944) (xy 44.671774 -53.038476) (xy 44.633287 -53.103791) (xy 44.588076 -53.164646)
			(xy 44.536652 -53.22035) (xy 44.479599 -53.270272) (xy 44.417563 -53.313847) (xy 44.351246 -53.350582)
			(xy 44.2814 -53.380059) (xy 44.208817 -53.401945) (xy 44.134319 -53.415992) (xy 44.058749 -53.422041)
			(xy 43.982965 -53.420022) (xy 43.907825 -53.40996) (xy 43.83418 -53.391968) (xy 43.762864 -53.36625)
			(xy 43.694687 -53.333098) (xy 43.630419 -53.292886) (xy 43.57079 -53.246071) (xy 43.516474 -53.193183)
			(xy 43.468088 -53.134821) (xy 43.42618 -53.071646) (xy 43.391224 -53.004375) (xy 43.363617 -52.93377)
			(xy 43.343671 -52.860629) (xy 43.331612 -52.785784) (xy 43.327577 -52.71008) (xy 42.500813 -52.71008)
			(xy 42.479042 -52.726857) (xy 42.381609 -52.791665) (xy 42.279905 -52.84954) (xy 42.174422 -52.900202)
			(xy 42.065671 -52.943404) (xy 41.954179 -52.978939) (xy 41.840485 -53.006634) (xy 41.725141 -53.026354)
			(xy 41.608704 -53.038005) (xy 41.491739 -53.04153) (xy 41.374812 -53.036912) (xy 41.258489 -53.024173)
			(xy 41.143334 -53.003375) (xy 41.029905 -52.974618) (xy 40.91875 -52.938042) (xy 40.810407 -52.893825)
			(xy 40.705403 -52.842179) (xy 40.604244 -52.783356) (xy 40.507421 -52.71764) (xy 40.415403 -52.645349)
			(xy 40.328636 -52.566834) (xy 40.247539 -52.482474) (xy 40.172506 -52.392679) (xy 40.103899 -52.297883)
			(xy 40.042051 -52.198544) (xy 39.987262 -52.095145) (xy 39.939796 -51.988186) (xy 39.899884 -51.878185)
			(xy 39.86772 -51.765674) (xy 39.843457 -51.651199) (xy 39.827215 -51.535313) (xy 39.819072 -51.418579)
			(xy 39.818564 -51.36007) (xy 24.795988 -51.36007) (xy 24.795988 -52.893484) (xy 29.519874 -52.893484)
			(xy 29.519874 -52.806584) (xy 29.527892 -52.720055) (xy 29.54386 -52.634635) (xy 29.567641 -52.551053)
			(xy 29.599033 -52.470021) (xy 29.637767 -52.392232) (xy 29.683514 -52.318348) (xy 29.735883 -52.249001)
			(xy 29.794427 -52.184781) (xy 29.858647 -52.126237) (xy 29.927994 -52.073868) (xy 30.001878 -52.028121)
			(xy 30.079667 -51.989387) (xy 30.160699 -51.957995) (xy 30.244281 -51.934214) (xy 30.329701 -51.918246)
			(xy 30.41623 -51.910228) (xy 30.50313 -51.910228) (xy 30.589659 -51.918246) (xy 30.675079 -51.934214)
			(xy 30.758661 -51.957995) (xy 30.839693 -51.989387) (xy 30.917482 -52.028121) (xy 30.991366 -52.073868)
			(xy 31.060713 -52.126237) (xy 31.124933 -52.184781) (xy 31.183477 -52.249001) (xy 31.235846 -52.318348)
			(xy 31.281593 -52.392232) (xy 31.320327 -52.470021) (xy 31.351719 -52.551053) (xy 31.3755 -52.634635)
			(xy 31.391468 -52.720055) (xy 31.399486 -52.806584) (xy 31.399988 -52.850034) (xy 31.399486 -52.893484)
			(xy 34.599874 -52.893484) (xy 34.599874 -52.806584) (xy 34.607892 -52.720055) (xy 34.62386 -52.634635)
			(xy 34.647641 -52.551053) (xy 34.679033 -52.470021) (xy 34.717767 -52.392232) (xy 34.763514 -52.318348)
			(xy 34.815883 -52.249001) (xy 34.874427 -52.184781) (xy 34.938647 -52.126237) (xy 35.007994 -52.073868)
			(xy 35.081878 -52.028121) (xy 35.159667 -51.989387) (xy 35.240699 -51.957995) (xy 35.324281 -51.934214)
			(xy 35.409701 -51.918246) (xy 35.49623 -51.910228) (xy 35.58313 -51.910228) (xy 35.669659 -51.918246)
			(xy 35.755079 -51.934214) (xy 35.838661 -51.957995) (xy 35.919693 -51.989387) (xy 35.997482 -52.028121)
			(xy 36.071366 -52.073868) (xy 36.140713 -52.126237) (xy 36.204933 -52.184781) (xy 36.263477 -52.249001)
			(xy 36.315846 -52.318348) (xy 36.361593 -52.392232) (xy 36.400327 -52.470021) (xy 36.431719 -52.551053)
			(xy 36.4555 -52.634635) (xy 36.471468 -52.720055) (xy 36.479486 -52.806584) (xy 36.479988 -52.850034)
			(xy 36.479486 -52.893484) (xy 36.471468 -52.980013) (xy 36.4555 -53.065433) (xy 36.431719 -53.149015)
			(xy 36.400327 -53.230047) (xy 36.361593 -53.307836) (xy 36.315846 -53.38172) (xy 36.263477 -53.451067)
			(xy 36.204933 -53.515287) (xy 36.140713 -53.573831) (xy 36.071366 -53.6262) (xy 35.997482 -53.671947)
			(xy 35.919693 -53.710681) (xy 35.838661 -53.742073) (xy 35.755079 -53.765854) (xy 35.669659 -53.781822)
			(xy 35.58313 -53.78984) (xy 35.49623 -53.78984) (xy 35.409701 -53.781822) (xy 35.324281 -53.765854)
			(xy 35.240699 -53.742073) (xy 35.159667 -53.710681) (xy 35.081878 -53.671947) (xy 35.007994 -53.6262)
			(xy 34.938647 -53.573831) (xy 34.874427 -53.515287) (xy 34.815883 -53.451067) (xy 34.763514 -53.38172)
			(xy 34.717767 -53.307836) (xy 34.679033 -53.230047) (xy 34.647641 -53.149015) (xy 34.62386 -53.065433)
			(xy 34.607892 -52.980013) (xy 34.599874 -52.893484) (xy 31.399486 -52.893484) (xy 31.391468 -52.980013)
			(xy 31.3755 -53.065433) (xy 31.351719 -53.149015) (xy 31.320327 -53.230047) (xy 31.281593 -53.307836)
			(xy 31.235846 -53.38172) (xy 31.183477 -53.451067) (xy 31.124933 -53.515287) (xy 31.060713 -53.573831)
			(xy 30.991366 -53.6262) (xy 30.917482 -53.671947) (xy 30.839693 -53.710681) (xy 30.758661 -53.742073)
			(xy 30.675079 -53.765854) (xy 30.589659 -53.781822) (xy 30.50313 -53.78984) (xy 30.41623 -53.78984)
			(xy 30.329701 -53.781822) (xy 30.244281 -53.765854) (xy 30.160699 -53.742073) (xy 30.079667 -53.710681)
			(xy 30.001878 -53.671947) (xy 29.927994 -53.6262) (xy 29.858647 -53.573831) (xy 29.794427 -53.515287)
			(xy 29.735883 -53.451067) (xy 29.683514 -53.38172) (xy 29.637767 -53.307836) (xy 29.599033 -53.230047)
			(xy 29.567641 -53.149015) (xy 29.54386 -53.065433) (xy 29.527892 -52.980013) (xy 29.519874 -52.893484)
			(xy 24.795988 -52.893484) (xy 24.795988 -60.395098) (xy 56.695513 -60.395098) (xy 56.6994 -60.340749)
			(xy 56.710983 -60.287507) (xy 56.730025 -60.236455) (xy 56.756138 -60.188633) (xy 56.788792 -60.145014)
			(xy 56.82732 -60.106486) (xy 56.87094 -60.073834) (xy 56.918763 -60.047722) (xy 56.969815 -60.028681)
			(xy 57.023057 -60.017099) (xy 57.077405 -60.013213) (xy 57.131754 -60.017101) (xy 57.184996 -60.028684)
			(xy 57.236047 -60.047726) (xy 57.283869 -60.07384) (xy 57.305956 -60.089796) (xy 57.324968 -60.103392)
			(xy 57.366851 -60.124124) (xy 57.411819 -60.13685) (xy 57.458356 -60.14114) (xy 57.504893 -60.13685)
			(xy 57.549861 -60.124124) (xy 57.591744 -60.103392) (xy 57.610756 -60.089796) (xy 57.632841 -60.073827)
			(xy 57.68067 -60.047699) (xy 57.731731 -60.028644) (xy 57.784984 -60.01705) (xy 57.839345 -60.013154)
			(xy 57.893706 -60.017034) (xy 57.946963 -60.028612) (xy 57.998029 -60.047653) (xy 58.045865 -60.073767)
			(xy 58.089498 -60.106424) (xy 58.128038 -60.144958) (xy 58.160702 -60.188586) (xy 58.186823 -60.236419)
			(xy 58.205871 -60.287482) (xy 58.217457 -60.340736) (xy 58.221346 -60.395098) (xy 58.217458 -60.449459)
			(xy 58.205873 -60.502714) (xy 58.186825 -60.553777) (xy 58.160704 -60.60161) (xy 58.128041 -60.645238)
			(xy 58.089501 -60.683773) (xy 58.045869 -60.71643) (xy 57.998033 -60.742545) (xy 57.946967 -60.761586)
			(xy 57.893711 -60.773165) (xy 57.839349 -60.777046) (xy 57.784988 -60.773151) (xy 57.731735 -60.761558)
			(xy 57.680675 -60.742503) (xy 57.632845 -60.716376) (xy 57.610756 -60.700412) (xy 57.591744 -60.686816)
			(xy 57.549861 -60.666084) (xy 57.504893 -60.653358) (xy 57.458356 -60.649068) (xy 57.411819 -60.653358)
			(xy 57.366851 -60.666084) (xy 57.324968 -60.686816) (xy 57.305956 -60.700412) (xy 57.283865 -60.716363)
			(xy 57.236043 -60.742476) (xy 57.184991 -60.761518) (xy 57.131749 -60.7731) (xy 57.077401 -60.776987)
			(xy 57.023052 -60.7731) (xy 56.96981 -60.761518) (xy 56.918758 -60.742477) (xy 56.870936 -60.716363)
			(xy 56.827317 -60.68371) (xy 56.788788 -60.645182) (xy 56.756136 -60.601563) (xy 56.730023 -60.55374)
			(xy 56.710982 -60.502688) (xy 56.6994 -60.449446) (xy 56.695513 -60.395098) (xy 24.795988 -60.395098)
			(xy 24.795988 -62.922827) (xy 47.525168 -62.922827) (xy 47.525168 -62.841717) (xy 47.533118 -62.760998)
			(xy 47.548941 -62.681447) (xy 47.572486 -62.603831) (xy 47.603525 -62.528895) (xy 47.64176 -62.457363)
			(xy 47.686822 -62.389923) (xy 47.738277 -62.327224) (xy 47.79563 -62.269871) (xy 47.858329 -62.218416)
			(xy 47.925769 -62.173354) (xy 47.997301 -62.135119) (xy 48.072237 -62.10408) (xy 48.149853 -62.080535)
			(xy 48.229404 -62.064712) (xy 48.310123 -62.056762) (xy 48.391233 -62.056762) (xy 48.471952 -62.064712)
			(xy 48.551503 -62.080535) (xy 48.629119 -62.10408) (xy 48.704055 -62.135119) (xy 48.775587 -62.173354)
			(xy 48.843027 -62.218416) (xy 48.905726 -62.269871) (xy 48.963079 -62.327224) (xy 49.014534 -62.389923)
			(xy 49.059596 -62.457363) (xy 49.097831 -62.528895) (xy 49.12887 -62.603831) (xy 49.152415 -62.681447)
			(xy 49.168238 -62.760998) (xy 49.176188 -62.841717) (xy 49.176686 -62.882272) (xy 49.176188 -62.922827)
			(xy 51.025288 -62.922827) (xy 51.025288 -62.841717) (xy 51.033238 -62.760998) (xy 51.049061 -62.681447)
			(xy 51.072606 -62.603831) (xy 51.103645 -62.528895) (xy 51.14188 -62.457363) (xy 51.186942 -62.389923)
			(xy 51.238397 -62.327224) (xy 51.29575 -62.269871) (xy 51.358449 -62.218416) (xy 51.425889 -62.173354)
			(xy 51.497421 -62.135119) (xy 51.572357 -62.10408) (xy 51.649973 -62.080535) (xy 51.729524 -62.064712)
			(xy 51.810243 -62.056762) (xy 51.891353 -62.056762) (xy 51.972072 -62.064712) (xy 52.051623 -62.080535)
			(xy 52.129239 -62.10408) (xy 52.204175 -62.135119) (xy 52.275707 -62.173354) (xy 52.343147 -62.218416)
			(xy 52.355656 -62.228682) (xy 56.695534 -62.228682) (xy 56.699423 -62.174337) (xy 56.711007 -62.121098)
			(xy 56.73005 -62.07005) (xy 56.756164 -62.022232) (xy 56.788818 -61.978616) (xy 56.827346 -61.940092)
			(xy 56.870964 -61.907443) (xy 56.918785 -61.881334) (xy 56.969836 -61.862296) (xy 57.023075 -61.850718)
			(xy 57.077421 -61.846834) (xy 57.131766 -61.850724) (xy 57.185005 -61.862308) (xy 57.236053 -61.881351)
			(xy 57.283871 -61.907466) (xy 57.305956 -61.923422) (xy 57.324968 -61.937018) (xy 57.366851 -61.95775)
			(xy 57.411819 -61.970476) (xy 57.458356 -61.974766) (xy 57.504893 -61.970476) (xy 57.549861 -61.95775)
			(xy 57.591744 -61.937018) (xy 57.610756 -61.923422) (xy 57.632817 -61.907418) (xy 57.680647 -61.881286)
			(xy 57.73171 -61.862228) (xy 57.784965 -61.850632) (xy 57.839329 -61.846733) (xy 57.893694 -61.850612)
			(xy 57.946954 -61.862188) (xy 57.998023 -61.881227) (xy 58.045863 -61.907341) (xy 58.0895 -61.939998)
			(xy 58.128044 -61.978533) (xy 58.160711 -62.022162) (xy 58.186836 -62.069996) (xy 58.205887 -62.121061)
			(xy 58.217476 -62.174318) (xy 58.221367 -62.228682) (xy 58.936509 -62.228682) (xy 58.940399 -62.174331)
			(xy 58.951984 -62.121087) (xy 58.97103 -62.070034) (xy 58.997148 -62.022211) (xy 59.029806 -61.978592)
			(xy 59.068339 -61.940064) (xy 59.111964 -61.907414) (xy 59.159791 -61.881304) (xy 59.210847 -61.862267)
			(xy 59.264093 -61.85069) (xy 59.318445 -61.846809) (xy 59.372796 -61.850703) (xy 59.426039 -61.862292)
			(xy 59.477091 -61.881341) (xy 59.524912 -61.907462) (xy 59.546998 -61.923422) (xy 59.56601 -61.937018)
			(xy 59.607893 -61.95775) (xy 59.652861 -61.970476) (xy 59.699398 -61.974766) (xy 59.745935 -61.970476)
			(xy 59.790903 -61.95775) (xy 59.832786 -61.937018) (xy 59.851798 -61.923422) (xy 59.873858 -61.907421)
			(xy 59.921686 -61.881296) (xy 59.972744 -61.862244) (xy 60.025995 -61.850653) (xy 60.080353 -61.846758)
			(xy 60.134712 -61.85064) (xy 60.187965 -61.862218) (xy 60.239029 -61.881257) (xy 60.286863 -61.90737)
			(xy 60.330493 -61.940025) (xy 60.369032 -61.978558) (xy 60.401694 -62.022183) (xy 60.427816 -62.070012)
			(xy 60.446864 -62.121072) (xy 60.458451 -62.174324) (xy 60.462342 -62.228682) (xy 60.840518 -62.228682)
			(xy 60.844408 -62.174333) (xy 60.855993 -62.121091) (xy 60.875038 -62.07004) (xy 60.901154 -62.022219)
			(xy 60.93381 -61.978601) (xy 60.972342 -61.940075) (xy 61.015964 -61.907425) (xy 61.063789 -61.881315)
			(xy 61.114843 -61.862278) (xy 61.168086 -61.8507) (xy 61.222436 -61.846818) (xy 61.276784 -61.850711)
			(xy 61.330026 -61.862298) (xy 61.381076 -61.881345) (xy 61.428896 -61.907464) (xy 61.450982 -61.923422)
			(xy 61.469994 -61.937018) (xy 61.511877 -61.95775) (xy 61.556845 -61.970476) (xy 61.603382 -61.974766)
			(xy 61.649919 -61.970476) (xy 61.694887 -61.95775) (xy 61.73677 -61.937018) (xy 61.755782 -61.923422)
			(xy 61.777842 -61.90742) (xy 61.825671 -61.881293) (xy 61.876731 -61.862238) (xy 61.929983 -61.850645)
			(xy 61.984344 -61.846749) (xy 62.038705 -61.850629) (xy 62.091961 -61.862206) (xy 62.143027 -61.881246)
			(xy 62.190863 -61.907359) (xy 62.234496 -61.940015) (xy 62.273036 -61.978548) (xy 62.305701 -62.022175)
			(xy 62.331823 -62.070006) (xy 62.350873 -62.121068) (xy 62.362461 -62.174321) (xy 62.366351 -62.228682)
			(xy 62.362466 -62.283043) (xy 62.350883 -62.336298) (xy 62.331838 -62.387361) (xy 62.30572 -62.435195)
			(xy 62.27306 -62.478824) (xy 62.234523 -62.517361) (xy 62.190893 -62.550021) (xy 62.143059 -62.576139)
			(xy 62.091995 -62.595183) (xy 62.038741 -62.606766) (xy 61.98438 -62.610651) (xy 61.930019 -62.60676)
			(xy 61.876766 -62.595172) (xy 61.825704 -62.576122) (xy 61.777873 -62.549999) (xy 61.755782 -62.534038)
			(xy 61.73677 -62.520442) (xy 61.694887 -62.49971) (xy 61.649919 -62.486984) (xy 61.603382 -62.482694)
			(xy 61.556845 -62.486984) (xy 61.511877 -62.49971) (xy 61.469994 -62.520442) (xy 61.450982 -62.534038)
			(xy 61.428866 -62.549956) (xy 61.381044 -62.57607) (xy 61.329991 -62.595112) (xy 61.276749 -62.606695)
			(xy 61.2224 -62.610582) (xy 61.168051 -62.606694) (xy 61.114808 -62.595112) (xy 61.063756 -62.57607)
			(xy 61.015934 -62.549956) (xy 60.972314 -62.517302) (xy 60.933787 -62.478772) (xy 60.901134 -62.435151)
			(xy 60.875023 -62.387327) (xy 60.855983 -62.336274) (xy 60.844403 -62.283031) (xy 60.840518 -62.228682)
			(xy 60.462342 -62.228682) (xy 60.458456 -62.283041) (xy 60.446874 -62.336293) (xy 60.427831 -62.387355)
			(xy 60.401714 -62.435187) (xy 60.369055 -62.478815) (xy 60.33052 -62.517351) (xy 60.286893 -62.55001)
			(xy 60.239061 -62.576128) (xy 60.188 -62.595172) (xy 60.134748 -62.606755) (xy 60.080389 -62.610642)
			(xy 60.02603 -62.606752) (xy 59.972779 -62.595166) (xy 59.921718 -62.576118) (xy 59.873888 -62.549998)
			(xy 59.851798 -62.534038) (xy 59.832786 -62.520442) (xy 59.790903 -62.49971) (xy 59.745935 -62.486984)
			(xy 59.699398 -62.482694) (xy 59.652861 -62.486984) (xy 59.607893 -62.49971) (xy 59.56601 -62.520442)
			(xy 59.546998 -62.534038) (xy 59.524882 -62.549957) (xy 59.477058 -62.576074) (xy 59.426004 -62.595118)
			(xy 59.37276 -62.606703) (xy 59.318409 -62.610591) (xy 59.264058 -62.606705) (xy 59.210813 -62.595123)
			(xy 59.159758 -62.576081) (xy 59.111933 -62.549967) (xy 59.068312 -62.517312) (xy 59.029782 -62.478781)
			(xy 58.997128 -62.435159) (xy 58.971015 -62.387334) (xy 58.951974 -62.336279) (xy 58.940394 -62.283033)
			(xy 58.936509 -62.228682) (xy 58.221367 -62.228682) (xy 58.217481 -62.283047) (xy 58.205897 -62.336304)
			(xy 58.186851 -62.387372) (xy 58.16073 -62.435208) (xy 58.128067 -62.47884) (xy 58.089527 -62.517378)
			(xy 58.045894 -62.55004) (xy 57.998056 -62.576158) (xy 57.946988 -62.595202) (xy 57.89373 -62.606783)
			(xy 57.839365 -62.610667) (xy 57.785001 -62.606773) (xy 57.731745 -62.595182) (xy 57.68068 -62.576129)
			(xy 57.632847 -62.550002) (xy 57.610756 -62.534038) (xy 57.591744 -62.520442) (xy 57.549861 -62.49971)
			(xy 57.504893 -62.486984) (xy 57.458356 -62.482694) (xy 57.411819 -62.486984) (xy 57.366851 -62.49971)
			(xy 57.324968 -62.520442) (xy 57.305956 -62.534038) (xy 57.283841 -62.549954) (xy 57.23602 -62.576064)
			(xy 57.18497 -62.595102) (xy 57.131731 -62.606681) (xy 57.077385 -62.610566) (xy 57.02304 -62.606677)
			(xy 56.969801 -62.595093) (xy 56.918753 -62.576051) (xy 56.870934 -62.549938) (xy 56.827318 -62.517284)
			(xy 56.788794 -62.478757) (xy 56.756145 -62.435138) (xy 56.730035 -62.387317) (xy 56.710997 -62.336267)
			(xy 56.699418 -62.283028) (xy 56.695534 -62.228682) (xy 52.355656 -62.228682) (xy 52.405846 -62.269871)
			(xy 52.463199 -62.327224) (xy 52.514654 -62.389923) (xy 52.559716 -62.457363) (xy 52.597951 -62.528895)
			(xy 52.62899 -62.603831) (xy 52.652535 -62.681447) (xy 52.668358 -62.760998) (xy 52.676308 -62.841717)
			(xy 52.676806 -62.882272) (xy 52.676308 -62.922827) (xy 52.668358 -63.003546) (xy 52.652535 -63.083097)
			(xy 52.62899 -63.160713) (xy 52.597951 -63.235649) (xy 52.559716 -63.307181) (xy 52.514654 -63.374621)
			(xy 52.463199 -63.43732) (xy 52.405846 -63.494673) (xy 52.343147 -63.546128) (xy 52.275707 -63.59119)
			(xy 52.204175 -63.629425) (xy 52.129239 -63.660464) (xy 52.051623 -63.684009) (xy 51.972072 -63.699832)
			(xy 51.891353 -63.707782) (xy 51.810243 -63.707782) (xy 51.729524 -63.699832) (xy 51.649973 -63.684009)
			(xy 51.572357 -63.660464) (xy 51.497421 -63.629425) (xy 51.425889 -63.59119) (xy 51.358449 -63.546128)
			(xy 51.29575 -63.494673) (xy 51.238397 -63.43732) (xy 51.186942 -63.374621) (xy 51.14188 -63.307181)
			(xy 51.103645 -63.235649) (xy 51.072606 -63.160713) (xy 51.049061 -63.083097) (xy 51.033238 -63.003546)
			(xy 51.025288 -62.922827) (xy 49.176188 -62.922827) (xy 49.168238 -63.003546) (xy 49.152415 -63.083097)
			(xy 49.12887 -63.160713) (xy 49.097831 -63.235649) (xy 49.059596 -63.307181) (xy 49.014534 -63.374621)
			(xy 48.963079 -63.43732) (xy 48.905726 -63.494673) (xy 48.843027 -63.546128) (xy 48.775587 -63.59119)
			(xy 48.704055 -63.629425) (xy 48.629119 -63.660464) (xy 48.551503 -63.684009) (xy 48.471952 -63.699832)
			(xy 48.391233 -63.707782) (xy 48.310123 -63.707782) (xy 48.229404 -63.699832) (xy 48.149853 -63.684009)
			(xy 48.072237 -63.660464) (xy 47.997301 -63.629425) (xy 47.925769 -63.59119) (xy 47.858329 -63.546128)
			(xy 47.79563 -63.494673) (xy 47.738277 -63.43732) (xy 47.686822 -63.374621) (xy 47.64176 -63.307181)
			(xy 47.603525 -63.235649) (xy 47.572486 -63.160713) (xy 47.548941 -63.083097) (xy 47.533118 -63.003546)
			(xy 47.525168 -62.922827) (xy 24.795988 -62.922827) (xy 24.795988 -64.12972) (xy 56.695483 -64.12972)
			(xy 56.699367 -64.075367) (xy 56.710947 -64.02212) (xy 56.729988 -63.971064) (xy 56.7561 -63.923236)
			(xy 56.788754 -63.879612) (xy 56.827283 -63.841078) (xy 56.870904 -63.808421) (xy 56.918729 -63.782303)
			(xy 56.969784 -63.763258) (xy 57.02303 -63.751673) (xy 57.077383 -63.747783) (xy 57.131736 -63.751668)
			(xy 57.184982 -63.763248) (xy 57.236039 -63.782289) (xy 57.283866 -63.808402) (xy 57.305956 -63.824358)
			(xy 57.324968 -63.837954) (xy 57.366851 -63.858686) (xy 57.411819 -63.871412) (xy 57.458356 -63.875702)
			(xy 57.504893 -63.871412) (xy 57.549861 -63.858686) (xy 57.591744 -63.837954) (xy 57.610756 -63.824358)
			(xy 57.632877 -63.80844) (xy 57.680704 -63.782317) (xy 57.731761 -63.763267) (xy 57.785011 -63.751677)
			(xy 57.839367 -63.747784) (xy 57.893725 -63.751668) (xy 57.946976 -63.763248) (xy 57.998037 -63.78229)
			(xy 58.045868 -63.808405) (xy 58.089495 -63.841062) (xy 58.12803 -63.879596) (xy 58.160689 -63.923222)
			(xy 58.186805 -63.971052) (xy 58.205848 -64.022112) (xy 58.217431 -64.075363) (xy 58.221316 -64.12972)
			(xy 58.936457 -64.12972) (xy 58.940343 -64.075362) (xy 58.951924 -64.022109) (xy 58.970967 -63.971047)
			(xy 58.997084 -63.923215) (xy 59.029742 -63.879587) (xy 59.068276 -63.841051) (xy 59.111904 -63.808391)
			(xy 59.159735 -63.782273) (xy 59.210796 -63.763228) (xy 59.264048 -63.751645) (xy 59.318407 -63.747757)
			(xy 59.372765 -63.751646) (xy 59.426017 -63.763232) (xy 59.477077 -63.782279) (xy 59.524907 -63.808398)
			(xy 59.546998 -63.824358) (xy 59.56601 -63.837954) (xy 59.607893 -63.858686) (xy 59.652861 -63.871412)
			(xy 59.699398 -63.875702) (xy 59.745935 -63.871412) (xy 59.790903 -63.858686) (xy 59.832786 -63.837954)
			(xy 59.851798 -63.824358) (xy 59.873918 -63.808444) (xy 59.921742 -63.782327) (xy 59.972796 -63.763283)
			(xy 60.02604 -63.751698) (xy 60.080391 -63.747809) (xy 60.134743 -63.751696) (xy 60.187988 -63.763278)
			(xy 60.239042 -63.78232) (xy 60.286867 -63.808434) (xy 60.330488 -63.841089) (xy 60.369018 -63.87962)
			(xy 60.401672 -63.923243) (xy 60.427785 -63.971068) (xy 60.446826 -64.022123) (xy 60.458406 -64.075369)
			(xy 60.462291 -64.12972) (xy 60.840467 -64.12972) (xy 60.844352 -64.075364) (xy 60.855933 -64.022114)
			(xy 60.874975 -63.971053) (xy 60.90109 -63.923223) (xy 60.933746 -63.879596) (xy 60.972279 -63.841061)
			(xy 61.015904 -63.808402) (xy 61.063733 -63.782285) (xy 61.114791 -63.76324) (xy 61.168041 -63.751655)
			(xy 61.222397 -63.747767) (xy 61.276754 -63.751654) (xy 61.330004 -63.763238) (xy 61.381063 -63.782283)
			(xy 61.428892 -63.8084) (xy 61.450982 -63.824358) (xy 61.469994 -63.837954) (xy 61.511877 -63.858686)
			(xy 61.556845 -63.871412) (xy 61.603382 -63.875702) (xy 61.649919 -63.871412) (xy 61.694887 -63.858686)
			(xy 61.73677 -63.837954) (xy 61.755782 -63.824358) (xy 61.777902 -63.808442) (xy 61.825727 -63.782323)
			(xy 61.876782 -63.763277) (xy 61.930029 -63.75169) (xy 61.984382 -63.7478) (xy 62.038736 -63.751685)
			(xy 62.091983 -63.763266) (xy 62.14304 -63.782308) (xy 62.190867 -63.808423) (xy 62.234491 -63.841079)
			(xy 62.273023 -63.879611) (xy 62.305678 -63.923235) (xy 62.331793 -63.971062) (xy 62.350834 -64.022119)
			(xy 62.362415 -64.075367) (xy 62.3663 -64.12972) (xy 62.36241 -64.184074) (xy 62.350823 -64.23732)
			(xy 62.331776 -64.288375) (xy 62.305656 -64.3362) (xy 62.272996 -64.37982) (xy 62.23446 -64.418348)
			(xy 62.190833 -64.450999) (xy 62.143003 -64.477109) (xy 62.091944 -64.496145) (xy 62.038695 -64.507721)
			(xy 61.984341 -64.5116) (xy 61.929988 -64.507704) (xy 61.876743 -64.496112) (xy 61.82569 -64.47706)
			(xy 61.777868 -64.450936) (xy 61.755782 -64.434974) (xy 61.73677 -64.421378) (xy 61.694887 -64.400646)
			(xy 61.649919 -64.38792) (xy 61.603382 -64.38363) (xy 61.556845 -64.38792) (xy 61.511877 -64.400646)
			(xy 61.469994 -64.421378) (xy 61.450982 -64.434974) (xy 61.428926 -64.450978) (xy 61.3811 -64.477101)
			(xy 61.330043 -64.49615) (xy 61.276794 -64.50774) (xy 61.222438 -64.511633) (xy 61.168081 -64.507751)
			(xy 61.114831 -64.496172) (xy 61.06377 -64.477132) (xy 61.015938 -64.45102) (xy 60.97231 -64.418365)
			(xy 60.933773 -64.379834) (xy 60.901112 -64.336211) (xy 60.874992 -64.288384) (xy 60.855945 -64.237326)
			(xy 60.844358 -64.184077) (xy 60.840467 -64.12972) (xy 60.462291 -64.12972) (xy 60.4584 -64.184072)
			(xy 60.446814 -64.237316) (xy 60.427768 -64.288369) (xy 60.40165 -64.336192) (xy 60.368992 -64.379811)
			(xy 60.330458 -64.418337) (xy 60.286833 -64.450988) (xy 60.239005 -64.477097) (xy 60.187949 -64.496134)
			(xy 60.134702 -64.50771) (xy 60.08035 -64.511591) (xy 60.026 -64.507696) (xy 59.972756 -64.496106)
			(xy 59.921705 -64.477056) (xy 59.873884 -64.450934) (xy 59.851798 -64.434974) (xy 59.832786 -64.421378)
			(xy 59.790903 -64.400646) (xy 59.745935 -64.38792) (xy 59.699398 -64.38363) (xy 59.652861 -64.38792)
			(xy 59.607893 -64.400646) (xy 59.56601 -64.421378) (xy 59.546998 -64.434974) (xy 59.524942 -64.45098)
			(xy 59.477114 -64.477104) (xy 59.426056 -64.496156) (xy 59.372805 -64.507748) (xy 59.318447 -64.511643)
			(xy 59.264088 -64.507761) (xy 59.210835 -64.496183) (xy 59.159772 -64.477144) (xy 59.111938 -64.451031)
			(xy 59.068307 -64.418376) (xy 59.029768 -64.379844) (xy 58.997106 -64.336219) (xy 58.970984 -64.28839)
			(xy 58.951936 -64.23733) (xy 58.940348 -64.184079) (xy 58.936457 -64.12972) (xy 58.221316 -64.12972)
			(xy 58.217425 -64.184077) (xy 58.205837 -64.237327) (xy 58.186788 -64.288385) (xy 58.160666 -64.336213)
			(xy 58.128003 -64.379835) (xy 58.089464 -64.418365) (xy 58.045834 -64.451017) (xy 57.998 -64.477127)
			(xy 57.946937 -64.496163) (xy 57.893684 -64.507738) (xy 57.839327 -64.511616) (xy 57.78497 -64.507717)
			(xy 57.731722 -64.496122) (xy 57.680666 -64.477066) (xy 57.632843 -64.450938) (xy 57.610756 -64.434974)
			(xy 57.591744 -64.421378) (xy 57.549861 -64.400646) (xy 57.504893 -64.38792) (xy 57.458356 -64.38363)
			(xy 57.411819 -64.38792) (xy 57.366851 -64.400646) (xy 57.324968 -64.421378) (xy 57.305956 -64.434974)
			(xy 57.283901 -64.450976) (xy 57.236076 -64.477094) (xy 57.185022 -64.49614) (xy 57.131776 -64.507727)
			(xy 57.077423 -64.511617) (xy 57.02307 -64.507733) (xy 56.969823 -64.496153) (xy 56.918766 -64.477114)
			(xy 56.870939 -64.451001) (xy 56.827314 -64.418348) (xy 56.78878 -64.379819) (xy 56.756122 -64.336198)
			(xy 56.730005 -64.288374) (xy 56.710959 -64.237319) (xy 56.699373 -64.184073) (xy 56.695483 -64.12972)
			(xy 24.795988 -64.12972) (xy 24.795988 -65.1256) (xy 69.8787 -65.1256) (xy 69.882771 -65.069978)
			(xy 69.894897 -65.015541) (xy 69.91482 -64.96345) (xy 69.942116 -64.914815) (xy 69.976202 -64.870672)
			(xy 70.016351 -64.831963) (xy 70.061709 -64.799512) (xy 70.111309 -64.774011) (xy 70.164093 -64.756004)
			(xy 70.218936 -64.745874) (xy 70.27467 -64.743837) (xy 70.330107 -64.749937) (xy 70.384064 -64.764043)
			(xy 70.435393 -64.785855) (xy 70.482999 -64.814909) (xy 70.525867 -64.850584) (xy 70.563084 -64.892121)
			(xy 70.593857 -64.938634) (xy 70.617529 -64.989131) (xy 70.633597 -65.042538) (xy 70.641717 -65.097714)
			(xy 70.642226 -65.1256) (xy 70.641717 -65.153486) (xy 70.637448 -65.182496) (xy 71.041004 -65.182496)
			(xy 71.045075 -65.126874) (xy 71.057201 -65.072437) (xy 71.077124 -65.020346) (xy 71.10442 -64.971711)
			(xy 71.138506 -64.927568) (xy 71.178655 -64.888859) (xy 71.224013 -64.856408) (xy 71.273613 -64.830907)
			(xy 71.326397 -64.8129) (xy 71.38124 -64.80277) (xy 71.436974 -64.800733) (xy 71.492411 -64.806833)
			(xy 71.546368 -64.820939) (xy 71.597697 -64.842751) (xy 71.645303 -64.871805) (xy 71.688171 -64.90748)
			(xy 71.725388 -64.949017) (xy 71.756161 -64.99553) (xy 71.779833 -65.046027) (xy 71.795901 -65.099434)
			(xy 71.804021 -65.15461) (xy 71.80453 -65.182496) (xy 71.804021 -65.210382) (xy 71.795901 -65.265558)
			(xy 71.779833 -65.318965) (xy 71.756161 -65.369462) (xy 71.725388 -65.415975) (xy 71.688171 -65.457512)
			(xy 71.645303 -65.493187) (xy 71.597697 -65.522241) (xy 71.546368 -65.544053) (xy 71.492411 -65.558159)
			(xy 71.436974 -65.564259) (xy 71.38124 -65.562222) (xy 71.326397 -65.552092) (xy 71.273613 -65.534085)
			(xy 71.224013 -65.508584) (xy 71.178655 -65.476133) (xy 71.138506 -65.437424) (xy 71.10442 -65.393281)
			(xy 71.077124 -65.344646) (xy 71.057201 -65.292555) (xy 71.045075 -65.238118) (xy 71.041004 -65.182496)
			(xy 70.637448 -65.182496) (xy 70.633597 -65.208662) (xy 70.617529 -65.262069) (xy 70.593857 -65.312566)
			(xy 70.563084 -65.359079) (xy 70.525867 -65.400616) (xy 70.482999 -65.436291) (xy 70.435393 -65.465345)
			(xy 70.384064 -65.487157) (xy 70.330107 -65.501263) (xy 70.27467 -65.507363) (xy 70.218936 -65.505326)
			(xy 70.164093 -65.495196) (xy 70.111309 -65.477189) (xy 70.061709 -65.451688) (xy 70.016351 -65.419237)
			(xy 69.976202 -65.380528) (xy 69.942116 -65.336385) (xy 69.91482 -65.28775) (xy 69.894897 -65.235659)
			(xy 69.882771 -65.181222) (xy 69.8787 -65.1256) (xy 24.795988 -65.1256) (xy 24.795988 -65.804802)
			(xy 56.695507 -65.804802) (xy 56.699393 -65.750453) (xy 56.710975 -65.69721) (xy 56.730017 -65.646157)
			(xy 56.75613 -65.598334) (xy 56.788784 -65.554714) (xy 56.827312 -65.516185) (xy 56.870932 -65.483531)
			(xy 56.918756 -65.457418) (xy 56.969808 -65.438376) (xy 57.023051 -65.426794) (xy 57.077401 -65.422907)
			(xy 57.13175 -65.426794) (xy 57.184993 -65.438376) (xy 57.236046 -65.457418) (xy 57.283869 -65.483532)
			(xy 57.305956 -65.499488) (xy 57.324968 -65.513084) (xy 57.366851 -65.533816) (xy 57.411819 -65.546542)
			(xy 57.458356 -65.550832) (xy 57.504893 -65.546542) (xy 57.549861 -65.533816) (xy 57.591744 -65.513084)
			(xy 57.610756 -65.499488) (xy 57.632849 -65.48353) (xy 57.680677 -65.457403) (xy 57.731737 -65.438349)
			(xy 57.784989 -65.426756) (xy 57.839349 -65.42286) (xy 57.89371 -65.426741) (xy 57.946965 -65.43832)
			(xy 57.998031 -65.45736) (xy 58.045866 -65.483475) (xy 58.089497 -65.516132) (xy 58.128037 -65.554666)
			(xy 58.160699 -65.598294) (xy 58.18682 -65.646126) (xy 58.205866 -65.697188) (xy 58.217452 -65.750442)
			(xy 58.22134 -65.804802) (xy 58.936481 -65.804802) (xy 58.940369 -65.750447) (xy 58.951953 -65.697199)
			(xy 58.970997 -65.646141) (xy 58.997114 -65.598313) (xy 59.029772 -65.554689) (xy 59.068306 -65.516157)
			(xy 59.111932 -65.483502) (xy 59.159761 -65.457388) (xy 59.21082 -65.438346) (xy 59.264069 -65.426766)
			(xy 59.318425 -65.422881) (xy 59.372779 -65.426773) (xy 59.426027 -65.43836) (xy 59.477084 -65.457408)
			(xy 59.52491 -65.483528) (xy 59.546998 -65.499488) (xy 59.56601 -65.513084) (xy 59.607893 -65.533816)
			(xy 59.652861 -65.546542) (xy 59.699398 -65.550832) (xy 59.745935 -65.546542) (xy 59.790903 -65.533816)
			(xy 59.832786 -65.513084) (xy 59.851798 -65.499488) (xy 59.87389 -65.483533) (xy 59.921715 -65.457413)
			(xy 59.972771 -65.438365) (xy 60.026019 -65.426777) (xy 60.080373 -65.422885) (xy 60.134728 -65.426769)
			(xy 60.187977 -65.43835) (xy 60.239036 -65.457391) (xy 60.286865 -65.483504) (xy 60.330491 -65.516159)
			(xy 60.369025 -65.554691) (xy 60.401682 -65.598315) (xy 60.427799 -65.646142) (xy 60.446843 -65.697199)
			(xy 60.458427 -65.750448) (xy 60.462315 -65.804802) (xy 60.840491 -65.804802) (xy 60.844378 -65.750449)
			(xy 60.855961 -65.697203) (xy 60.875004 -65.646147) (xy 60.90112 -65.598321) (xy 60.933776 -65.554699)
			(xy 60.972308 -65.516168) (xy 61.015932 -65.483513) (xy 61.063759 -65.457399) (xy 61.114815 -65.438358)
			(xy 61.168062 -65.426776) (xy 61.222415 -65.422891) (xy 61.276768 -65.426781) (xy 61.330014 -65.438366)
			(xy 61.381069 -65.457412) (xy 61.428894 -65.48353) (xy 61.450982 -65.499488) (xy 61.469994 -65.513084)
			(xy 61.511877 -65.533816) (xy 61.556845 -65.546542) (xy 61.603382 -65.550832) (xy 61.649919 -65.546542)
			(xy 61.694887 -65.533816) (xy 61.73677 -65.513084) (xy 61.755782 -65.499488) (xy 61.777874 -65.483532)
			(xy 61.825701 -65.457409) (xy 61.876758 -65.438359) (xy 61.930008 -65.426769) (xy 61.984364 -65.422876)
			(xy 62.038721 -65.426759) (xy 62.091973 -65.438338) (xy 62.143034 -65.457379) (xy 62.190865 -65.483493)
			(xy 62.234493 -65.516149) (xy 62.273029 -65.554682) (xy 62.305689 -65.598307) (xy 62.331807 -65.646136)
			(xy 62.350852 -65.697195) (xy 62.362437 -65.750445) (xy 62.366324 -65.804802) (xy 62.362436 -65.859159)
			(xy 62.350851 -65.912409) (xy 62.331805 -65.963469) (xy 62.305686 -66.011297) (xy 62.273026 -66.054922)
			(xy 62.23449 -66.093454) (xy 62.190861 -66.126109) (xy 62.184353 -66.129662) (xy 68.59092 -66.129662)
			(xy 68.594991 -66.07404) (xy 68.607117 -66.019603) (xy 68.62704 -65.967512) (xy 68.654336 -65.918877)
			(xy 68.688422 -65.874734) (xy 68.728571 -65.836025) (xy 68.773929 -65.803574) (xy 68.823529 -65.778073)
			(xy 68.876313 -65.760066) (xy 68.931156 -65.749936) (xy 68.98689 -65.747899) (xy 69.042327 -65.753999)
			(xy 69.096284 -65.768105) (xy 69.147613 -65.789917) (xy 69.195219 -65.818971) (xy 69.238087 -65.854646)
			(xy 69.275304 -65.896183) (xy 69.306077 -65.942696) (xy 69.329749 -65.993193) (xy 69.345817 -66.0466)
			(xy 69.353937 -66.101776) (xy 69.354446 -66.129662) (xy 69.353937 -66.157548) (xy 69.345817 -66.212724)
			(xy 69.329749 -66.266131) (xy 69.306077 -66.316628) (xy 69.275304 -66.363141) (xy 69.238087 -66.404678)
			(xy 69.195219 -66.440353) (xy 69.147613 -66.469407) (xy 69.096284 -66.491219) (xy 69.042327 -66.505325)
			(xy 68.98689 -66.511425) (xy 68.931156 -66.509388) (xy 68.876313 -66.499258) (xy 68.823529 -66.481251)
			(xy 68.773929 -66.45575) (xy 68.728571 -66.423299) (xy 68.688422 -66.38459) (xy 68.654336 -66.340447)
			(xy 68.62704 -66.291812) (xy 68.607117 -66.239721) (xy 68.594991 -66.185284) (xy 68.59092 -66.129662)
			(xy 62.184353 -66.129662) (xy 62.143029 -66.152223) (xy 62.091968 -66.171263) (xy 62.038717 -66.182842)
			(xy 61.984359 -66.186724) (xy 61.930003 -66.18283) (xy 61.876754 -66.17124) (xy 61.825696 -66.152189)
			(xy 61.77787 -66.126065) (xy 61.755782 -66.110104) (xy 61.73677 -66.096508) (xy 61.694887 -66.075776)
			(xy 61.649919 -66.06305) (xy 61.603382 -66.05876) (xy 61.556845 -66.06305) (xy 61.511877 -66.075776)
			(xy 61.469994 -66.096508) (xy 61.450982 -66.110104) (xy 61.428898 -66.126068) (xy 61.381073 -66.152186)
			(xy 61.330019 -66.171232) (xy 61.276773 -66.182819) (xy 61.22242 -66.186709) (xy 61.168067 -66.182824)
			(xy 61.11482 -66.171244) (xy 61.063763 -66.152203) (xy 61.015936 -66.12609) (xy 60.972312 -66.093435)
			(xy 60.933779 -66.054905) (xy 60.901123 -66.011283) (xy 60.875006 -65.963457) (xy 60.855963 -65.912402)
			(xy 60.844379 -65.859155) (xy 60.840491 -65.804802) (xy 60.462315 -65.804802) (xy 60.458426 -65.859157)
			(xy 60.446842 -65.912405) (xy 60.427797 -65.963462) (xy 60.40168 -66.01129) (xy 60.369021 -66.054913)
			(xy 60.330487 -66.093444) (xy 60.286861 -66.126098) (xy 60.239032 -66.152211) (xy 60.187973 -66.171252)
			(xy 60.134723 -66.182831) (xy 60.080368 -66.186715) (xy 60.026014 -66.182822) (xy 59.972767 -66.171234)
			(xy 59.921711 -66.152185) (xy 59.873886 -66.126064) (xy 59.851798 -66.110104) (xy 59.832786 -66.096508)
			(xy 59.790903 -66.075776) (xy 59.745935 -66.06305) (xy 59.699398 -66.05876) (xy 59.652861 -66.06305)
			(xy 59.607893 -66.075776) (xy 59.56601 -66.096508) (xy 59.546998 -66.110104) (xy 59.524914 -66.126069)
			(xy 59.477088 -66.15219) (xy 59.426032 -66.171239) (xy 59.372784 -66.182827) (xy 59.318429 -66.186719)
			(xy 59.264074 -66.182835) (xy 59.210825 -66.171255) (xy 59.159765 -66.152214) (xy 59.111936 -66.126101)
			(xy 59.068309 -66.093446) (xy 59.029775 -66.054915) (xy 58.997116 -66.011291) (xy 58.970999 -65.963464)
			(xy 58.951954 -65.912406) (xy 58.94037 -65.859157) (xy 58.936481 -65.804802) (xy 58.22134 -65.804802)
			(xy 58.217451 -65.859163) (xy 58.205865 -65.912416) (xy 58.186818 -65.963479) (xy 58.160696 -66.01131)
			(xy 58.128033 -66.054937) (xy 58.089494 -66.093471) (xy 58.045862 -66.126128) (xy 57.998026 -66.152242)
			(xy 57.946961 -66.171281) (xy 57.893706 -66.182859) (xy 57.839345 -66.18674) (xy 57.784985 -66.182844)
			(xy 57.731733 -66.17125) (xy 57.680673 -66.152196) (xy 57.632845 -66.126068) (xy 57.610756 -66.110104)
			(xy 57.591744 -66.096508) (xy 57.549861 -66.075776) (xy 57.504893 -66.06305) (xy 57.458356 -66.05876)
			(xy 57.411819 -66.06305) (xy 57.366851 -66.075776) (xy 57.324968 -66.096508) (xy 57.305956 -66.110104)
			(xy 57.283873 -66.126066) (xy 57.23605 -66.15218) (xy 57.184998 -66.171222) (xy 57.131755 -66.182805)
			(xy 57.077405 -66.186693) (xy 57.023056 -66.182807) (xy 56.969813 -66.171225) (xy 56.91876 -66.152184)
			(xy 56.870936 -66.126071) (xy 56.827316 -66.093418) (xy 56.788787 -66.05489) (xy 56.756133 -66.01127)
			(xy 56.730019 -65.963447) (xy 56.710977 -65.912395) (xy 56.699394 -65.859152) (xy 56.695507 -65.804802)
			(xy 24.795988 -65.804802) (xy 24.795988 -66.444914) (xy 44.076475 -66.444914) (xy 44.080361 -66.390559)
			(xy 44.091943 -66.33731) (xy 44.110985 -66.286251) (xy 44.1371 -66.238422) (xy 44.169756 -66.194797)
			(xy 44.208289 -66.156263) (xy 44.251913 -66.123606) (xy 44.299741 -66.097489) (xy 44.350799 -66.078446)
			(xy 44.404048 -66.066862) (xy 44.458403 -66.062975) (xy 44.512759 -66.066863) (xy 44.566007 -66.078448)
			(xy 44.617065 -66.097492) (xy 44.664893 -66.12361) (xy 44.686982 -66.139568) (xy 44.705994 -66.153164)
			(xy 44.747877 -66.173896) (xy 44.792845 -66.186622) (xy 44.839382 -66.190912) (xy 44.885919 -66.186622)
			(xy 44.930887 -66.173896) (xy 44.97277 -66.153164) (xy 44.991782 -66.139568) (xy 45.013893 -66.123639)
			(xy 45.061718 -66.097518) (xy 45.112774 -66.078471) (xy 45.166022 -66.066883) (xy 45.220376 -66.062992)
			(xy 45.274731 -66.066876) (xy 45.32798 -66.078457) (xy 45.379038 -66.097499) (xy 45.426867 -66.123613)
			(xy 45.470492 -66.156269) (xy 45.509025 -66.194801) (xy 45.541682 -66.238425) (xy 45.567797 -66.286253)
			(xy 45.58684 -66.337311) (xy 45.598422 -66.39056) (xy 45.602308 -66.444914) (xy 45.598418 -66.499269)
			(xy 45.586832 -66.552516) (xy 45.567786 -66.603573) (xy 45.541666 -66.651399) (xy 45.509006 -66.695021)
			(xy 45.47047 -66.73355) (xy 45.426842 -66.766202) (xy 45.379012 -66.792313) (xy 45.327952 -66.811351)
			(xy 45.274702 -66.822928) (xy 45.220347 -66.826808) (xy 45.165993 -66.822913) (xy 45.112747 -66.811321)
			(xy 45.061692 -66.79227) (xy 45.013869 -66.766146) (xy 44.991782 -66.750184) (xy 44.97277 -66.736588)
			(xy 44.930887 -66.715856) (xy 44.885919 -66.70313) (xy 44.839382 -66.69884) (xy 44.792845 -66.70313)
			(xy 44.747877 -66.715856) (xy 44.705994 -66.736588) (xy 44.686982 -66.750184) (xy 44.664917 -66.766175)
			(xy 44.617091 -66.792296) (xy 44.566035 -66.811344) (xy 44.512787 -66.822933) (xy 44.458432 -66.826825)
			(xy 44.404077 -66.822942) (xy 44.350827 -66.811362) (xy 44.299768 -66.792323) (xy 44.251937 -66.76621)
			(xy 44.208311 -66.733555) (xy 44.169775 -66.695025) (xy 44.137116 -66.651402) (xy 44.110997 -66.603575)
			(xy 44.091951 -66.552518) (xy 44.080365 -66.499269) (xy 44.076475 -66.444914) (xy 24.795988 -66.444914)
			(xy 24.795988 -67.816019) (xy 56.651945 -67.816019) (xy 56.65583 -67.761657) (xy 56.667413 -67.708402)
			(xy 56.686458 -67.657337) (xy 56.712576 -67.609503) (xy 56.745237 -67.565873) (xy 56.783775 -67.527336)
			(xy 56.827405 -67.494675) (xy 56.875239 -67.468557) (xy 56.926304 -67.449513) (xy 56.97956 -67.43793)
			(xy 57.033921 -67.434045) (xy 57.088283 -67.437936) (xy 57.141537 -67.449525) (xy 57.192599 -67.468575)
			(xy 57.240431 -67.494698) (xy 57.262522 -67.51066) (xy 57.281534 -67.524256) (xy 57.323417 -67.544988)
			(xy 57.368385 -67.557714) (xy 57.414922 -67.562004) (xy 57.461459 -67.557714) (xy 57.506427 -67.544988)
			(xy 57.54831 -67.524256) (xy 57.567322 -67.51066) (xy 57.58944 -67.494745) (xy 57.637262 -67.468632)
			(xy 57.688313 -67.449591) (xy 57.741555 -67.438009) (xy 57.795904 -67.434122) (xy 57.850252 -67.43801)
			(xy 57.903494 -67.449593) (xy 57.954545 -67.468635) (xy 58.002367 -67.494749) (xy 58.045985 -67.527403)
			(xy 58.084512 -67.565932) (xy 58.117163 -67.609553) (xy 58.143274 -67.657376) (xy 58.162314 -67.708428)
			(xy 58.173893 -67.761671) (xy 58.177778 -67.816019) (xy 58.893079 -67.816019) (xy 58.896964 -67.761665)
			(xy 58.908545 -67.708418) (xy 58.927586 -67.65736) (xy 58.953699 -67.609532) (xy 58.986353 -67.565907)
			(xy 59.024884 -67.527374) (xy 59.068506 -67.494716) (xy 59.116332 -67.468599) (xy 59.167388 -67.449554)
			(xy 59.220635 -67.437969) (xy 59.274988 -67.434079) (xy 59.329342 -67.437965) (xy 59.38259 -67.449547)
			(xy 59.433647 -67.468589) (xy 59.481474 -67.494703) (xy 59.503564 -67.51066) (xy 59.522576 -67.524256)
			(xy 59.564459 -67.544988) (xy 59.609427 -67.557714) (xy 59.655964 -67.562004) (xy 59.702501 -67.557714)
			(xy 59.747469 -67.544988) (xy 59.789352 -67.524256) (xy 59.808364 -67.51066) (xy 59.830483 -67.49474)
			(xy 59.878309 -67.468618) (xy 59.929366 -67.449568) (xy 59.982615 -67.43798) (xy 60.036971 -67.434088)
			(xy 60.091327 -67.437971) (xy 60.144578 -67.449552) (xy 60.195638 -67.468594) (xy 60.243468 -67.494708)
			(xy 60.287094 -67.527365) (xy 60.325628 -67.565898) (xy 60.358286 -67.609524) (xy 60.384402 -67.657353)
			(xy 60.403445 -67.708413) (xy 60.415027 -67.761663) (xy 60.418912 -67.816019) (xy 60.796929 -67.816019)
			(xy 60.800815 -67.761654) (xy 60.812399 -67.708395) (xy 60.831445 -67.657327) (xy 60.857566 -67.60949)
			(xy 60.89023 -67.565858) (xy 60.928771 -67.527318) (xy 60.972404 -67.494657) (xy 61.020243 -67.468538)
			(xy 61.071311 -67.449494) (xy 61.124571 -67.437913) (xy 61.178936 -67.434029) (xy 61.233301 -67.437923)
			(xy 61.286558 -67.449515) (xy 61.337623 -67.468568) (xy 61.385456 -67.494696) (xy 61.407548 -67.51066)
			(xy 61.42656 -67.524256) (xy 61.468443 -67.544988) (xy 61.513411 -67.557714) (xy 61.559948 -67.562004)
			(xy 61.606485 -67.557714) (xy 61.651453 -67.544988) (xy 61.693336 -67.524256) (xy 61.712348 -67.51066)
			(xy 61.734465 -67.494747) (xy 61.782285 -67.468638) (xy 61.833335 -67.449601) (xy 61.886574 -67.438022)
			(xy 61.940918 -67.434138) (xy 61.995263 -67.438027) (xy 62.048501 -67.449611) (xy 62.099548 -67.468654)
			(xy 62.147366 -67.494767) (xy 62.190981 -67.52742) (xy 62.229505 -67.565948) (xy 62.262153 -67.609566)
			(xy 62.288262 -67.657386) (xy 62.307299 -67.708435) (xy 62.318878 -67.761674) (xy 62.322762 -67.816019)
			(xy 62.318873 -67.870364) (xy 62.307289 -67.923602) (xy 62.288246 -67.974649) (xy 62.262132 -68.022467)
			(xy 62.229479 -68.066081) (xy 62.190952 -68.104605) (xy 62.147334 -68.137254) (xy 62.099513 -68.163362)
			(xy 62.048464 -68.1824) (xy 61.995225 -68.193978) (xy 61.94088 -68.197862) (xy 61.886536 -68.193972)
			(xy 61.833298 -68.182388) (xy 61.78225 -68.163346) (xy 61.734433 -68.137232) (xy 61.712348 -68.121276)
			(xy 61.693336 -68.10768) (xy 61.651453 -68.086948) (xy 61.606485 -68.074222) (xy 61.559948 -68.069932)
			(xy 61.513411 -68.074222) (xy 61.468443 -68.086948) (xy 61.42656 -68.10768) (xy 61.407548 -68.121276)
			(xy 61.385489 -68.137283) (xy 61.337658 -68.163416) (xy 61.286595 -68.182475) (xy 61.233339 -68.194072)
			(xy 61.178975 -68.197971) (xy 61.124609 -68.194093) (xy 61.071348 -68.182517) (xy 61.020278 -68.163478)
			(xy 60.972437 -68.137364) (xy 60.9288 -68.104707) (xy 60.890255 -68.066171) (xy 60.857587 -68.022542)
			(xy 60.831461 -67.974708) (xy 60.81241 -67.923642) (xy 60.80082 -67.870384) (xy 60.796929 -67.816019)
			(xy 60.418912 -67.816019) (xy 60.415022 -67.870375) (xy 60.403434 -67.923624) (xy 60.384386 -67.974682)
			(xy 60.358265 -68.022508) (xy 60.325603 -68.066131) (xy 60.287065 -68.10466) (xy 60.243435 -68.137312)
			(xy 60.195603 -68.163422) (xy 60.144541 -68.182459) (xy 60.091289 -68.194034) (xy 60.036932 -68.197912)
			(xy 59.982577 -68.194015) (xy 59.929329 -68.182421) (xy 59.878274 -68.163366) (xy 59.830451 -68.137239)
			(xy 59.808364 -68.121276) (xy 59.789352 -68.10768) (xy 59.747469 -68.086948) (xy 59.702501 -68.074222)
			(xy 59.655964 -68.069932) (xy 59.609427 -68.074222) (xy 59.564459 -68.086948) (xy 59.522576 -68.10768)
			(xy 59.503564 -68.121276) (xy 59.481507 -68.137276) (xy 59.433682 -68.163395) (xy 59.382626 -68.182442)
			(xy 59.32938 -68.194029) (xy 59.275027 -68.197921) (xy 59.220673 -68.194037) (xy 59.167425 -68.182457)
			(xy 59.116367 -68.163417) (xy 59.068538 -68.137305) (xy 59.024913 -68.104652) (xy 58.986379 -68.066122)
			(xy 58.95372 -68.0225) (xy 58.927602 -67.974675) (xy 58.908556 -67.923619) (xy 58.89697 -67.870373)
			(xy 58.893079 -67.816019) (xy 58.177778 -67.816019) (xy 58.173888 -67.870367) (xy 58.162303 -67.923609)
			(xy 58.143258 -67.974659) (xy 58.117143 -68.02248) (xy 58.084487 -68.066097) (xy 58.045956 -68.104622)
			(xy 58.002334 -68.137272) (xy 57.95451 -68.163381) (xy 57.903457 -68.182418) (xy 57.850214 -68.193995)
			(xy 57.795865 -68.197878) (xy 57.741517 -68.193986) (xy 57.688277 -68.182398) (xy 57.637227 -68.163352)
			(xy 57.589407 -68.137234) (xy 57.567322 -68.121276) (xy 57.54831 -68.10768) (xy 57.506427 -68.086948)
			(xy 57.461459 -68.074222) (xy 57.414922 -68.069932) (xy 57.368385 -68.074222) (xy 57.323417 -68.086948)
			(xy 57.281534 -68.10768) (xy 57.262522 -68.121276) (xy 57.240463 -68.137281) (xy 57.192634 -68.163409)
			(xy 57.141574 -68.182465) (xy 57.088321 -68.194059) (xy 57.03396 -68.197955) (xy 56.979598 -68.194076)
			(xy 56.926341 -68.182498) (xy 56.875274 -68.163459) (xy 56.827437 -68.137346) (xy 56.783804 -68.10469)
			(xy 56.745262 -68.066156) (xy 56.712597 -68.022529) (xy 56.686474 -67.974698) (xy 56.667424 -67.923635)
			(xy 56.655836 -67.870381) (xy 56.651945 -67.816019) (xy 24.795988 -67.816019) (xy 24.795988 -68.278499)
			(xy 44.076496 -68.278499) (xy 44.080384 -68.224147) (xy 44.091967 -68.170901) (xy 44.11101 -68.119846)
			(xy 44.137126 -68.072021) (xy 44.169782 -68.028399) (xy 44.208314 -67.989869) (xy 44.251938 -67.957215)
			(xy 44.299764 -67.931102) (xy 44.35082 -67.912061) (xy 44.404067 -67.900481) (xy 44.458419 -67.896596)
			(xy 44.512771 -67.900486) (xy 44.566016 -67.912072) (xy 44.61707 -67.931118) (xy 44.664894 -67.957236)
			(xy 44.686982 -67.973194) (xy 44.705994 -67.98679) (xy 44.747877 -68.007522) (xy 44.792845 -68.020248)
			(xy 44.839382 -68.024538) (xy 44.885919 -68.020248) (xy 44.930887 -68.007522) (xy 44.97277 -67.98679)
			(xy 44.991782 -67.973194) (xy 45.013869 -67.95723) (xy 45.061696 -67.931106) (xy 45.112754 -67.912055)
			(xy 45.166003 -67.900465) (xy 45.220361 -67.896571) (xy 45.274719 -67.900453) (xy 45.327971 -67.912033)
			(xy 45.379033 -67.931073) (xy 45.426865 -67.957187) (xy 45.470494 -67.989843) (xy 45.50903 -68.028376)
			(xy 45.541691 -68.072001) (xy 45.56781 -68.11983) (xy 45.586856 -68.17089) (xy 45.598441 -68.224141)
			(xy 45.602329 -68.278499) (xy 45.598441 -68.332856) (xy 45.586856 -68.386107) (xy 45.567811 -68.437167)
			(xy 45.541692 -68.484997) (xy 45.509032 -68.528622) (xy 45.470495 -68.567156) (xy 45.426867 -68.599812)
			(xy 45.379035 -68.625926) (xy 45.327973 -68.644967) (xy 45.274721 -68.656546) (xy 45.220363 -68.660429)
			(xy 45.166006 -68.656536) (xy 45.112756 -68.644946) (xy 45.061698 -68.625895) (xy 45.013871 -68.599771)
			(xy 44.991782 -68.58381) (xy 44.97277 -68.570214) (xy 44.930887 -68.549482) (xy 44.885919 -68.536756)
			(xy 44.839382 -68.532466) (xy 44.792845 -68.536756) (xy 44.747877 -68.549482) (xy 44.705994 -68.570214)
			(xy 44.686982 -68.58381) (xy 44.664892 -68.599766) (xy 44.617068 -68.625883) (xy 44.566014 -68.644929)
			(xy 44.512769 -68.656514) (xy 44.458417 -68.660404) (xy 44.404064 -68.656519) (xy 44.350818 -68.644938)
			(xy 44.299762 -68.625897) (xy 44.251936 -68.599784) (xy 44.208312 -68.567129) (xy 44.169781 -68.528599)
			(xy 44.137125 -68.484977) (xy 44.111009 -68.437152) (xy 44.091966 -68.386097) (xy 44.080383 -68.332851)
			(xy 44.076496 -68.278499) (xy 24.795988 -68.278499) (xy 24.795988 -69.706506) (xy 56.651962 -69.706506)
			(xy 56.65585 -69.652147) (xy 56.667434 -69.598894) (xy 56.686479 -69.547833) (xy 56.712598 -69.500002)
			(xy 56.745259 -69.456375) (xy 56.783796 -69.41784) (xy 56.827426 -69.385183) (xy 56.875259 -69.359067)
			(xy 56.926322 -69.340026) (xy 56.979575 -69.328445) (xy 57.033935 -69.324562) (xy 57.088293 -69.328455)
			(xy 57.141545 -69.340045) (xy 57.192604 -69.359096) (xy 57.240433 -69.38522) (xy 57.262522 -69.401182)
			(xy 57.281534 -69.414778) (xy 57.323417 -69.43551) (xy 57.368385 -69.448236) (xy 57.414922 -69.452526)
			(xy 57.461459 -69.448236) (xy 57.506427 -69.43551) (xy 57.54831 -69.414778) (xy 57.567322 -69.401182)
			(xy 57.589419 -69.385237) (xy 57.637242 -69.359122) (xy 57.688296 -69.340078) (xy 57.74154 -69.328493)
			(xy 57.79589 -69.324605) (xy 57.850241 -69.328491) (xy 57.903486 -69.340072) (xy 57.95454 -69.359114)
			(xy 58.002365 -69.385227) (xy 58.045986 -69.417881) (xy 58.084517 -69.456411) (xy 58.117171 -69.500032)
			(xy 58.143285 -69.547857) (xy 58.162327 -69.598911) (xy 58.173909 -69.652155) (xy 58.177795 -69.706506)
			(xy 58.893097 -69.706506) (xy 58.896984 -69.652155) (xy 58.908565 -69.59891) (xy 58.927607 -69.547855)
			(xy 58.953721 -69.50003) (xy 58.986375 -69.456409) (xy 59.024905 -69.417878) (xy 59.068527 -69.385223)
			(xy 59.116351 -69.359109) (xy 59.167406 -69.340067) (xy 59.22065 -69.328484) (xy 59.275002 -69.324597)
			(xy 59.329353 -69.328485) (xy 59.382597 -69.340068) (xy 59.433652 -69.35911) (xy 59.481476 -69.385225)
			(xy 59.503564 -69.401182) (xy 59.522576 -69.414778) (xy 59.564459 -69.43551) (xy 59.609427 -69.448236)
			(xy 59.655964 -69.452526) (xy 59.702501 -69.448236) (xy 59.747469 -69.43551) (xy 59.789352 -69.414778)
			(xy 59.808364 -69.401182) (xy 59.830462 -69.385232) (xy 59.87829 -69.359107) (xy 59.929349 -69.340055)
			(xy 59.982599 -69.328464) (xy 60.036957 -69.32457) (xy 60.091317 -69.328452) (xy 60.14457 -69.340031)
			(xy 60.195633 -69.359072) (xy 60.243466 -69.385187) (xy 60.287096 -69.417843) (xy 60.325633 -69.456377)
			(xy 60.358294 -69.500003) (xy 60.384413 -69.547834) (xy 60.403458 -69.598895) (xy 60.415043 -69.652147)
			(xy 60.41893 -69.706506) (xy 60.796947 -69.706506) (xy 60.800834 -69.652143) (xy 60.81242 -69.598887)
			(xy 60.831467 -69.547823) (xy 60.857588 -69.499989) (xy 60.890252 -69.456359) (xy 60.928792 -69.417823)
			(xy 60.972425 -69.385165) (xy 61.020262 -69.359049) (xy 61.071329 -69.340007) (xy 61.124586 -69.328428)
			(xy 61.178949 -69.324547) (xy 61.233311 -69.328442) (xy 61.286566 -69.340035) (xy 61.337628 -69.35909)
			(xy 61.385458 -69.385218) (xy 61.407548 -69.401182) (xy 61.42656 -69.414778) (xy 61.468443 -69.43551)
			(xy 61.513411 -69.448236) (xy 61.559948 -69.452526) (xy 61.606485 -69.448236) (xy 61.651453 -69.43551)
			(xy 61.693336 -69.414778) (xy 61.712348 -69.401182) (xy 61.734444 -69.38524) (xy 61.782266 -69.359128)
			(xy 61.833317 -69.340088) (xy 61.886558 -69.328506) (xy 61.940905 -69.32462) (xy 61.995252 -69.328508)
			(xy 62.048493 -69.340091) (xy 62.099544 -69.359132) (xy 62.147364 -69.385245) (xy 62.190982 -69.417898)
			(xy 62.229509 -69.456426) (xy 62.262161 -69.500045) (xy 62.288272 -69.547867) (xy 62.307313 -69.598918)
			(xy 62.318894 -69.652159) (xy 62.32278 -69.706506) (xy 62.318892 -69.760853) (xy 62.307309 -69.814094)
			(xy 62.288267 -69.865144) (xy 62.262154 -69.912965) (xy 62.229501 -69.956583) (xy 62.190973 -69.99511)
			(xy 62.147354 -70.027761) (xy 62.099533 -70.053873) (xy 62.048482 -70.072913) (xy 61.995241 -70.084494)
			(xy 61.940893 -70.08838) (xy 61.886546 -70.084492) (xy 61.833305 -70.072909) (xy 61.782255 -70.053867)
			(xy 61.734434 -70.027754) (xy 61.712348 -70.011798) (xy 61.693336 -69.998202) (xy 61.651453 -69.97747)
			(xy 61.606485 -69.964744) (xy 61.559948 -69.960454) (xy 61.513411 -69.964744) (xy 61.468443 -69.97747)
			(xy 61.42656 -69.998202) (xy 61.407548 -70.011798) (xy 61.385468 -70.027776) (xy 61.337639 -70.053905)
			(xy 61.286577 -70.072961) (xy 61.233323 -70.084556) (xy 61.178961 -70.088453) (xy 61.124598 -70.084574)
			(xy 61.071341 -70.072996) (xy 61.020273 -70.053956) (xy 60.972435 -70.027842) (xy 60.928801 -69.995185)
			(xy 60.890259 -69.95665) (xy 60.857595 -69.913022) (xy 60.831472 -69.865188) (xy 60.812423 -69.814124)
			(xy 60.800836 -69.760869) (xy 60.796947 -69.706506) (xy 60.41893 -69.706506) (xy 60.415041 -69.760865)
			(xy 60.403455 -69.814116) (xy 60.384408 -69.865177) (xy 60.358287 -69.913007) (xy 60.325625 -69.956632)
			(xy 60.287086 -69.995165) (xy 60.243456 -70.02782) (xy 60.195622 -70.053933) (xy 60.144558 -70.072972)
			(xy 60.091305 -70.08455) (xy 60.036945 -70.08843) (xy 59.982587 -70.084534) (xy 59.929337 -70.072941)
			(xy 59.878279 -70.053888) (xy 59.830452 -70.027761) (xy 59.808364 -70.011798) (xy 59.789352 -69.998202)
			(xy 59.747469 -69.97747) (xy 59.702501 -69.964744) (xy 59.655964 -69.960454) (xy 59.609427 -69.964744)
			(xy 59.564459 -69.97747) (xy 59.522576 -69.998202) (xy 59.503564 -70.011798) (xy 59.481486 -70.027768)
			(xy 59.433662 -70.053885) (xy 59.382609 -70.072929) (xy 59.329365 -70.084514) (xy 59.275014 -70.088403)
			(xy 59.220662 -70.084518) (xy 59.167417 -70.072937) (xy 59.116362 -70.053896) (xy 59.068537 -70.027783)
			(xy 59.024914 -69.99513) (xy 58.986383 -69.9566) (xy 58.953728 -69.91298) (xy 58.927612 -69.865156)
			(xy 58.908569 -69.814102) (xy 58.896985 -69.760857) (xy 58.893097 -69.706506) (xy 58.177795 -69.706506)
			(xy 58.173907 -69.760857) (xy 58.162323 -69.814101) (xy 58.14328 -69.865154) (xy 58.117164 -69.912978)
			(xy 58.084509 -69.956598) (xy 58.045977 -69.995127) (xy 58.002355 -70.027779) (xy 57.954529 -70.053891)
			(xy 57.903474 -70.072931) (xy 57.850229 -70.084511) (xy 57.795878 -70.088395) (xy 57.741528 -70.084505)
			(xy 57.688284 -70.072919) (xy 57.637232 -70.053874) (xy 57.589409 -70.027756) (xy 57.567322 -70.011798)
			(xy 57.54831 -69.998202) (xy 57.506427 -69.97747) (xy 57.461459 -69.964744) (xy 57.414922 -69.960454)
			(xy 57.368385 -69.964744) (xy 57.323417 -69.97747) (xy 57.281534 -69.998202) (xy 57.262522 -70.011798)
			(xy 57.240443 -70.027773) (xy 57.192615 -70.053899) (xy 57.141556 -70.072951) (xy 57.088305 -70.084543)
			(xy 57.033947 -70.088438) (xy 56.979587 -70.084556) (xy 56.926333 -70.072978) (xy 56.87527 -70.053938)
			(xy 56.827436 -70.027824) (xy 56.783805 -69.995168) (xy 56.745267 -69.956634) (xy 56.712605 -69.913009)
			(xy 56.686484 -69.865178) (xy 56.667437 -69.814117) (xy 56.655851 -69.760865) (xy 56.651962 -69.706506)
			(xy 24.795988 -69.706506) (xy 24.795988 -70.179377) (xy 44.076525 -70.179377) (xy 44.080415 -70.125029)
			(xy 44.092001 -70.071788) (xy 44.111045 -70.020738) (xy 44.137162 -69.972918) (xy 44.169818 -69.929302)
			(xy 44.208349 -69.890777) (xy 44.251971 -69.858128) (xy 44.299796 -69.832019) (xy 44.350849 -69.812983)
			(xy 44.404092 -69.801406) (xy 44.458441 -69.797525) (xy 44.512788 -69.801418) (xy 44.566029 -69.813006)
			(xy 44.617078 -69.832053) (xy 44.664897 -69.858171) (xy 44.686982 -69.87413) (xy 44.705994 -69.887726)
			(xy 44.747877 -69.908458) (xy 44.792845 -69.921184) (xy 44.839382 -69.925474) (xy 44.885919 -69.921184)
			(xy 44.930887 -69.908458) (xy 44.97277 -69.887726) (xy 44.991782 -69.87413) (xy 45.013835 -69.858117)
			(xy 45.061664 -69.831989) (xy 45.112725 -69.812933) (xy 45.165978 -69.801339) (xy 45.220339 -69.797442)
			(xy 45.274701 -69.801322) (xy 45.327958 -69.812899) (xy 45.379025 -69.831938) (xy 45.426862 -69.858051)
			(xy 45.470496 -69.890707) (xy 45.509038 -69.92924) (xy 45.541703 -69.972867) (xy 45.567827 -70.020699)
			(xy 45.586877 -70.071762) (xy 45.598466 -70.125016) (xy 45.602358 -70.179377) (xy 45.598473 -70.233739)
			(xy 45.58689 -70.286995) (xy 45.567846 -70.33806) (xy 45.541728 -70.385894) (xy 45.509068 -70.429525)
			(xy 45.470531 -70.468063) (xy 45.426901 -70.500724) (xy 45.379066 -70.526843) (xy 45.328002 -70.545888)
			(xy 45.274746 -70.557472) (xy 45.220385 -70.561358) (xy 45.166023 -70.557467) (xy 45.112769 -70.545879)
			(xy 45.061705 -70.52683) (xy 45.013873 -70.500707) (xy 44.991782 -70.484746) (xy 44.97277 -70.47115)
			(xy 44.930887 -70.450418) (xy 44.885919 -70.437692) (xy 44.839382 -70.433402) (xy 44.792845 -70.437692)
			(xy 44.747877 -70.450418) (xy 44.705994 -70.47115) (xy 44.686982 -70.484746) (xy 44.664859 -70.500653)
			(xy 44.617037 -70.526766) (xy 44.565985 -70.545807) (xy 44.512743 -70.557389) (xy 44.458395 -70.561275)
			(xy 44.404047 -70.557387) (xy 44.350805 -70.545804) (xy 44.299754 -70.526762) (xy 44.251933 -70.500648)
			(xy 44.208315 -70.467994) (xy 44.169788 -70.429464) (xy 44.137137 -70.385844) (xy 44.111027 -70.33802)
			(xy 44.091988 -70.286968) (xy 44.080409 -70.233726) (xy 44.076525 -70.179377) (xy 24.795988 -70.179377)
			(xy 24.795988 -71.854619) (xy 44.076469 -71.854619) (xy 44.080354 -71.800263) (xy 44.091935 -71.747013)
			(xy 44.110977 -71.695953) (xy 44.137092 -71.648123) (xy 44.169748 -71.604497) (xy 44.208281 -71.565962)
			(xy 44.251906 -71.533303) (xy 44.299734 -71.507186) (xy 44.350793 -71.488141) (xy 44.404043 -71.476557)
			(xy 44.458399 -71.472669) (xy 44.512755 -71.476556) (xy 44.566004 -71.48814) (xy 44.617063 -71.507184)
			(xy 44.664892 -71.533302) (xy 44.686982 -71.54926) (xy 44.705994 -71.562856) (xy 44.747877 -71.583588)
			(xy 44.792845 -71.596314) (xy 44.839382 -71.600604) (xy 44.885919 -71.596314) (xy 44.930887 -71.583588)
			(xy 44.97277 -71.562856) (xy 44.991782 -71.54926) (xy 45.013901 -71.533342) (xy 45.061725 -71.507222)
			(xy 45.112781 -71.488175) (xy 45.166027 -71.476589) (xy 45.220381 -71.472698) (xy 45.274735 -71.476583)
			(xy 45.327983 -71.488165) (xy 45.37904 -71.507206) (xy 45.426867 -71.533321) (xy 45.470491 -71.565977)
			(xy 45.509023 -71.604509) (xy 45.541679 -71.648133) (xy 45.567794 -71.69596) (xy 45.586835 -71.747018)
			(xy 45.586957 -71.74758) (xy 56.651998 -71.74758) (xy 56.655888 -71.693226) (xy 56.667475 -71.639979)
			(xy 56.686522 -71.588923) (xy 56.712642 -71.541098) (xy 56.745303 -71.497478) (xy 56.783839 -71.45895)
			(xy 56.827467 -71.426298) (xy 56.875297 -71.400189) (xy 56.926357 -71.381152) (xy 56.979606 -71.369577)
			(xy 57.033961 -71.365698) (xy 57.088314 -71.369594) (xy 57.14156 -71.381186) (xy 57.192614 -71.400239)
			(xy 57.240436 -71.426364) (xy 57.262522 -71.442326) (xy 57.281534 -71.455922) (xy 57.323417 -71.476654)
			(xy 57.368385 -71.48938) (xy 57.414922 -71.49367) (xy 57.461459 -71.48938) (xy 57.506427 -71.476654)
			(xy 57.54831 -71.455922) (xy 57.567322 -71.442326) (xy 57.589378 -71.426322) (xy 57.637204 -71.4002)
			(xy 57.688261 -71.381151) (xy 57.741509 -71.369562) (xy 57.795864 -71.365669) (xy 57.85022 -71.369552)
			(xy 57.903471 -71.381131) (xy 57.954531 -71.400171) (xy 58.002362 -71.426283) (xy 58.045989 -71.458937)
			(xy 58.084526 -71.497468) (xy 58.117186 -71.541091) (xy 58.143306 -71.588918) (xy 58.162353 -71.639975)
			(xy 58.17394 -71.693224) (xy 58.177831 -71.74758) (xy 58.893132 -71.74758) (xy 58.897022 -71.693234)
			(xy 58.908607 -71.639995) (xy 58.92765 -71.588946) (xy 58.953765 -71.541127) (xy 58.986419 -71.497512)
			(xy 59.024948 -71.458988) (xy 59.068568 -71.426339) (xy 59.11639 -71.40023) (xy 59.167441 -71.381193)
			(xy 59.220682 -71.369615) (xy 59.275028 -71.365732) (xy 59.329374 -71.369623) (xy 59.382613 -71.381209)
			(xy 59.433661 -71.400253) (xy 59.481479 -71.426369) (xy 59.503564 -71.442326) (xy 59.522576 -71.455922)
			(xy 59.564459 -71.476654) (xy 59.609427 -71.48938) (xy 59.655964 -71.49367) (xy 59.702501 -71.48938)
			(xy 59.747469 -71.476654) (xy 59.789352 -71.455922) (xy 59.808364 -71.442326) (xy 59.830421 -71.426317)
			(xy 59.878251 -71.400186) (xy 59.929313 -71.381129) (xy 59.982568 -71.369533) (xy 60.036931 -71.365635)
			(xy 60.091295 -71.369513) (xy 60.144554 -71.38109) (xy 60.195623 -71.400129) (xy 60.243463 -71.426243)
			(xy 60.287099 -71.458899) (xy 60.325642 -71.497434) (xy 60.358309 -71.541062) (xy 60.384434 -71.588895)
			(xy 60.403485 -71.63996) (xy 60.415074 -71.693216) (xy 60.418965 -71.74758) (xy 60.796982 -71.74758)
			(xy 60.800873 -71.693222) (xy 60.812461 -71.639972) (xy 60.83151 -71.588913) (xy 60.857632 -71.541085)
			(xy 60.890295 -71.497462) (xy 60.928835 -71.458932) (xy 60.972466 -71.42628) (xy 61.020301 -71.40017)
			(xy 61.071364 -71.381134) (xy 61.124617 -71.369559) (xy 61.178976 -71.365682) (xy 61.233333 -71.369581)
			(xy 61.286581 -71.381176) (xy 61.337637 -71.400233) (xy 61.385461 -71.426362) (xy 61.407548 -71.442326)
			(xy 61.42656 -71.455922) (xy 61.468443 -71.476654) (xy 61.513411 -71.48938) (xy 61.559948 -71.49367)
			(xy 61.606485 -71.48938) (xy 61.651453 -71.476654) (xy 61.693336 -71.455922) (xy 61.712348 -71.442326)
			(xy 61.734403 -71.426324) (xy 61.782227 -71.400207) (xy 61.833282 -71.381161) (xy 61.886527 -71.369575)
			(xy 61.940879 -71.365685) (xy 61.995231 -71.369569) (xy 62.048478 -71.381149) (xy 62.099534 -71.400189)
			(xy 62.147361 -71.426301) (xy 62.190985 -71.458954) (xy 62.229518 -71.497483) (xy 62.262176 -71.541104)
			(xy 62.288294 -71.588928) (xy 62.307339 -71.639982) (xy 62.318925 -71.693228) (xy 62.322815 -71.74758)
			(xy 62.318931 -71.801932) (xy 62.30735 -71.855178) (xy 62.28831 -71.906235) (xy 62.262198 -71.954062)
			(xy 62.229545 -71.997686) (xy 62.191016 -72.036219) (xy 62.147396 -72.068877) (xy 62.099571 -72.094994)
			(xy 62.048517 -72.114039) (xy 61.995272 -72.125625) (xy 61.94092 -72.129515) (xy 61.886567 -72.12563)
			(xy 61.833321 -72.11405) (xy 61.782264 -72.09501) (xy 61.734437 -72.068898) (xy 61.712348 -72.052942)
			(xy 61.693336 -72.039346) (xy 61.651453 -72.018614) (xy 61.606485 -72.005888) (xy 61.559948 -72.001598)
			(xy 61.513411 -72.005888) (xy 61.468443 -72.018614) (xy 61.42656 -72.039346) (xy 61.407548 -72.052942)
			(xy 61.385427 -72.06886) (xy 61.3376 -72.094984) (xy 61.286542 -72.114035) (xy 61.233292 -72.125625)
			(xy 61.178935 -72.129518) (xy 61.124577 -72.125635) (xy 61.071325 -72.114055) (xy 61.020264 -72.095013)
			(xy 60.972432 -72.068898) (xy 60.928804 -72.036241) (xy 60.890269 -71.997707) (xy 60.85761 -71.95408)
			(xy 60.831493 -71.90625) (xy 60.812449 -71.855189) (xy 60.800867 -71.801937) (xy 60.796982 -71.74758)
			(xy 60.418965 -71.74758) (xy 60.41508 -71.801943) (xy 60.403496 -71.855201) (xy 60.384451 -71.906268)
			(xy 60.358331 -71.954104) (xy 60.325669 -71.997735) (xy 60.28713 -72.036274) (xy 60.243497 -72.068935)
			(xy 60.195661 -72.095054) (xy 60.144594 -72.114098) (xy 60.091336 -72.125681) (xy 60.036972 -72.129565)
			(xy 59.982608 -72.125673) (xy 59.929352 -72.114083) (xy 59.878288 -72.095031) (xy 59.830455 -72.068905)
			(xy 59.808364 -72.052942) (xy 59.789352 -72.039346) (xy 59.747469 -72.018614) (xy 59.702501 -72.005888)
			(xy 59.655964 -72.001598) (xy 59.609427 -72.005888) (xy 59.564459 -72.018614) (xy 59.522576 -72.039346)
			(xy 59.503564 -72.052942) (xy 59.481445 -72.068853) (xy 59.433624 -72.094964) (xy 59.382574 -72.114003)
			(xy 59.329333 -72.125583) (xy 59.274987 -72.129468) (xy 59.220641 -72.125579) (xy 59.167402 -72.113995)
			(xy 59.116353 -72.094953) (xy 59.068534 -72.068839) (xy 59.024918 -72.036186) (xy 58.986393 -71.997657)
			(xy 58.953743 -71.954038) (xy 58.927633 -71.906217) (xy 58.908595 -71.855166) (xy 58.897016 -71.801926)
			(xy 58.893132 -71.74758) (xy 58.177831 -71.74758) (xy 58.173946 -71.801936) (xy 58.162365 -71.855185)
			(xy 58.143323 -71.906245) (xy 58.117208 -71.954075) (xy 58.084553 -71.997701) (xy 58.04602 -72.036236)
			(xy 58.002396 -72.068895) (xy 57.954568 -72.095012) (xy 57.90351 -72.114058) (xy 57.850261 -72.125642)
			(xy 57.795905 -72.129531) (xy 57.741549 -72.125644) (xy 57.6883 -72.11406) (xy 57.637241 -72.095017)
			(xy 57.589412 -72.0689) (xy 57.567322 -72.052942) (xy 57.54831 -72.039346) (xy 57.506427 -72.018614)
			(xy 57.461459 -72.005888) (xy 57.414922 -72.001598) (xy 57.368385 -72.005888) (xy 57.323417 -72.018614)
			(xy 57.281534 -72.039346) (xy 57.262522 -72.052942) (xy 57.240401 -72.068858) (xy 57.192576 -72.094978)
			(xy 57.141521 -72.114025) (xy 57.088274 -72.125612) (xy 57.03392 -72.129502) (xy 56.979566 -72.125618)
			(xy 56.926318 -72.114036) (xy 56.87526 -72.094995) (xy 56.827432 -72.06888) (xy 56.783808 -72.036224)
			(xy 56.745276 -71.997691) (xy 56.71262 -71.954067) (xy 56.686505 -71.90624) (xy 56.667464 -71.855182)
			(xy 56.655882 -71.801934) (xy 56.651998 -71.74758) (xy 45.586957 -71.74758) (xy 45.598417 -71.800265)
			(xy 45.602302 -71.854619) (xy 45.598411 -71.908973) (xy 45.586825 -71.962219) (xy 45.567778 -72.013275)
			(xy 45.541658 -72.0611) (xy 45.508998 -72.10472) (xy 45.470462 -72.143248) (xy 45.426835 -72.1759)
			(xy 45.379005 -72.20201) (xy 45.327946 -72.221046) (xy 45.274697 -72.232622) (xy 45.220343 -72.236502)
			(xy 45.165989 -72.232606) (xy 45.112744 -72.221014) (xy 45.061691 -72.201962) (xy 45.013868 -72.175838)
			(xy 44.991782 -72.159876) (xy 44.97277 -72.14628) (xy 44.930887 -72.125548) (xy 44.885919 -72.112822)
			(xy 44.839382 -72.108532) (xy 44.792845 -72.112822) (xy 44.747877 -72.125548) (xy 44.705994 -72.14628)
			(xy 44.686982 -72.159876) (xy 44.664924 -72.175878) (xy 44.617098 -72.202) (xy 44.566041 -72.221049)
			(xy 44.512793 -72.232638) (xy 44.458437 -72.236531) (xy 44.404081 -72.232649) (xy 44.35083 -72.22107)
			(xy 44.299769 -72.20203) (xy 44.251938 -72.175918) (xy 44.20831 -72.143263) (xy 44.169773 -72.104732)
			(xy 44.137113 -72.061109) (xy 44.110993 -72.013282) (xy 44.091946 -71.962224) (xy 44.080359 -71.908975)
			(xy 44.076469 -71.854619) (xy 24.795988 -71.854619) (xy 24.795988 -73.865676) (xy 44.032987 -73.865676)
			(xy 44.036878 -73.811319) (xy 44.048466 -73.75807) (xy 44.067516 -73.707012) (xy 44.093638 -73.659185)
			(xy 44.126301 -73.615563) (xy 44.164841 -73.577034) (xy 44.208472 -73.544382) (xy 44.256306 -73.518273)
			(xy 44.307369 -73.499237) (xy 44.360622 -73.487663) (xy 44.414979 -73.483787) (xy 44.469335 -73.487686)
			(xy 44.522583 -73.499282) (xy 44.573638 -73.518339) (xy 44.621462 -73.544468) (xy 44.643548 -73.560432)
			(xy 44.66256 -73.574028) (xy 44.704443 -73.59476) (xy 44.749411 -73.607486) (xy 44.795948 -73.611776)
			(xy 44.842485 -73.607486) (xy 44.887453 -73.59476) (xy 44.929336 -73.574028) (xy 44.948348 -73.560432)
			(xy 44.970398 -73.544422) (xy 45.018222 -73.518304) (xy 45.069277 -73.499258) (xy 45.122523 -73.487671)
			(xy 45.176875 -73.48378) (xy 45.231228 -73.487664) (xy 45.284476 -73.499244) (xy 45.335533 -73.518283)
			(xy 45.383361 -73.544395) (xy 45.426986 -73.577048) (xy 45.46552 -73.615577) (xy 45.496925 -73.657524)
			(xy 56.651938 -73.657524) (xy 56.655823 -73.603161) (xy 56.667406 -73.549905) (xy 56.68645 -73.498839)
			(xy 56.712568 -73.451004) (xy 56.745229 -73.407372) (xy 56.783767 -73.368834) (xy 56.827397 -73.336172)
			(xy 56.875232 -73.310053) (xy 56.926298 -73.291008) (xy 56.979554 -73.279424) (xy 57.033917 -73.275538)
			(xy 57.088279 -73.279429) (xy 57.141534 -73.291017) (xy 57.192598 -73.310067) (xy 57.24043 -73.33619)
			(xy 57.262522 -73.352152) (xy 57.281534 -73.365748) (xy 57.323417 -73.38648) (xy 57.368385 -73.399206)
			(xy 57.414922 -73.403496) (xy 57.461459 -73.399206) (xy 57.506427 -73.38648) (xy 57.54831 -73.365748)
			(xy 57.567322 -73.352152) (xy 57.589447 -73.336248) (xy 57.637269 -73.310136) (xy 57.68832 -73.291096)
			(xy 57.741561 -73.279515) (xy 57.795908 -73.275629) (xy 57.850256 -73.279517) (xy 57.903496 -73.2911)
			(xy 57.954547 -73.310143) (xy 58.002367 -73.336257) (xy 58.045984 -73.368911) (xy 58.08451 -73.40744)
			(xy 58.117161 -73.45106) (xy 58.143271 -73.498883) (xy 58.162309 -73.549935) (xy 58.173888 -73.603176)
			(xy 58.177771 -73.657524) (xy 58.893073 -73.657524) (xy 58.896957 -73.603169) (xy 58.908537 -73.54992)
			(xy 58.927578 -73.498862) (xy 58.953691 -73.451033) (xy 58.986345 -73.407407) (xy 59.024876 -73.368872)
			(xy 59.068499 -73.336213) (xy 59.116325 -73.310095) (xy 59.167382 -73.291049) (xy 59.220629 -73.279463)
			(xy 59.274984 -73.275573) (xy 59.329338 -73.279458) (xy 59.382587 -73.29104) (xy 59.433645 -73.310081)
			(xy 59.481474 -73.336195) (xy 59.503564 -73.352152) (xy 59.522576 -73.365748) (xy 59.564459 -73.38648)
			(xy 59.609427 -73.399206) (xy 59.655964 -73.403496) (xy 59.702501 -73.399206) (xy 59.747469 -73.38648)
			(xy 59.789352 -73.365748) (xy 59.808364 -73.352152) (xy 59.830491 -73.336243) (xy 59.878316 -73.310122)
			(xy 59.929373 -73.291073) (xy 59.98262 -73.279485) (xy 60.036975 -73.275594) (xy 60.091331 -73.279478)
			(xy 60.14458 -73.291059) (xy 60.195639 -73.310101) (xy 60.243468 -73.336216) (xy 60.287093 -73.368873)
			(xy 60.325627 -73.407406) (xy 60.358283 -73.451031) (xy 60.384398 -73.49886) (xy 60.40344 -73.549919)
			(xy 60.415022 -73.603168) (xy 60.418906 -73.657524) (xy 60.796923 -73.657524) (xy 60.800808 -73.603158)
			(xy 60.812392 -73.549898) (xy 60.831438 -73.498829) (xy 60.857558 -73.450991) (xy 60.890222 -73.407357)
			(xy 60.928763 -73.368817) (xy 60.972397 -73.336154) (xy 61.020236 -73.310034) (xy 61.071305 -73.290989)
			(xy 61.124565 -73.279407) (xy 61.178931 -73.275523) (xy 61.233297 -73.279416) (xy 61.286555 -73.291007)
			(xy 61.337621 -73.310061) (xy 61.385456 -73.336188) (xy 61.407548 -73.352152) (xy 61.42656 -73.365748)
			(xy 61.468443 -73.38648) (xy 61.513411 -73.399206) (xy 61.559948 -73.403496) (xy 61.606485 -73.399206)
			(xy 61.651453 -73.38648) (xy 61.693336 -73.365748) (xy 61.712348 -73.352152) (xy 61.734473 -73.33625)
			(xy 61.782292 -73.310142) (xy 61.833341 -73.291106) (xy 61.886579 -73.279528) (xy 61.940923 -73.275644)
			(xy 61.995267 -73.279534) (xy 62.048504 -73.291119) (xy 62.09955 -73.310162) (xy 62.147367 -73.336275)
			(xy 62.19098 -73.368928) (xy 62.229503 -73.407456) (xy 62.26215 -73.451073) (xy 62.288258 -73.498893)
			(xy 62.307295 -73.549942) (xy 62.318872 -73.60318) (xy 62.322756 -73.657524) (xy 62.318866 -73.711868)
			(xy 62.307281 -73.765104) (xy 62.288238 -73.816151) (xy 62.262124 -73.863967) (xy 62.229471 -73.907581)
			(xy 62.190944 -73.946103) (xy 62.147326 -73.978751) (xy 62.099506 -74.004858) (xy 62.048458 -74.023895)
			(xy 61.995219 -74.035473) (xy 61.940875 -74.039356) (xy 61.886532 -74.035465) (xy 61.833295 -74.023881)
			(xy 61.782249 -74.004838) (xy 61.734432 -73.978724) (xy 61.712348 -73.962768) (xy 61.693336 -73.949172)
			(xy 61.651453 -73.92844) (xy 61.606485 -73.915714) (xy 61.559948 -73.911424) (xy 61.513411 -73.915714)
			(xy 61.468443 -73.92844) (xy 61.42656 -73.949172) (xy 61.407548 -73.962768) (xy 61.385496 -73.978786)
			(xy 61.337665 -74.00492) (xy 61.286601 -74.023979) (xy 61.233345 -74.035577) (xy 61.178979 -74.039477)
			(xy 61.124613 -74.0356) (xy 61.071351 -74.024024) (xy 61.020279 -74.004985) (xy 60.972437 -73.978872)
			(xy 60.928799 -73.946215) (xy 60.890253 -73.907679) (xy 60.857584 -73.86405) (xy 60.831457 -73.816215)
			(xy 60.812405 -73.765148) (xy 60.800815 -73.71189) (xy 60.796923 -73.657524) (xy 60.418906 -73.657524)
			(xy 60.415015 -73.711879) (xy 60.403427 -73.765127) (xy 60.384379 -73.816183) (xy 60.358257 -73.864009)
			(xy 60.325595 -73.90763) (xy 60.287057 -73.946158) (xy 60.243428 -73.97881) (xy 60.195596 -74.004919)
			(xy 60.144534 -74.023954) (xy 60.091283 -74.035529) (xy 60.036927 -74.039406) (xy 59.982573 -74.035508)
			(xy 59.929327 -74.023913) (xy 59.878272 -74.004858) (xy 59.83045 -73.978731) (xy 59.808364 -73.962768)
			(xy 59.789352 -73.949172) (xy 59.747469 -73.92844) (xy 59.702501 -73.915714) (xy 59.655964 -73.911424)
			(xy 59.609427 -73.915714) (xy 59.564459 -73.92844) (xy 59.522576 -73.949172) (xy 59.503564 -73.962768)
			(xy 59.481514 -73.978779) (xy 59.433689 -74.004899) (xy 59.382633 -74.023947) (xy 59.329386 -74.035535)
			(xy 59.275032 -74.039427) (xy 59.220677 -74.035544) (xy 59.167428 -74.023965) (xy 59.116369 -74.004925)
			(xy 59.068539 -73.978813) (xy 59.024912 -73.94616) (xy 58.986377 -73.90763) (xy 58.953717 -73.864008)
			(xy 58.927598 -73.816182) (xy 58.908551 -73.765126) (xy 58.896964 -73.711878) (xy 58.893073 -73.657524)
			(xy 58.177771 -73.657524) (xy 58.173881 -73.711871) (xy 58.162295 -73.765111) (xy 58.143251 -73.816161)
			(xy 58.117135 -73.86398) (xy 58.084479 -73.907596) (xy 58.045948 -73.94612) (xy 58.002327 -73.978769)
			(xy 57.954503 -74.004877) (xy 57.90345 -74.023913) (xy 57.850208 -74.03549) (xy 57.79586 -74.039371)
			(xy 57.741514 -74.035479) (xy 57.688274 -74.023891) (xy 57.637225 -74.004844) (xy 57.589407 -73.978726)
			(xy 57.567322 -73.962768) (xy 57.54831 -73.949172) (xy 57.506427 -73.92844) (xy 57.461459 -73.915714)
			(xy 57.414922 -73.911424) (xy 57.368385 -73.915714) (xy 57.323417 -73.92844) (xy 57.281534 -73.949172)
			(xy 57.262522 -73.962768) (xy 57.240471 -73.978784) (xy 57.192641 -74.004913) (xy 57.14158 -74.023969)
			(xy 57.088326 -74.035564) (xy 57.033965 -74.039462) (xy 56.979601 -74.035583) (xy 56.926344 -74.024006)
			(xy 56.875276 -74.004967) (xy 56.827438 -73.978854) (xy 56.783803 -73.946198) (xy 56.74526 -73.907664)
			(xy 56.712594 -73.864037) (xy 56.68647 -73.816205) (xy 56.667419 -73.765141) (xy 56.65583 -73.711886)
			(xy 56.651938 -73.657524) (xy 45.496925 -73.657524) (xy 45.498178 -73.659198) (xy 45.524296 -73.707023)
			(xy 45.543343 -73.758078) (xy 45.554929 -73.811323) (xy 45.55882 -73.865676) (xy 45.554936 -73.920029)
			(xy 45.543356 -73.973276) (xy 45.524316 -74.024334) (xy 45.498204 -74.072161) (xy 45.465551 -74.115786)
			(xy 45.427022 -74.15432) (xy 45.383401 -74.186979) (xy 45.335577 -74.213097) (xy 45.284522 -74.232143)
			(xy 45.231276 -74.243729) (xy 45.176923 -74.24762) (xy 45.12257 -74.243736) (xy 45.069323 -74.232156)
			(xy 45.018266 -74.213116) (xy 44.970438 -74.187004) (xy 44.948348 -74.171048) (xy 44.929336 -74.157452)
			(xy 44.887453 -74.13672) (xy 44.842485 -74.123994) (xy 44.795948 -74.119704) (xy 44.749411 -74.123994)
			(xy 44.704443 -74.13672) (xy 44.66256 -74.157452) (xy 44.643548 -74.171048) (xy 44.621421 -74.186958)
			(xy 44.573595 -74.213081) (xy 44.522537 -74.232131) (xy 44.469288 -74.243721) (xy 44.414931 -74.247613)
			(xy 44.360574 -74.24373) (xy 44.307323 -74.232149) (xy 44.256262 -74.213107) (xy 44.208432 -74.186992)
			(xy 44.164805 -74.154335) (xy 44.12627 -74.115801) (xy 44.093612 -74.072175) (xy 44.067496 -74.024344)
			(xy 44.048453 -73.973284) (xy 44.036871 -73.920033) (xy 44.032987 -73.865676) (xy 24.795988 -73.865676)
			(xy 24.795988 -75.756323) (xy 44.032924 -75.756323) (xy 44.03681 -75.701957) (xy 44.048393 -75.648697)
			(xy 44.067439 -75.597629) (xy 44.09356 -75.549791) (xy 44.126224 -75.506157) (xy 44.164765 -75.467617)
			(xy 44.208399 -75.434955) (xy 44.256237 -75.408835) (xy 44.307307 -75.389791) (xy 44.360566 -75.378208)
			(xy 44.414933 -75.374324) (xy 44.469298 -75.378218) (xy 44.522556 -75.389809) (xy 44.573622 -75.408862)
			(xy 44.621456 -75.43499) (xy 44.643548 -75.450954) (xy 44.66256 -75.46455) (xy 44.704443 -75.485282)
			(xy 44.749411 -75.498008) (xy 44.795948 -75.502298) (xy 44.842485 -75.498008) (xy 44.887453 -75.485282)
			(xy 44.929336 -75.46455) (xy 44.948348 -75.450954) (xy 44.970471 -75.435049) (xy 45.018291 -75.408941)
			(xy 45.069339 -75.389904) (xy 45.122578 -75.378326) (xy 45.176922 -75.374443) (xy 45.231266 -75.378333)
			(xy 45.284503 -75.389917) (xy 45.33555 -75.40896) (xy 45.383366 -75.435073) (xy 45.42698 -75.467726)
			(xy 45.465503 -75.506254) (xy 45.498151 -75.549871) (xy 45.524259 -75.597691) (xy 45.543296 -75.64874)
			(xy 45.554874 -75.701979) (xy 45.558757 -75.756323) (xy 45.554867 -75.810667) (xy 45.543283 -75.863904)
			(xy 45.52424 -75.91495) (xy 45.498126 -75.962767) (xy 45.465473 -76.006381) (xy 45.426946 -76.044904)
			(xy 45.383328 -76.077551) (xy 45.335508 -76.103659) (xy 45.284459 -76.122696) (xy 45.231221 -76.134274)
			(xy 45.176876 -76.138157) (xy 45.122533 -76.134267) (xy 45.069296 -76.122683) (xy 45.018249 -76.10364)
			(xy 44.970432 -76.077526) (xy 44.948348 -76.06157) (xy 44.929336 -76.047974) (xy 44.887453 -76.027242)
			(xy 44.842485 -76.014516) (xy 44.795948 -76.010226) (xy 44.749411 -76.014516) (xy 44.704443 -76.027242)
			(xy 44.66256 -76.047974) (xy 44.643548 -76.06157) (xy 44.621494 -76.077585) (xy 44.573663 -76.103719)
			(xy 44.5226 -76.122778) (xy 44.469343 -76.134376) (xy 44.414978 -76.138276) (xy 44.360612 -76.134398)
			(xy 44.30735 -76.122822) (xy 44.256279 -76.103784) (xy 44.208437 -76.07767) (xy 44.164799 -76.045013)
			(xy 44.126253 -76.006477) (xy 44.093585 -75.962848) (xy 44.067458 -75.915013) (xy 44.048406 -75.863947)
			(xy 44.036816 -75.810688) (xy 44.032924 -75.756323) (xy 24.795988 -75.756323) (xy 24.795988 -77.797396)
			(xy 44.03296 -77.797396) (xy 44.036848 -77.743036) (xy 44.048435 -77.689782) (xy 44.067482 -77.638719)
			(xy 44.093604 -77.590887) (xy 44.126267 -77.54726) (xy 44.164808 -77.508727) (xy 44.20844 -77.47607)
			(xy 44.256276 -77.449956) (xy 44.307342 -77.430917) (xy 44.360598 -77.419339) (xy 44.414959 -77.41546)
			(xy 44.469319 -77.419356) (xy 44.522571 -77.43095) (xy 44.573631 -77.450005) (xy 44.621459 -77.476134)
			(xy 44.643548 -77.492098) (xy 44.66256 -77.505694) (xy 44.704443 -77.526426) (xy 44.749411 -77.539152)
			(xy 44.795948 -77.543442) (xy 44.842485 -77.539152) (xy 44.887453 -77.526426) (xy 44.929336 -77.505694)
			(xy 44.948348 -77.492098) (xy 44.970429 -77.476134) (xy 45.018252 -77.45002) (xy 45.069304 -77.430978)
			(xy 45.122547 -77.419395) (xy 45.176896 -77.415507) (xy 45.231245 -77.419394) (xy 45.284488 -77.430976)
			(xy 45.33554 -77.450017) (xy 45.383363 -77.476129) (xy 45.426983 -77.508782) (xy 45.465513 -77.547311)
			(xy 45.498166 -77.59093) (xy 45.52428 -77.638753) (xy 45.543322 -77.689805) (xy 45.554905 -77.743047)
			(xy 45.558793 -77.797396) (xy 45.554906 -77.851745) (xy 45.543324 -77.904988) (xy 45.524283 -77.956041)
			(xy 45.49817 -78.003864) (xy 45.465517 -78.047484) (xy 45.426989 -78.086013) (xy 45.383369 -78.118667)
			(xy 45.335547 -78.14478) (xy 45.284494 -78.163822) (xy 45.231252 -78.175405) (xy 45.176903 -78.179293)
			(xy 45.122554 -78.175406) (xy 45.069311 -78.163824) (xy 45.018259 -78.144783) (xy 44.970435 -78.11867)
			(xy 44.948348 -78.102714) (xy 44.929336 -78.089118) (xy 44.887453 -78.068386) (xy 44.842485 -78.05566)
			(xy 44.795948 -78.05137) (xy 44.749411 -78.05566) (xy 44.704443 -78.068386) (xy 44.66256 -78.089118)
			(xy 44.643548 -78.102714) (xy 44.621453 -78.11867) (xy 44.573625 -78.144798) (xy 44.522564 -78.163852)
			(xy 44.469312 -78.175445) (xy 44.414952 -78.17934) (xy 44.36059 -78.17546) (xy 44.307335 -78.163881)
			(xy 44.25627 -78.144841) (xy 44.208434 -78.118726) (xy 44.164802 -78.086069) (xy 44.126263 -78.047534)
			(xy 44.0936 -78.003907) (xy 44.067479 -77.956074) (xy 44.048433 -77.905011) (xy 44.036847 -77.851757)
			(xy 44.03296 -77.797396) (xy 24.795988 -77.797396) (xy 24.795988 -79.707181) (xy 44.03298 -79.707181)
			(xy 44.036871 -79.652823) (xy 44.048459 -79.599573) (xy 44.067508 -79.548514) (xy 44.09363 -79.500686)
			(xy 44.126293 -79.457062) (xy 44.164833 -79.418532) (xy 44.208464 -79.385879) (xy 44.256299 -79.359769)
			(xy 44.307363 -79.340733) (xy 44.360616 -79.329158) (xy 44.414975 -79.32528) (xy 44.469332 -79.329179)
			(xy 44.52258 -79.340775) (xy 44.573637 -79.359831) (xy 44.621461 -79.38596) (xy 44.643548 -79.401924)
			(xy 44.66256 -79.41552) (xy 44.704443 -79.436252) (xy 44.749411 -79.448978) (xy 44.795948 -79.453268)
			(xy 44.842485 -79.448978) (xy 44.887453 -79.436252) (xy 44.929336 -79.41552) (xy 44.948348 -79.401924)
			(xy 44.970405 -79.385925) (xy 45.018229 -79.359808) (xy 45.069283 -79.340762) (xy 45.122528 -79.329177)
			(xy 45.17688 -79.325287) (xy 45.231232 -79.329171) (xy 45.284478 -79.340751) (xy 45.335535 -79.359791)
			(xy 45.383361 -79.385903) (xy 45.426985 -79.418556) (xy 45.465518 -79.457085) (xy 45.498175 -79.500706)
			(xy 45.524293 -79.54853) (xy 45.543338 -79.599584) (xy 45.554923 -79.652829) (xy 45.558813 -79.707181)
			(xy 45.554929 -79.761533) (xy 45.543349 -79.814779) (xy 45.524309 -79.865835) (xy 45.498196 -79.913662)
			(xy 45.465543 -79.957286) (xy 45.427014 -79.995819) (xy 45.383394 -80.028476) (xy 45.33557 -80.054593)
			(xy 45.284515 -80.073638) (xy 45.23127 -80.085223) (xy 45.176918 -80.089113) (xy 45.122566 -80.085229)
			(xy 45.06932 -80.073648) (xy 45.018264 -80.054608) (xy 44.970437 -80.028496) (xy 44.948348 -80.01254)
			(xy 44.929336 -79.998944) (xy 44.887453 -79.978212) (xy 44.842485 -79.965486) (xy 44.795948 -79.961196)
			(xy 44.749411 -79.965486) (xy 44.704443 -79.978212) (xy 44.66256 -79.998944) (xy 44.643548 -80.01254)
			(xy 44.621429 -80.028461) (xy 44.573602 -80.054585) (xy 44.522544 -80.073636) (xy 44.469294 -80.085226)
			(xy 44.414936 -80.08912) (xy 44.360578 -80.085237) (xy 44.307326 -80.073657) (xy 44.256264 -80.054615)
			(xy 44.208432 -80.0285) (xy 44.164804 -79.995843) (xy 44.126268 -79.957309) (xy 44.093609 -79.913682)
			(xy 44.067492 -79.865851) (xy 44.048448 -79.81479) (xy 44.036866 -79.761539) (xy 44.03298 -79.707181)
			(xy 24.795988 -79.707181) (xy 24.795988 -84.314199) (xy 47.642008 -84.314199) (xy 47.642008 -84.233089)
			(xy 47.649958 -84.15237) (xy 47.665781 -84.072819) (xy 47.689326 -83.995203) (xy 47.720365 -83.920267)
			(xy 47.7586 -83.848735) (xy 47.803662 -83.781295) (xy 47.855117 -83.718596) (xy 47.91247 -83.661243)
			(xy 47.975169 -83.609788) (xy 48.042609 -83.564726) (xy 48.114141 -83.526491) (xy 48.189077 -83.495452)
			(xy 48.266693 -83.471907) (xy 48.346244 -83.456084) (xy 48.426963 -83.448134) (xy 48.508073 -83.448134)
			(xy 48.588792 -83.456084) (xy 48.668343 -83.471907) (xy 48.745959 -83.495452) (xy 48.820895 -83.526491)
			(xy 48.892427 -83.564726) (xy 48.959867 -83.609788) (xy 49.022566 -83.661243) (xy 49.079919 -83.718596)
			(xy 49.131374 -83.781295) (xy 49.176436 -83.848735) (xy 49.214671 -83.920267) (xy 49.24571 -83.995203)
			(xy 49.269255 -84.072819) (xy 49.285078 -84.15237) (xy 49.293028 -84.233089) (xy 49.293526 -84.273644)
			(xy 49.293028 -84.314199) (xy 51.142128 -84.314199) (xy 51.142128 -84.233089) (xy 51.150078 -84.15237)
			(xy 51.165901 -84.072819) (xy 51.189446 -83.995203) (xy 51.220485 -83.920267) (xy 51.25872 -83.848735)
			(xy 51.303782 -83.781295) (xy 51.355237 -83.718596) (xy 51.41259 -83.661243) (xy 51.475289 -83.609788)
			(xy 51.542729 -83.564726) (xy 51.614261 -83.526491) (xy 51.689197 -83.495452) (xy 51.766813 -83.471907)
			(xy 51.846364 -83.456084) (xy 51.927083 -83.448134) (xy 52.008193 -83.448134) (xy 52.088912 -83.456084)
			(xy 52.168463 -83.471907) (xy 52.246079 -83.495452) (xy 52.321015 -83.526491) (xy 52.392547 -83.564726)
			(xy 52.459987 -83.609788) (xy 52.522686 -83.661243) (xy 52.580039 -83.718596) (xy 52.631494 -83.781295)
			(xy 52.676556 -83.848735) (xy 52.714791 -83.920267) (xy 52.74583 -83.995203) (xy 52.769375 -84.072819)
			(xy 52.785198 -84.15237) (xy 52.793148 -84.233089) (xy 52.793646 -84.273644) (xy 52.793148 -84.314199)
			(xy 52.785198 -84.394918) (xy 52.769375 -84.474469) (xy 52.74583 -84.552085) (xy 52.714791 -84.627021)
			(xy 52.676556 -84.698553) (xy 52.631494 -84.765993) (xy 52.580039 -84.828692) (xy 52.522686 -84.886045)
			(xy 52.459987 -84.9375) (xy 52.392547 -84.982562) (xy 52.321015 -85.020797) (xy 52.246079 -85.051836)
			(xy 52.168463 -85.075381) (xy 52.088912 -85.091204) (xy 52.008193 -85.099154) (xy 51.927083 -85.099154)
			(xy 51.846364 -85.091204) (xy 51.766813 -85.075381) (xy 51.689197 -85.051836) (xy 51.614261 -85.020797)
			(xy 51.542729 -84.982562) (xy 51.475289 -84.9375) (xy 51.41259 -84.886045) (xy 51.355237 -84.828692)
			(xy 51.303782 -84.765993) (xy 51.25872 -84.698553) (xy 51.220485 -84.627021) (xy 51.189446 -84.552085)
			(xy 51.165901 -84.474469) (xy 51.150078 -84.394918) (xy 51.142128 -84.314199) (xy 49.293028 -84.314199)
			(xy 49.285078 -84.394918) (xy 49.269255 -84.474469) (xy 49.24571 -84.552085) (xy 49.214671 -84.627021)
			(xy 49.176436 -84.698553) (xy 49.131374 -84.765993) (xy 49.079919 -84.828692) (xy 49.022566 -84.886045)
			(xy 48.959867 -84.9375) (xy 48.892427 -84.982562) (xy 48.820895 -85.020797) (xy 48.745959 -85.051836)
			(xy 48.668343 -85.075381) (xy 48.588792 -85.091204) (xy 48.508073 -85.099154) (xy 48.426963 -85.099154)
			(xy 48.346244 -85.091204) (xy 48.266693 -85.075381) (xy 48.189077 -85.051836) (xy 48.114141 -85.020797)
			(xy 48.042609 -84.982562) (xy 47.975169 -84.9375) (xy 47.91247 -84.886045) (xy 47.855117 -84.828692)
			(xy 47.803662 -84.765993) (xy 47.7586 -84.698553) (xy 47.720365 -84.627021) (xy 47.689326 -84.552085)
			(xy 47.665781 -84.474469) (xy 47.649958 -84.394918) (xy 47.642008 -84.314199) (xy 24.795988 -84.314199)
			(xy 24.795988 -88.800178) (xy 24.809845 -88.817592) (xy 24.842583 -88.847731) (xy 24.880078 -88.871695)
			(xy 24.921179 -88.888748) (xy 24.964626 -88.898367) (xy 25.009085 -88.900257) (xy 25.031192 -88.897714)
			(xy 28.06954 -85.859112) (xy 52.342034 -85.859112) (xy 74.11974 -64.081406) (xy 74.11974 -59.779916)
			(xy 80.29829 -53.601112) (xy 81.820766 -53.601112) (xy 82.808064 -52.613814) (xy 82.808064 -49.591722)
			(xy 83.7692 -48.63084) (xy 83.780552 -48.618693) (xy 83.797148 -48.589898) (xy 83.805747 -48.557795)
			(xy 83.806284 -48.541178) (xy 83.806284 -13.151612) (xy 83.80349 -13.138404) (xy 83.798167 -13.111519)
			(xy 83.794384 -13.056844) (xy 83.79847 -13.002191) (xy 83.81034 -12.948686) (xy 83.82975 -12.897433)
			(xy 83.842606 -12.873228) (xy 83.858608 -12.844526) (xy 83.858608 -5.65277) (xy 85.974174 -3.537204)
			(xy 90.97137 -3.537204) (xy 91.335098 -3.900678) (xy 91.711018 -4.276598) (xy 91.721399 -4.286474)
			(xy 91.745642 -4.301736) (xy 91.772675 -4.311217) (xy 91.801141 -4.31444) (xy 91.815412 -4.313174)
			(xy 91.82989 -4.311396) (xy 91.83624 -4.309872) (xy 91.873017 -4.302257) (xy 91.947657 -4.293889)
			(xy 92.022763 -4.293425) (xy 92.097501 -4.300871) (xy 92.171039 -4.316144) (xy 92.242561 -4.339074)
			(xy 92.311272 -4.369405) (xy 92.376408 -4.406802) (xy 92.437244 -4.450848) (xy 92.493106 -4.501054)
			(xy 92.543372 -4.556862) (xy 92.587483 -4.617651) (xy 92.62495 -4.682747) (xy 92.655355 -4.751425)
			(xy 92.678361 -4.822922) (xy 92.693713 -4.896445) (xy 92.701239 -4.971174) (xy 92.700856 -5.046281)
			(xy 92.692568 -5.12093) (xy 92.676468 -5.194292) (xy 92.652733 -5.265551) (xy 92.621629 -5.333915)
			(xy 92.583501 -5.398625) (xy 92.538772 -5.458962) (xy 92.48794 -5.514254) (xy 92.431569 -5.563888)
			(xy 92.370286 -5.607311) (xy 92.304773 -5.644042) (xy 92.235756 -5.673671) (xy 92.164004 -5.69587)
			(xy 92.090314 -5.710392) (xy 92.015504 -5.717076) (xy 91.940406 -5.715846) (xy 91.865856 -5.706718)
			(xy 91.79268 -5.689792) (xy 91.721693 -5.665256) (xy 91.653683 -5.633384) (xy 91.589407 -5.594529)
			(xy 91.529578 -5.549123) (xy 91.474862 -5.49767) (xy 91.425867 -5.440744) (xy 91.383137 -5.378976)
			(xy 91.347147 -5.313052) (xy 91.318297 -5.243707) (xy 91.296908 -5.171709) (xy 91.289632 -5.134864)
			(xy 91.286548 -5.12047) (xy 91.274708 -5.093528) (xy 91.257001 -5.070022) (xy 91.234372 -5.051208)
			(xy 91.208029 -5.038089) (xy 91.179379 -5.031365) (xy 91.164664 -5.030978) (xy 91.148018 -5.031525)
			(xy 91.115861 -5.040149) (xy 91.087031 -5.056799) (xy 91.063491 -5.080342) (xy 91.046844 -5.109174)
			(xy 91.038224 -5.141332) (xy 91.037664 -5.157978) (xy 91.037664 -5.564124) (xy 91.038138 -5.580218)
			(xy 91.0462 -5.611381) (xy 91.061805 -5.639534) (xy 91.083959 -5.662885) (xy 91.097354 -5.67182)
			(xy 91.130952 -5.693511) (xy 91.19357 -5.743263) (xy 91.250229 -5.799707) (xy 91.275662 -5.83057)
			(xy 91.280996 -5.837174) (xy 91.303656 -5.866953) (xy 91.343278 -5.930438) (xy 91.376004 -5.997737)
			(xy 91.3892 -6.032754) (xy 91.401351 -6.067745) (xy 91.419169 -6.139647) (xy 91.42476 -6.176264)
			(xy 91.429212 -6.211061) (xy 91.432069 -6.28116) (xy 91.42802 -6.3512) (xy 91.417103 -6.420502) (xy 91.399424 -6.488395)
			(xy 91.387676 -6.52145) (xy 91.374526 -6.55585) (xy 91.342096 -6.621973) (xy 91.303008 -6.684393)
			(xy 91.257682 -6.742441) (xy 91.206601 -6.795497) (xy 91.150314 -6.842992) (xy 91.089421 -6.884419)
			(xy 91.024575 -6.919334) (xy 90.956469 -6.947364) (xy 90.885832 -6.968209) (xy 90.849704 -6.975348)
			(xy 90.835311 -6.978429) (xy 90.80837 -6.990267) (xy 90.784868 -7.007974) (xy 90.76606 -7.030605)
			(xy 90.752951 -7.056951) (xy 90.746243 -7.085602) (xy 90.745818 -7.100316) (xy 90.746315 -7.116969)
			(xy 90.754939 -7.149138) (xy 90.771595 -7.177979) (xy 90.795149 -7.201526) (xy 90.823994 -7.218174)
			(xy 90.856165 -7.22679) (xy 90.872818 -7.227316) (xy 91.278964 -7.227316) (xy 91.295062 -7.226849)
			(xy 91.326233 -7.218797) (xy 91.354396 -7.203198) (xy 91.377757 -7.181044) (xy 91.38666 -7.167626)
			(xy 91.406969 -7.136082) (xy 91.453239 -7.07702) (xy 91.505465 -7.023154) (xy 91.56307 -6.975083)
			(xy 91.625412 -6.933338) (xy 91.6918 -6.898385) (xy 91.761497 -6.87061) (xy 91.83373 -6.850323) (xy 91.907696 -6.837748)
			(xy 91.982575 -6.833025) (xy 92.057535 -6.836207) (xy 92.131744 -6.847257) (xy 92.204379 -6.866054)
			(xy 92.274633 -6.892389) (xy 92.341726 -6.925969) (xy 92.404914 -6.966422) (xy 92.463495 -7.013299)
			(xy 92.516818 -7.066079) (xy 92.564293 -7.124176) (xy 92.605391 -7.186946) (xy 92.639658 -7.253691)
			(xy 92.666711 -7.323672) (xy 92.686252 -7.39611) (xy 92.698063 -7.470202) (xy 92.702012 -7.545125)
			(xy 92.698057 -7.620049) (xy 92.686241 -7.69414) (xy 92.666695 -7.766577) (xy 92.639637 -7.836555)
			(xy 92.605366 -7.903298) (xy 92.564263 -7.966065) (xy 92.516784 -8.024159) (xy 92.463457 -8.076935)
			(xy 92.404872 -8.123807) (xy 92.341682 -8.164256) (xy 92.274586 -8.197831) (xy 92.20433 -8.224161)
			(xy 92.131694 -8.242953) (xy 92.057484 -8.253998) (xy 91.982524 -8.257174) (xy 91.907646 -8.252446)
			(xy 91.83368 -8.239866) (xy 91.761449 -8.219573) (xy 91.691754 -8.191794) (xy 91.625368 -8.156836)
			(xy 91.563029 -8.115087) (xy 91.505428 -8.067011) (xy 91.453205 -8.013142) (xy 91.40694 -7.954077)
			(xy 91.38666 -7.922514) (xy 91.37773 -7.909116) (xy 91.354379 -7.886962) (xy 91.326223 -7.871362)
			(xy 91.295058 -7.86331) (xy 91.278964 -7.862824) (xy 90.956638 -7.862824) (xy 90.939913 -7.863298)
			(xy 90.907599 -7.871938) (xy 90.878646 -7.888687) (xy 90.866468 -7.900162) (xy 90.857832 -7.909052)
			(xy 90.813636 -7.953248) (xy 90.813636 -8.058658) (xy 90.875612 -8.120634) (xy 90.913197 -8.129585)
			(xy 90.986315 -8.154564) (xy 91.056297 -8.187315) (xy 91.122321 -8.227452) (xy 91.164821 -8.26008)
			(xy 93.154506 -8.26008) (xy 93.158522 -8.14381) (xy 93.170549 -8.028095) (xy 93.190531 -7.913485)
			(xy 93.218373 -7.800526) (xy 93.253942 -7.689758) (xy 93.297068 -7.581707) (xy 93.347545 -7.476889)
			(xy 93.405134 -7.375804) (xy 93.46956 -7.278932) (xy 93.540515 -7.186736) (xy 93.617662 -7.099655)
			(xy 93.700633 -7.018104) (xy 93.789033 -6.942472) (xy 93.88244 -6.873118) (xy 93.980409 -6.810375)
			(xy 94.082473 -6.754539) (xy 94.188147 -6.705878) (xy 94.296926 -6.664624) (xy 94.408291 -6.630973)
			(xy 94.521714 -6.605085) (xy 94.636651 -6.587084) (xy 94.752557 -6.577055) (xy 94.868879 -6.575047)
			(xy 94.985062 -6.581069) (xy 95.100553 -6.595092) (xy 95.214801 -6.61705) (xy 95.327262 -6.646837)
			(xy 95.4374 -6.684312) (xy 95.54469 -6.729297) (xy 95.648621 -6.781576) (xy 95.748697 -6.840901)
			(xy 95.844443 -6.906989) (xy 95.9354 -6.979525) (xy 96.021136 -7.058164) (xy 96.101243 -7.14253)
			(xy 96.175339 -7.232222) (xy 96.243069 -7.326812) (xy 96.304113 -7.42585) (xy 96.358178 -7.528863)
			(xy 96.405008 -7.63536) (xy 96.444379 -7.744835) (xy 96.476103 -7.856765) (xy 96.500029 -7.970617)
			(xy 96.516043 -8.085849) (xy 96.52407 -8.201911) (xy 96.524572 -8.26008) (xy 96.52407 -8.318249)
			(xy 96.516043 -8.434311) (xy 96.500029 -8.549543) (xy 96.476103 -8.663395) (xy 96.444379 -8.775325)
			(xy 96.405008 -8.8848) (xy 96.358178 -8.991297) (xy 96.304113 -9.09431) (xy 96.243069 -9.193348)
			(xy 96.175339 -9.287938) (xy 96.101243 -9.37763) (xy 96.021136 -9.461996) (xy 95.9354 -9.540635)
			(xy 95.844443 -9.613171) (xy 95.748697 -9.679259) (xy 95.648621 -9.738584) (xy 95.54469 -9.790863)
			(xy 95.4374 -9.835848) (xy 95.327262 -9.873323) (xy 95.214801 -9.90311) (xy 95.100553 -9.925068)
			(xy 94.985062 -9.939091) (xy 94.868879 -9.945113) (xy 94.752557 -9.943105) (xy 94.636651 -9.933076)
			(xy 94.521714 -9.915075) (xy 94.408291 -9.889187) (xy 94.296926 -9.855536) (xy 94.188147 -9.814282)
			(xy 94.082473 -9.765621) (xy 93.980409 -9.709785) (xy 93.88244 -9.647042) (xy 93.789033 -9.577688)
			(xy 93.700633 -9.502056) (xy 93.617662 -9.420505) (xy 93.540515 -9.333424) (xy 93.46956 -9.241228)
			(xy 93.405134 -9.144356) (xy 93.347545 -9.043271) (xy 93.297068 -8.938453) (xy 93.253942 -8.830402)
			(xy 93.218373 -8.719634) (xy 93.190531 -8.606675) (xy 93.170549 -8.492065) (xy 93.158522 -8.37635)
			(xy 93.154506 -8.26008) (xy 91.164821 -8.26008) (xy 91.183609 -8.274504) (xy 91.239441 -8.327917)
			(xy 91.289159 -8.387063) (xy 91.332179 -8.451246) (xy 91.367995 -8.51971) (xy 91.382596 -8.555482)
			(xy 91.396308 -8.59193) (xy 91.416624 -8.667109) (xy 91.428612 -8.744057) (xy 91.432131 -8.821854)
			(xy 91.427138 -8.89957) (xy 91.413693 -8.976277) (xy 91.391956 -9.051058) (xy 91.362187 -9.12302)
			(xy 91.324742 -9.191303) (xy 91.30284 -9.223502) (xy 91.29141 -9.23925) (xy 91.26819 -9.269677) (xy 91.216234 -9.325885)
			(xy 91.158549 -9.376196) (xy 91.095802 -9.420032) (xy 91.028715 -9.456886) (xy 90.958063 -9.486332)
			(xy 90.884661 -9.508032) (xy 90.809355 -9.521735) (xy 90.733014 -9.527283) (xy 90.656518 -9.524612)
			(xy 90.618564 -9.519666) (xy 90.61704 -9.519412) (xy 90.612722 -9.518904) (xy 90.604086 -9.518142)
			(xy 90.585673 -9.51725) (xy 90.549614 -9.52483) (xy 90.517207 -9.542368) (xy 90.503756 -9.554972)
			(xy 88.872568 -11.185906) (xy 88.861223 -11.198056) (xy 88.844642 -11.226853) (xy 88.836056 -11.258954)
			(xy 88.835484 -11.275568) (xy 88.835484 -12.825476) (xy 88.838278 -12.838684) (xy 88.843602 -12.865569)
			(xy 88.847387 -12.920244) (xy 88.843303 -12.974898) (xy 88.831433 -13.028404) (xy 88.812023 -13.079658)
			(xy 88.799162 -13.10386) (xy 88.78316 -13.132562) (xy 88.78316 -13.256006) (xy 91.040456 -13.256006)
			(xy 91.044527 -13.200384) (xy 91.056653 -13.145947) (xy 91.076576 -13.093856) (xy 91.103872 -13.045221)
			(xy 91.137958 -13.001078) (xy 91.178107 -12.962369) (xy 91.223465 -12.929918) (xy 91.273065 -12.904417)
			(xy 91.325849 -12.88641) (xy 91.380692 -12.87628) (xy 91.436426 -12.874243) (xy 91.491863 -12.880343)
			(xy 91.54582 -12.894449) (xy 91.597149 -12.916261) (xy 91.644755 -12.945315) (xy 91.687623 -12.98099)
			(xy 91.72484 -13.022527) (xy 91.755613 -13.06904) (xy 91.779285 -13.119537) (xy 91.795353 -13.172944)
			(xy 91.803473 -13.22812) (xy 91.803838 -13.248132) (xy 95.94926 -13.248132) (xy 95.953331 -13.19251)
			(xy 95.965457 -13.138073) (xy 95.98538 -13.085982) (xy 96.012676 -13.037347) (xy 96.046762 -12.993204)
			(xy 96.086911 -12.954495) (xy 96.132269 -12.922044) (xy 96.181869 -12.896543) (xy 96.234653 -12.878536)
			(xy 96.289496 -12.868406) (xy 96.34523 -12.866369) (xy 96.400667 -12.872469) (xy 96.454624 -12.886575)
			(xy 96.505953 -12.908387) (xy 96.553559 -12.937441) (xy 96.596427 -12.973116) (xy 96.633644 -13.014653)
			(xy 96.664417 -13.061166) (xy 96.688089 -13.111663) (xy 96.704157 -13.16507) (xy 96.712277 -13.220246)
			(xy 96.712786 -13.248132) (xy 96.712277 -13.276018) (xy 96.704157 -13.331194) (xy 96.688089 -13.384601)
			(xy 96.664417 -13.435098) (xy 96.633644 -13.481611) (xy 96.596427 -13.523148) (xy 96.553559 -13.558823)
			(xy 96.505953 -13.587877) (xy 96.454624 -13.609689) (xy 96.400667 -13.623795) (xy 96.34523 -13.629895)
			(xy 96.289496 -13.627858) (xy 96.234653 -13.617728) (xy 96.181869 -13.599721) (xy 96.132269 -13.57422)
			(xy 96.086911 -13.541769) (xy 96.046762 -13.50306) (xy 96.012676 -13.458917) (xy 95.98538 -13.410282)
			(xy 95.965457 -13.358191) (xy 95.953331 -13.303754) (xy 95.94926 -13.248132) (xy 91.803838 -13.248132)
			(xy 91.803982 -13.256006) (xy 91.803473 -13.283892) (xy 91.795353 -13.339068) (xy 91.779285 -13.392475)
			(xy 91.755613 -13.442972) (xy 91.72484 -13.489485) (xy 91.687623 -13.531022) (xy 91.644755 -13.566697)
			(xy 91.597149 -13.595751) (xy 91.54582 -13.617563) (xy 91.491863 -13.631669) (xy 91.436426 -13.637769)
			(xy 91.380692 -13.635732) (xy 91.325849 -13.625602) (xy 91.273065 -13.607595) (xy 91.223465 -13.582094)
			(xy 91.178107 -13.549643) (xy 91.137958 -13.510934) (xy 91.103872 -13.466791) (xy 91.076576 -13.418156)
			(xy 91.056653 -13.366065) (xy 91.044527 -13.311628) (xy 91.040456 -13.256006) (xy 88.78316 -13.256006)
			(xy 88.78316 -14.256004) (xy 94.157798 -14.256004) (xy 94.161869 -14.200382) (xy 94.173995 -14.145945)
			(xy 94.193918 -14.093854) (xy 94.221214 -14.045219) (xy 94.2553 -14.001076) (xy 94.295449 -13.962367)
			(xy 94.340807 -13.929916) (xy 94.390407 -13.904415) (xy 94.443191 -13.886408) (xy 94.498034 -13.876278)
			(xy 94.553768 -13.874241) (xy 94.609205 -13.880341) (xy 94.663162 -13.894447) (xy 94.714491 -13.916259)
			(xy 94.762097 -13.945313) (xy 94.804965 -13.980988) (xy 94.842182 -14.022525) (xy 94.872955 -14.069038)
			(xy 94.896627 -14.119535) (xy 94.912695 -14.172942) (xy 94.920815 -14.228118) (xy 94.921324 -14.256004)
			(xy 94.920815 -14.28389) (xy 94.912695 -14.339066) (xy 94.896627 -14.392473) (xy 94.872955 -14.44297)
			(xy 94.842182 -14.489483) (xy 94.804965 -14.53102) (xy 94.762097 -14.566695) (xy 94.714491 -14.595749)
			(xy 94.663162 -14.617561) (xy 94.609205 -14.631667) (xy 94.553768 -14.637767) (xy 94.498034 -14.63573)
			(xy 94.443191 -14.6256) (xy 94.390407 -14.607593) (xy 94.340807 -14.582092) (xy 94.295449 -14.549641)
			(xy 94.2553 -14.510932) (xy 94.221214 -14.466789) (xy 94.193918 -14.418154) (xy 94.173995 -14.366063)
			(xy 94.161869 -14.311626) (xy 94.157798 -14.256004) (xy 88.78316 -14.256004) (xy 88.78316 -14.59738)
			(xy 86.199472 -17.181068) (xy 86.199472 -20.01012) (xy 86.877404 -20.01012) (xy 86.881424 -19.819469)
			(xy 86.893478 -19.629156) (xy 86.913544 -19.439521) (xy 86.941587 -19.2509) (xy 86.977556 -19.06363)
			(xy 87.021388 -18.878042) (xy 87.073005 -18.694467) (xy 87.132315 -18.513231) (xy 87.199213 -18.334656)
			(xy 87.273579 -18.159061) (xy 87.355281 -17.986756) (xy 87.444175 -17.818049) (xy 87.540101 -17.653239)
			(xy 87.64289 -17.49262) (xy 87.752359 -17.336477) (xy 87.868313 -17.185088) (xy 87.990547 -17.038721)
			(xy 88.118841 -16.897637) (xy 88.252969 -16.762088) (xy 88.392693 -16.632313) (xy 88.537763 -16.508543)
			(xy 88.687921 -16.391) (xy 88.842902 -16.279891) (xy 89.002429 -16.175414) (xy 89.166218 -16.077755)
			(xy 89.333978 -15.987088) (xy 89.505412 -15.903574) (xy 89.680214 -15.827361) (xy 89.858073 -15.758585)
			(xy 90.038674 -15.697367) (xy 90.221694 -15.643818) (xy 90.40681 -15.598032) (xy 90.593691 -15.56009)
			(xy 90.782006 -15.530061) (xy 90.971419 -15.507996) (xy 91.161593 -15.493937) (xy 91.352192 -15.487907)
			(xy 91.542875 -15.489917) (xy 91.733304 -15.499964) (xy 91.92314 -15.51803) (xy 92.112046 -15.544083)
			(xy 92.299685 -15.578076) (xy 92.485725 -15.619949) (xy 92.669834 -15.669628) (xy 92.851685 -15.727024)
			(xy 93.030955 -15.792035) (xy 93.207325 -15.864546) (xy 93.380481 -15.944427) (xy 93.550116 -16.031537)
			(xy 93.715928 -16.125721) (xy 93.877622 -16.226812) (xy 94.03491 -16.334628) (xy 94.187513 -16.44898)
			(xy 94.335161 -16.569663) (xy 94.477589 -16.696464) (xy 94.614545 -16.829155) (xy 94.745786 -16.967503)
			(xy 94.871078 -17.11126) (xy 94.990198 -17.260171) (xy 95.102934 -17.413972) (xy 95.209087 -17.572388)
			(xy 95.308467 -17.735139) (xy 95.400897 -17.901934) (xy 95.486214 -18.072478) (xy 95.564266 -18.246466)
			(xy 95.634913 -18.423591) (xy 95.698031 -18.603536) (xy 95.753507 -18.785982) (xy 95.801242 -18.970605)
			(xy 95.841152 -19.157075) (xy 95.873165 -19.345063) (xy 95.895305 -19.519138) (xy 98.049078 -19.519138)
			(xy 98.053149 -19.463516) (xy 98.065275 -19.409079) (xy 98.085198 -19.356988) (xy 98.112494 -19.308353)
			(xy 98.14658 -19.26421) (xy 98.186729 -19.225501) (xy 98.232087 -19.19305) (xy 98.281687 -19.167549)
			(xy 98.334471 -19.149542) (xy 98.389314 -19.139412) (xy 98.445048 -19.137375) (xy 98.500485 -19.143475)
			(xy 98.554442 -19.157581) (xy 98.605771 -19.179393) (xy 98.653377 -19.208447) (xy 98.696245 -19.244122)
			(xy 98.733462 -19.285659) (xy 98.764235 -19.332172) (xy 98.787907 -19.382669) (xy 98.803975 -19.436076)
			(xy 98.812095 -19.491252) (xy 98.812604 -19.519138) (xy 98.812095 -19.547024) (xy 98.803975 -19.6022)
			(xy 98.787907 -19.655607) (xy 98.764235 -19.706104) (xy 98.733462 -19.752617) (xy 98.696245 -19.794154)
			(xy 98.653377 -19.829829) (xy 98.605771 -19.858883) (xy 98.554442 -19.880695) (xy 98.500485 -19.894801)
			(xy 98.445048 -19.900901) (xy 98.389314 -19.898864) (xy 98.334471 -19.888734) (xy 98.281687 -19.870727)
			(xy 98.232087 -19.845226) (xy 98.186729 -19.812775) (xy 98.14658 -19.774066) (xy 98.112494 -19.729923)
			(xy 98.085198 -19.681288) (xy 98.065275 -19.629197) (xy 98.053149 -19.57476) (xy 98.049078 -19.519138)
			(xy 95.895305 -19.519138) (xy 95.897225 -19.534233) (xy 95.913288 -19.724249) (xy 95.921327 -19.914773)
			(xy 95.92183 -20.01012) (xy 95.921327 -20.105467) (xy 95.913288 -20.295991) (xy 95.897225 -20.486007)
			(xy 95.873165 -20.675177) (xy 95.841152 -20.863165) (xy 95.801242 -21.049635) (xy 95.753507 -21.234258)
			(xy 95.698031 -21.416704) (xy 95.634913 -21.596649) (xy 95.564266 -21.773774) (xy 95.486214 -21.947762)
			(xy 95.400897 -22.118306) (xy 95.308467 -22.285101) (xy 95.209087 -22.447852) (xy 95.102934 -22.606268)
			(xy 94.990198 -22.760069) (xy 94.871078 -22.90898) (xy 94.745786 -23.052737) (xy 94.614545 -23.191085)
			(xy 94.477589 -23.323776) (xy 94.335161 -23.450577) (xy 94.187513 -23.57126) (xy 94.03491 -23.685612)
			(xy 93.877622 -23.793428) (xy 93.715928 -23.894519) (xy 93.550116 -23.988703) (xy 93.380481 -24.075813)
			(xy 93.207325 -24.155694) (xy 93.030955 -24.228205) (xy 92.851685 -24.293216) (xy 92.669834 -24.350612)
			(xy 92.485725 -24.400291) (xy 92.299685 -24.442164) (xy 92.112046 -24.476157) (xy 91.92314 -24.50221)
			(xy 91.733304 -24.520276) (xy 91.542875 -24.530323) (xy 91.352192 -24.532333) (xy 91.161593 -24.526303)
			(xy 90.971419 -24.512244) (xy 90.782006 -24.490179) (xy 90.593691 -24.46015) (xy 90.40681 -24.422208)
			(xy 90.221694 -24.376422) (xy 90.038674 -24.322873) (xy 89.858073 -24.261655) (xy 89.680214 -24.192879)
			(xy 89.505412 -24.116666) (xy 89.333978 -24.033152) (xy 89.166218 -23.942485) (xy 89.002429 -23.844826)
			(xy 88.842902 -23.740349) (xy 88.687921 -23.62924) (xy 88.537763 -23.511697) (xy 88.392693 -23.387927)
			(xy 88.252969 -23.258152) (xy 88.118841 -23.122603) (xy 87.990547 -22.981519) (xy 87.868313 -22.835152)
			(xy 87.752359 -22.683763) (xy 87.64289 -22.52762) (xy 87.540101 -22.367001) (xy 87.444175 -22.202191)
			(xy 87.355281 -22.033484) (xy 87.273579 -21.861179) (xy 87.199213 -21.685584) (xy 87.132315 -21.507009)
			(xy 87.073005 -21.325773) (xy 87.021388 -21.142198) (xy 86.977556 -20.95661) (xy 86.941587 -20.76934)
			(xy 86.913544 -20.580719) (xy 86.893478 -20.391084) (xy 86.881424 -20.200771) (xy 86.877404 -20.01012)
			(xy 86.199472 -20.01012) (xy 86.199472 -48.624998) (xy 86.201843 -48.647521) (xy 86.213528 -48.691271)
			(xy 86.232773 -48.732262) (xy 86.25897 -48.769199) (xy 86.291291 -48.800916) (xy 86.328716 -48.82641)
			(xy 86.370063 -48.844878) (xy 86.414026 -48.855736) (xy 86.459216 -48.85864) (xy 86.504207 -48.8535)
			(xy 86.547578 -48.840477) (xy 86.568026 -48.830738) (xy 86.600825 -48.813321) (xy 86.669323 -48.784621)
			(xy 86.740437 -48.763211) (xy 86.813395 -48.749323) (xy 86.887402 -48.74311) (xy 86.961653 -48.744637)
			(xy 87.035342 -48.753889) (xy 87.107666 -48.770766) (xy 87.17784 -48.795082) (xy 87.211662 -48.810418)
			(xy 87.255096 -48.832516) (xy 87.287368 -48.850959) (xy 87.348267 -48.893583) (xy 87.404388 -48.942328)
			(xy 87.430102 -48.969168) (xy 87.440516 -48.980598) (xy 87.455904 -48.998115) (xy 87.484627 -49.034849)
			(xy 87.49792 -49.054004) (xy 87.519019 -49.085816) (xy 87.555049 -49.153118) (xy 87.58367 -49.223889)
			(xy 87.604553 -49.297316) (xy 87.61746 -49.372557) (xy 87.620348 -49.41062) (xy 87.623396 -49.458626)
			(xy 87.694516 -49.529746) (xy 87.799926 -49.529746) (xy 87.885524 -49.444148) (xy 88.622632 -49.444148)
			(xy 88.637507 -49.443739) (xy 88.666446 -49.436832) (xy 88.692993 -49.423403) (xy 88.715703 -49.404183)
			(xy 88.733337 -49.380221) (xy 88.744933 -49.352823) (xy 88.747854 -49.33823) (xy 88.747854 -49.337976)
			(xy 88.754189 -49.302708) (xy 88.773024 -49.233568) (xy 88.798707 -49.166669) (xy 88.830979 -49.102688)
			(xy 88.869513 -49.042271) (xy 88.891364 -49.013872) (xy 88.901593 -49.001124) (xy 88.923064 -48.976475)
			(xy 88.93429 -48.964596) (xy 88.9635 -48.93564) (xy 88.974676 -48.925226) (xy 89.00255 -48.900864)
			(xy 89.062498 -48.857422) (xy 89.126631 -48.820437) (xy 89.194258 -48.790309) (xy 89.264646 -48.767364)
			(xy 89.337036 -48.751849) (xy 89.410645 -48.743933) (xy 89.484678 -48.7437) (xy 89.558336 -48.751153)
			(xy 89.630822 -48.766212) (xy 89.701353 -48.788713) (xy 89.769168 -48.818415) (xy 89.833533 -48.854995)
			(xy 89.893753 -48.898059) (xy 89.949178 -48.947142) (xy 89.999208 -49.001712) (xy 90.021664 -49.031144)
			(xy 90.044125 -49.062297) (xy 90.08296 -49.128559) (xy 90.114432 -49.198619) (xy 90.138174 -49.271661)
			(xy 90.153909 -49.346836) (xy 90.161455 -49.423269) (xy 90.16159 -49.45507) (xy 91.277697 -49.45507)
			(xy 91.281732 -49.379366) (xy 91.293791 -49.304521) (xy 91.313737 -49.23138) (xy 91.341344 -49.160775)
			(xy 91.3763 -49.093504) (xy 91.418208 -49.030329) (xy 91.466594 -48.971967) (xy 91.52091 -48.919079)
			(xy 91.580539 -48.872264) (xy 91.644807 -48.832052) (xy 91.712984 -48.7989) (xy 91.7843 -48.773182)
			(xy 91.857945 -48.75519) (xy 91.933085 -48.745128) (xy 92.008869 -48.743109) (xy 92.084439 -48.749158)
			(xy 92.158937 -48.763205) (xy 92.23152 -48.785091) (xy 92.301366 -48.814568) (xy 92.367683 -48.851303)
			(xy 92.429719 -48.894878) (xy 92.486772 -48.9448) (xy 92.538196 -49.000504) (xy 92.583407 -49.061359)
			(xy 92.621894 -49.126674) (xy 92.65322 -49.19571) (xy 92.67703 -49.267685) (xy 92.693055 -49.341783)
			(xy 92.701114 -49.417164) (xy 92.701618 -49.45507) (xy 92.701114 -49.492976) (xy 92.693055 -49.568357)
			(xy 92.67703 -49.642455) (xy 92.65322 -49.71443) (xy 92.621894 -49.783466) (xy 92.583407 -49.848781)
			(xy 92.538196 -49.909636) (xy 92.486772 -49.96534) (xy 92.429719 -50.015262) (xy 92.367683 -50.058837)
			(xy 92.301366 -50.095572) (xy 92.23152 -50.125049) (xy 92.158937 -50.146935) (xy 92.084439 -50.160982)
			(xy 92.008869 -50.167031) (xy 91.933085 -50.165012) (xy 91.857945 -50.15495) (xy 91.7843 -50.136958)
			(xy 91.712984 -50.11124) (xy 91.644807 -50.078088) (xy 91.580539 -50.037876) (xy 91.52091 -49.991061)
			(xy 91.466594 -49.938173) (xy 91.418208 -49.879811) (xy 91.3763 -49.816636) (xy 91.341344 -49.749365)
			(xy 91.313737 -49.67876) (xy 91.293791 -49.605619) (xy 91.281732 -49.530774) (xy 91.277697 -49.45507)
			(xy 90.16159 -49.45507) (xy 90.161618 -49.461674) (xy 90.16076 -49.499537) (xy 90.152012 -49.574768)
			(xy 90.135325 -49.648645) (xy 90.110888 -49.720333) (xy 90.078976 -49.78902) (xy 90.039951 -49.853931)
			(xy 89.994254 -49.91433) (xy 89.942402 -49.969536) (xy 89.884982 -50.018924) (xy 89.822641 -50.061935)
			(xy 89.756086 -50.098084) (xy 89.686068 -50.12696) (xy 89.613381 -50.148239) (xy 89.538844 -50.161679)
			(xy 89.463302 -50.167128) (xy 89.387609 -50.164525) (xy 89.312619 -50.153899) (xy 89.239182 -50.135371)
			(xy 89.168128 -50.109149) (xy 89.133934 -50.092864) (xy 89.107264 -50.079656) (xy 89.054686 -50.079656)
			(xy 89.032094 -50.080863) (xy 88.987845 -50.090274) (xy 88.945962 -50.107371) (xy 88.907767 -50.131614)
			(xy 88.874469 -50.162236) (xy 88.847119 -50.198271) (xy 88.826581 -50.238579) (xy 88.813505 -50.281886)
			(xy 88.808304 -50.326824) (xy 88.811141 -50.371974) (xy 88.821928 -50.415907) (xy 88.830658 -50.43678)
			(xy 88.845467 -50.471401) (xy 88.868548 -50.54308) (xy 88.883941 -50.616794) (xy 88.891475 -50.69172)
			(xy 88.891294 -50.72507) (xy 90.007697 -50.72507) (xy 90.011732 -50.649366) (xy 90.023791 -50.574521)
			(xy 90.043737 -50.50138) (xy 90.071344 -50.430775) (xy 90.1063 -50.363504) (xy 90.148208 -50.300329)
			(xy 90.196594 -50.241967) (xy 90.25091 -50.189079) (xy 90.310539 -50.142264) (xy 90.374807 -50.102052)
			(xy 90.442984 -50.0689) (xy 90.5143 -50.043182) (xy 90.587945 -50.02519) (xy 90.663085 -50.015128)
			(xy 90.738869 -50.013109) (xy 90.814439 -50.019158) (xy 90.888937 -50.033205) (xy 90.96152 -50.055091)
			(xy 91.031366 -50.084568) (xy 91.097683 -50.121303) (xy 91.159719 -50.164878) (xy 91.216772 -50.2148)
			(xy 91.268196 -50.270504) (xy 91.313407 -50.331359) (xy 91.351894 -50.396674) (xy 91.38322 -50.46571)
			(xy 91.40703 -50.537685) (xy 91.423055 -50.611783) (xy 91.431114 -50.687164) (xy 91.431618 -50.72507)
			(xy 91.431114 -50.762976) (xy 91.423055 -50.838357) (xy 91.40703 -50.912455) (xy 91.38322 -50.98443)
			(xy 91.351894 -51.053466) (xy 91.313407 -51.118781) (xy 91.268196 -51.179636) (xy 91.216772 -51.23534)
			(xy 91.159719 -51.285262) (xy 91.097683 -51.328837) (xy 91.031366 -51.365572) (xy 90.96152 -51.395049)
			(xy 90.888937 -51.416935) (xy 90.814439 -51.430982) (xy 90.738869 -51.437031) (xy 90.663085 -51.435012)
			(xy 90.587945 -51.42495) (xy 90.5143 -51.406958) (xy 90.442984 -51.38124) (xy 90.374807 -51.348088)
			(xy 90.310539 -51.307876) (xy 90.25091 -51.261061) (xy 90.196594 -51.208173) (xy 90.148208 -51.149811)
			(xy 90.1063 -51.086636) (xy 90.071344 -51.019365) (xy 90.043737 -50.94876) (xy 90.023791 -50.875619)
			(xy 90.011732 -50.800774) (xy 90.007697 -50.72507) (xy 88.891294 -50.72507) (xy 88.891066 -50.767022)
			(xy 88.882718 -50.841862) (xy 88.875108 -50.87874) (xy 88.874854 -50.879502) (xy 88.87333 -50.886614)
			(xy 88.870453 -50.902203) (xy 88.871587 -50.933873) (xy 88.880475 -50.964291) (xy 88.896573 -50.991588)
			(xy 88.907366 -51.0032) (xy 88.91778 -51.013614) (xy 88.91778 -51.091338) (xy 88.920132 -51.11363)
			(xy 88.931659 -51.156942) (xy 88.950597 -51.197566) (xy 88.976359 -51.234243) (xy 89.008148 -51.265839)
			(xy 89.044982 -51.291377) (xy 89.08572 -51.310066) (xy 89.129102 -51.321329) (xy 89.173787 -51.324818)
			(xy 89.218391 -51.320423) (xy 89.240106 -51.314858) (xy 89.276522 -51.304138) (xy 89.351034 -51.289609)
			(xy 89.42667 -51.283093) (xy 89.502569 -51.284664) (xy 89.57787 -51.294304) (xy 89.651717 -51.311904)
			(xy 89.723272 -51.337263) (xy 89.791722 -51.370093) (xy 89.856288 -51.410022) (xy 89.916239 -51.456596)
			(xy 89.970892 -51.509286) (xy 90.019627 -51.567493) (xy 90.06189 -51.630557) (xy 90.097201 -51.69776)
			(xy 90.12516 -51.76834) (xy 90.145448 -51.841494) (xy 90.157835 -51.916392) (xy 90.16218 -51.992183)
			(xy 90.162079 -51.99507) (xy 91.277697 -51.99507) (xy 91.281732 -51.919366) (xy 91.293791 -51.844521)
			(xy 91.313737 -51.77138) (xy 91.341344 -51.700775) (xy 91.3763 -51.633504) (xy 91.418208 -51.570329)
			(xy 91.466594 -51.511967) (xy 91.52091 -51.459079) (xy 91.580539 -51.412264) (xy 91.644807 -51.372052)
			(xy 91.712984 -51.3389) (xy 91.7843 -51.313182) (xy 91.857945 -51.29519) (xy 91.933085 -51.285128)
			(xy 92.008869 -51.283109) (xy 92.084439 -51.289158) (xy 92.158937 -51.303205) (xy 92.23152 -51.325091)
			(xy 92.301366 -51.354568) (xy 92.367683 -51.391303) (xy 92.429719 -51.434878) (xy 92.486772 -51.4848)
			(xy 92.538196 -51.540504) (xy 92.583407 -51.601359) (xy 92.621894 -51.666674) (xy 92.65322 -51.73571)
			(xy 92.67703 -51.807685) (xy 92.693055 -51.881783) (xy 92.701114 -51.957164) (xy 92.701618 -51.99507)
			(xy 92.701114 -52.032976) (xy 92.693055 -52.108357) (xy 92.67703 -52.182455) (xy 92.65322 -52.25443)
			(xy 92.621894 -52.323466) (xy 92.583407 -52.388781) (xy 92.538196 -52.449636) (xy 92.486772 -52.50534)
			(xy 92.429719 -52.555262) (xy 92.367683 -52.598837) (xy 92.301366 -52.635572) (xy 92.23152 -52.665049)
			(xy 92.158937 -52.686935) (xy 92.084439 -52.700982) (xy 92.008869 -52.707031) (xy 91.933085 -52.705012)
			(xy 91.857945 -52.69495) (xy 91.7843 -52.676958) (xy 91.712984 -52.65124) (xy 91.644807 -52.618088)
			(xy 91.580539 -52.577876) (xy 91.52091 -52.531061) (xy 91.466594 -52.478173) (xy 91.418208 -52.419811)
			(xy 91.3763 -52.356636) (xy 91.341344 -52.289365) (xy 91.313737 -52.21876) (xy 91.293791 -52.145619)
			(xy 91.281732 -52.070774) (xy 91.277697 -51.99507) (xy 90.162079 -51.99507) (xy 90.160856 -52.030122)
			(xy 90.160602 -52.033424) (xy 90.160602 -52.035202) (xy 90.158152 -52.07054) (xy 90.147124 -52.140517)
			(xy 90.129204 -52.209054) (xy 90.10457 -52.275473) (xy 90.073464 -52.339119) (xy 90.055192 -52.369466)
			(xy 90.044016 -52.386992) (xy 90.022584 -52.418536) (xy 89.973991 -52.477316) (xy 89.919395 -52.530567)
			(xy 89.859421 -52.577679) (xy 89.827354 -52.59832) (xy 89.81396 -52.607253) (xy 89.791812 -52.630607)
			(xy 89.776216 -52.658761) (xy 89.768163 -52.689923) (xy 89.767664 -52.706016) (xy 89.767664 -53.113686)
			(xy 89.768205 -53.130337) (xy 89.77682 -53.162506) (xy 89.793467 -53.19135) (xy 89.81701 -53.214903)
			(xy 89.845847 -53.231561) (xy 89.878013 -53.240188) (xy 89.894664 -53.240686) (xy 89.940638 -53.240686)
			(xy 90.010996 -53.182266) (xy 90.019378 -53.1368) (xy 90.023522 -53.115577) (xy 90.034071 -53.073638)
			(xy 90.04046 -53.05298) (xy 90.053158 -53.014202) (xy 90.086219 -52.939599) (xy 90.127595 -52.869266)
			(xy 90.17674 -52.804126) (xy 90.233012 -52.745032) (xy 90.26398 -52.718462) (xy 90.29573 -52.69357)
			(xy 90.326321 -52.671487) (xy 90.391328 -52.633187) (xy 90.460021 -52.601978) (xy 90.531631 -52.57821)
			(xy 90.605352 -52.56215) (xy 90.680359 -52.553978) (xy 90.75581 -52.553785) (xy 90.830857 -52.561575)
			(xy 90.90466 -52.577258) (xy 90.97639 -52.60066) (xy 91.045242 -52.631518) (xy 91.110444 -52.669486)
			(xy 91.165738 -52.71008) (xy 93.154506 -52.71008) (xy 93.158522 -52.59381) (xy 93.170549 -52.478095)
			(xy 93.190531 -52.363485) (xy 93.218373 -52.250526) (xy 93.253942 -52.139758) (xy 93.297068 -52.031707)
			(xy 93.347545 -51.926889) (xy 93.405134 -51.825804) (xy 93.46956 -51.728932) (xy 93.540515 -51.636736)
			(xy 93.617662 -51.549655) (xy 93.700633 -51.468104) (xy 93.789033 -51.392472) (xy 93.88244 -51.323118)
			(xy 93.980409 -51.260375) (xy 94.082473 -51.204539) (xy 94.188147 -51.155878) (xy 94.296926 -51.114624)
			(xy 94.408291 -51.080973) (xy 94.521714 -51.055085) (xy 94.636651 -51.037084) (xy 94.752557 -51.027055)
			(xy 94.868879 -51.025047) (xy 94.985062 -51.031069) (xy 95.100553 -51.045092) (xy 95.214801 -51.06705)
			(xy 95.327262 -51.096837) (xy 95.4374 -51.134312) (xy 95.54469 -51.179297) (xy 95.648621 -51.231576)
			(xy 95.748697 -51.290901) (xy 95.844443 -51.356989) (xy 95.9354 -51.429525) (xy 96.021136 -51.508164)
			(xy 96.101243 -51.59253) (xy 96.175339 -51.682222) (xy 96.243069 -51.776812) (xy 96.304113 -51.87585)
			(xy 96.358178 -51.978863) (xy 96.405008 -52.08536) (xy 96.444379 -52.194835) (xy 96.476103 -52.306765)
			(xy 96.500029 -52.420617) (xy 96.516043 -52.535849) (xy 96.52407 -52.651911) (xy 96.524572 -52.71008)
			(xy 96.52407 -52.768249) (xy 96.516043 -52.884311) (xy 96.500029 -52.999543) (xy 96.476103 -53.113395)
			(xy 96.444379 -53.225325) (xy 96.405008 -53.3348) (xy 96.358178 -53.441297) (xy 96.304113 -53.54431)
			(xy 96.243069 -53.643348) (xy 96.175339 -53.737938) (xy 96.101243 -53.82763) (xy 96.021136 -53.911996)
			(xy 95.9354 -53.990635) (xy 95.844443 -54.063171) (xy 95.748697 -54.129259) (xy 95.648621 -54.188584)
			(xy 95.54469 -54.240863) (xy 95.4374 -54.285848) (xy 95.327262 -54.323323) (xy 95.214801 -54.35311)
			(xy 95.100553 -54.375068) (xy 94.985062 -54.389091) (xy 94.868879 -54.395113) (xy 94.752557 -54.393105)
			(xy 94.636651 -54.383076) (xy 94.521714 -54.365075) (xy 94.408291 -54.339187) (xy 94.296926 -54.305536)
			(xy 94.188147 -54.264282) (xy 94.082473 -54.215621) (xy 93.980409 -54.159785) (xy 93.88244 -54.097042)
			(xy 93.789033 -54.027688) (xy 93.700633 -53.952056) (xy 93.617662 -53.870505) (xy 93.540515 -53.783424)
			(xy 93.46956 -53.691228) (xy 93.405134 -53.594356) (xy 93.347545 -53.493271) (xy 93.297068 -53.388453)
			(xy 93.253942 -53.280402) (xy 93.218373 -53.169634) (xy 93.190531 -53.056675) (xy 93.170549 -52.942065)
			(xy 93.158522 -52.82635) (xy 93.154506 -52.71008) (xy 91.165738 -52.71008) (xy 91.171264 -52.714137)
			(xy 91.22702 -52.764971) (xy 91.277086 -52.821417) (xy 91.320901 -52.882842) (xy 91.357973 -52.948557)
			(xy 91.387886 -53.017825) (xy 91.410305 -53.089868) (xy 91.424977 -53.163878) (xy 91.431739 -53.239026)
			(xy 91.431618 -53.276754) (xy 91.430602 -53.303678) (xy 91.430348 -53.306472) (xy 91.427694 -53.343734)
			(xy 91.415548 -53.417447) (xy 91.395751 -53.489484) (xy 91.368521 -53.559052) (xy 91.334157 -53.625386)
			(xy 91.293037 -53.687758) (xy 91.245612 -53.745482) (xy 91.192405 -53.797924) (xy 91.133999 -53.844507)
			(xy 91.071037 -53.884718) (xy 91.004212 -53.918117) (xy 90.934256 -53.944336) (xy 90.898218 -53.954172)
			(xy 90.891868 -53.955696) (xy 90.856661 -53.964) (xy 90.785054 -53.974269) (xy 90.712775 -53.977227)
			(xy 90.640568 -53.972845) (xy 90.569176 -53.961167) (xy 90.499336 -53.942314) (xy 90.465402 -53.929788)
			(xy 90.451432 -53.9242) (xy 90.416894 -53.909607) (xy 90.350807 -53.874181) (xy 90.288802 -53.832017)
			(xy 90.231562 -53.78358) (xy 90.205306 -53.756814) (xy 90.189091 -53.740561) (xy 90.151931 -53.71361)
			(xy 90.110536 -53.693767) (xy 90.066251 -53.681678) (xy 90.020515 -53.677735) (xy 89.974815 -53.682067)
			(xy 89.930635 -53.694533) (xy 89.88941 -53.714728) (xy 89.852481 -53.741995) (xy 89.821046 -53.775449)
			(xy 89.796128 -53.814003) (xy 89.778536 -53.856403) (xy 89.768842 -53.901273) (xy 89.767664 -53.9242)
			(xy 89.767664 -54.62651) (xy 89.096596 -55.297832) (xy 89.012268 -55.38216) (xy 89.012268 -57.643268)
			(xy 84.177886 -62.47765) (xy 84.168996 -62.509146) (xy 84.160911 -62.535512) (xy 84.138205 -62.585767)
			(xy 84.108503 -62.632231) (xy 84.072423 -62.673937) (xy 84.030715 -62.710015) (xy 83.98425 -62.739715)
			(xy 83.933993 -62.762418) (xy 83.90763 -62.770512) (xy 83.876134 -62.779402) (xy 82.195416 -64.46012)
			(xy 86.877404 -64.46012) (xy 86.881424 -64.269469) (xy 86.893478 -64.079156) (xy 86.913544 -63.889521)
			(xy 86.941587 -63.7009) (xy 86.977556 -63.51363) (xy 87.021388 -63.328042) (xy 87.073005 -63.144467)
			(xy 87.132315 -62.963231) (xy 87.199213 -62.784656) (xy 87.273579 -62.609061) (xy 87.355281 -62.436756)
			(xy 87.444175 -62.268049) (xy 87.540101 -62.103239) (xy 87.64289 -61.94262) (xy 87.752359 -61.786477)
			(xy 87.868313 -61.635088) (xy 87.990547 -61.488721) (xy 88.118841 -61.347637) (xy 88.252969 -61.212088)
			(xy 88.392693 -61.082313) (xy 88.537763 -60.958543) (xy 88.687921 -60.841) (xy 88.842902 -60.729891)
			(xy 89.002429 -60.625414) (xy 89.166218 -60.527755) (xy 89.333978 -60.437088) (xy 89.505412 -60.353574)
			(xy 89.680214 -60.277361) (xy 89.858073 -60.208585) (xy 90.038674 -60.147367) (xy 90.221694 -60.093818)
			(xy 90.40681 -60.048032) (xy 90.593691 -60.01009) (xy 90.782006 -59.980061) (xy 90.971419 -59.957996)
			(xy 91.161593 -59.943937) (xy 91.352192 -59.937907) (xy 91.542875 -59.939917) (xy 91.733304 -59.949964)
			(xy 91.92314 -59.96803) (xy 92.112046 -59.994083) (xy 92.299685 -60.028076) (xy 92.485725 -60.069949)
			(xy 92.669834 -60.119628) (xy 92.851685 -60.177024) (xy 93.030955 -60.242035) (xy 93.207325 -60.314546)
			(xy 93.380481 -60.394427) (xy 93.550116 -60.481537) (xy 93.715928 -60.575721) (xy 93.877622 -60.676812)
			(xy 94.03491 -60.784628) (xy 94.187513 -60.89898) (xy 94.335161 -61.019663) (xy 94.477589 -61.146464)
			(xy 94.614545 -61.279155) (xy 94.745786 -61.417503) (xy 94.871078 -61.56126) (xy 94.990198 -61.710171)
			(xy 95.102934 -61.863972) (xy 95.209087 -62.022388) (xy 95.308467 -62.185139) (xy 95.400897 -62.351934)
			(xy 95.486214 -62.522478) (xy 95.564266 -62.696466) (xy 95.634913 -62.873591) (xy 95.698031 -63.053536)
			(xy 95.753507 -63.235982) (xy 95.801242 -63.420605) (xy 95.841152 -63.607075) (xy 95.873165 -63.795063)
			(xy 95.897225 -63.984233) (xy 95.913288 -64.174249) (xy 95.921327 -64.364773) (xy 95.92183 -64.46012)
			(xy 95.921327 -64.555467) (xy 95.913288 -64.745991) (xy 95.897225 -64.936007) (xy 95.873165 -65.125177)
			(xy 95.841152 -65.313165) (xy 95.801242 -65.499635) (xy 95.753507 -65.684258) (xy 95.698031 -65.866704)
			(xy 95.634913 -66.046649) (xy 95.564266 -66.223774) (xy 95.486214 -66.397762) (xy 95.400897 -66.568306)
			(xy 95.308467 -66.735101) (xy 95.209087 -66.897852) (xy 95.102934 -67.056268) (xy 94.990198 -67.210069)
			(xy 94.871078 -67.35898) (xy 94.745786 -67.502737) (xy 94.614545 -67.641085) (xy 94.477589 -67.773776)
			(xy 94.335161 -67.900577) (xy 94.187513 -68.02126) (xy 94.03491 -68.135612) (xy 93.877622 -68.243428)
			(xy 93.715928 -68.344519) (xy 93.550116 -68.438703) (xy 93.380481 -68.525813) (xy 93.207325 -68.605694)
			(xy 93.030955 -68.678205) (xy 92.851685 -68.743216) (xy 92.669834 -68.800612) (xy 92.485725 -68.850291)
			(xy 92.299685 -68.892164) (xy 92.112046 -68.926157) (xy 91.92314 -68.95221) (xy 91.733304 -68.970276)
			(xy 91.542875 -68.980323) (xy 91.352192 -68.982333) (xy 91.161593 -68.976303) (xy 90.971419 -68.962244)
			(xy 90.782006 -68.940179) (xy 90.593691 -68.91015) (xy 90.40681 -68.872208) (xy 90.221694 -68.826422)
			(xy 90.038674 -68.772873) (xy 89.858073 -68.711655) (xy 89.680214 -68.642879) (xy 89.505412 -68.566666)
			(xy 89.333978 -68.483152) (xy 89.166218 -68.392485) (xy 89.002429 -68.294826) (xy 88.842902 -68.190349)
			(xy 88.687921 -68.07924) (xy 88.537763 -67.961697) (xy 88.392693 -67.837927) (xy 88.252969 -67.708152)
			(xy 88.118841 -67.572603) (xy 87.990547 -67.431519) (xy 87.868313 -67.285152) (xy 87.752359 -67.133763)
			(xy 87.64289 -66.97762) (xy 87.540101 -66.817001) (xy 87.444175 -66.652191) (xy 87.355281 -66.483484)
			(xy 87.273579 -66.311179) (xy 87.199213 -66.135584) (xy 87.132315 -65.957009) (xy 87.073005 -65.775773)
			(xy 87.021388 -65.592198) (xy 86.977556 -65.40661) (xy 86.941587 -65.21934) (xy 86.913544 -65.030719)
			(xy 86.893478 -64.841084) (xy 86.881424 -64.650771) (xy 86.877404 -64.46012) (xy 82.195416 -64.46012)
			(xy 68.276863 -78.378673) (xy 74.888081 -78.378673) (xy 74.888081 -78.220963) (xy 74.896069 -78.063456)
			(xy 74.912025 -77.906556) (xy 74.935906 -77.750665) (xy 74.967653 -77.596184) (xy 75.007183 -77.443509)
			(xy 75.054395 -77.293033) (xy 75.109169 -77.14514) (xy 75.171362 -77.000212) (xy 75.240817 -76.85862)
			(xy 75.317353 -76.720727) (xy 75.400776 -76.586888) (xy 75.49087 -76.457446) (xy 75.587405 -76.332733)
			(xy 75.690133 -76.21307) (xy 75.798789 -76.098763) (xy 75.913096 -75.990107) (xy 76.032759 -75.887379)
			(xy 76.157472 -75.790844) (xy 76.286914 -75.70075) (xy 76.420753 -75.617327) (xy 76.558646 -75.540791)
			(xy 76.700238 -75.471336) (xy 76.845166 -75.409143) (xy 76.993059 -75.354369) (xy 77.143535 -75.307157)
			(xy 77.29621 -75.267627) (xy 77.450691 -75.23588) (xy 77.606582 -75.211999) (xy 77.763482 -75.196043)
			(xy 77.920989 -75.188055) (xy 78.078699 -75.188055) (xy 78.236206 -75.196043) (xy 78.393106 -75.211999)
			(xy 78.548997 -75.23588) (xy 78.703478 -75.267627) (xy 78.856153 -75.307157) (xy 79.006629 -75.354369)
			(xy 79.154522 -75.409143) (xy 79.29945 -75.471336) (xy 79.441042 -75.540791) (xy 79.578935 -75.617327)
			(xy 79.712774 -75.70075) (xy 79.842216 -75.790844) (xy 79.966929 -75.887379) (xy 80.086592 -75.990107)
			(xy 80.200899 -76.098763) (xy 80.309555 -76.21307) (xy 80.412283 -76.332733) (xy 80.508818 -76.457446)
			(xy 80.598912 -76.586888) (xy 80.682335 -76.720727) (xy 80.758871 -76.85862) (xy 80.828326 -77.000212)
			(xy 80.890519 -77.14514) (xy 80.945293 -77.293033) (xy 80.992505 -77.443509) (xy 81.032035 -77.596184)
			(xy 81.063782 -77.750665) (xy 81.087663 -77.906556) (xy 81.103619 -78.063456) (xy 81.111607 -78.220963)
			(xy 81.112106 -78.299818) (xy 81.111607 -78.378673) (xy 81.103619 -78.53618) (xy 81.087663 -78.69308)
			(xy 81.063782 -78.848971) (xy 81.032035 -79.003452) (xy 80.992505 -79.156127) (xy 80.968621 -79.232252)
			(xy 91.514928 -79.232252) (xy 91.518999 -79.17663) (xy 91.531125 -79.122193) (xy 91.551048 -79.070102)
			(xy 91.578344 -79.021467) (xy 91.61243 -78.977324) (xy 91.652579 -78.938615) (xy 91.697937 -78.906164)
			(xy 91.747537 -78.880663) (xy 91.800321 -78.862656) (xy 91.855164 -78.852526) (xy 91.910898 -78.850489)
			(xy 91.966335 -78.856589) (xy 92.020292 -78.870695) (xy 92.071621 -78.892507) (xy 92.119227 -78.921561)
			(xy 92.162095 -78.957236) (xy 92.199312 -78.998773) (xy 92.230085 -79.045286) (xy 92.253757 -79.095783)
			(xy 92.269825 -79.14919) (xy 92.277945 -79.204366) (xy 92.278454 -79.232252) (xy 92.277945 -79.260138)
			(xy 92.269825 -79.315314) (xy 92.253757 -79.368721) (xy 92.230085 -79.419218) (xy 92.199312 -79.465731)
			(xy 92.162095 -79.507268) (xy 92.119227 -79.542943) (xy 92.071621 -79.571997) (xy 92.020292 -79.593809)
			(xy 91.966335 -79.607915) (xy 91.910898 -79.614015) (xy 91.855164 -79.611978) (xy 91.800321 -79.601848)
			(xy 91.747537 -79.583841) (xy 91.697937 -79.55834) (xy 91.652579 -79.525889) (xy 91.61243 -79.48718)
			(xy 91.578344 -79.443037) (xy 91.551048 -79.394402) (xy 91.531125 -79.342311) (xy 91.518999 -79.287874)
			(xy 91.514928 -79.232252) (xy 80.968621 -79.232252) (xy 80.945293 -79.306603) (xy 80.890519 -79.454496)
			(xy 80.828326 -79.599424) (xy 80.758871 -79.741016) (xy 80.682335 -79.878909) (xy 80.598912 -80.012748)
			(xy 80.508818 -80.14219) (xy 80.412283 -80.266903) (xy 80.309555 -80.386566) (xy 80.200899 -80.500873)
			(xy 80.086592 -80.609529) (xy 79.966929 -80.712257) (xy 79.842216 -80.808792) (xy 79.712774 -80.898886)
			(xy 79.578935 -80.982309) (xy 79.441042 -81.058845) (xy 79.29945 -81.1283) (xy 79.154522 -81.190493)
			(xy 79.006629 -81.245267) (xy 78.856153 -81.292479) (xy 78.703478 -81.332009) (xy 78.548997 -81.363756)
			(xy 78.393106 -81.387637) (xy 78.236206 -81.403593) (xy 78.078699 -81.411581) (xy 77.920989 -81.411581)
			(xy 77.763482 -81.403593) (xy 77.606582 -81.387637) (xy 77.450691 -81.363756) (xy 77.29621 -81.332009)
			(xy 77.143535 -81.292479) (xy 76.993059 -81.245267) (xy 76.845166 -81.190493) (xy 76.700238 -81.1283)
			(xy 76.558646 -81.058845) (xy 76.420753 -80.982309) (xy 76.286914 -80.898886) (xy 76.157472 -80.808792)
			(xy 76.032759 -80.712257) (xy 75.913096 -80.609529) (xy 75.798789 -80.500873) (xy 75.690133 -80.386566)
			(xy 75.587405 -80.266903) (xy 75.49087 -80.14219) (xy 75.400776 -80.012748) (xy 75.317353 -79.878909)
			(xy 75.240817 -79.741016) (xy 75.171362 -79.599424) (xy 75.109169 -79.454496) (xy 75.054395 -79.306603)
			(xy 75.007183 -79.156127) (xy 74.967653 -79.003452) (xy 74.935906 -78.848971) (xy 74.912025 -78.69308)
			(xy 74.896069 -78.53618) (xy 74.888081 -78.378673) (xy 68.276863 -78.378673) (xy 64.692784 -81.962752)
			(xy 71.010778 -81.962752) (xy 71.014849 -81.90713) (xy 71.026975 -81.852693) (xy 71.046898 -81.800602)
			(xy 71.074194 -81.751967) (xy 71.10828 -81.707824) (xy 71.148429 -81.669115) (xy 71.193787 -81.636664)
			(xy 71.243387 -81.611163) (xy 71.296171 -81.593156) (xy 71.351014 -81.583026) (xy 71.406748 -81.580989)
			(xy 71.462185 -81.587089) (xy 71.516142 -81.601195) (xy 71.567471 -81.623007) (xy 71.615077 -81.652061)
			(xy 71.657945 -81.687736) (xy 71.695162 -81.729273) (xy 71.725935 -81.775786) (xy 71.749607 -81.826283)
			(xy 71.765675 -81.87969) (xy 71.773795 -81.934866) (xy 71.774304 -81.962752) (xy 72.138284 -81.962752)
			(xy 72.142355 -81.90713) (xy 72.154481 -81.852693) (xy 72.174404 -81.800602) (xy 72.2017 -81.751967)
			(xy 72.235786 -81.707824) (xy 72.275935 -81.669115) (xy 72.321293 -81.636664) (xy 72.370893 -81.611163)
			(xy 72.423677 -81.593156) (xy 72.47852 -81.583026) (xy 72.534254 -81.580989) (xy 72.589691 -81.587089)
			(xy 72.643648 -81.601195) (xy 72.694977 -81.623007) (xy 72.742583 -81.652061) (xy 72.785451 -81.687736)
			(xy 72.822668 -81.729273) (xy 72.853441 -81.775786) (xy 72.877113 -81.826283) (xy 72.893181 -81.87969)
			(xy 72.901301 -81.934866) (xy 72.90181 -81.962752) (xy 73.251312 -81.962752) (xy 73.255383 -81.90713)
			(xy 73.267509 -81.852693) (xy 73.287432 -81.800602) (xy 73.314728 -81.751967) (xy 73.348814 -81.707824)
			(xy 73.388963 -81.669115) (xy 73.434321 -81.636664) (xy 73.483921 -81.611163) (xy 73.536705 -81.593156)
			(xy 73.591548 -81.583026) (xy 73.647282 -81.580989) (xy 73.702719 -81.587089) (xy 73.756676 -81.601195)
			(xy 73.808005 -81.623007) (xy 73.855611 -81.652061) (xy 73.898479 -81.687736) (xy 73.935696 -81.729273)
			(xy 73.966469 -81.775786) (xy 73.990141 -81.826283) (xy 74.006209 -81.87969) (xy 74.014329 -81.934866)
			(xy 74.014838 -81.962752) (xy 74.422506 -81.962752) (xy 74.426577 -81.90713) (xy 74.438703 -81.852693)
			(xy 74.458626 -81.800602) (xy 74.485922 -81.751967) (xy 74.520008 -81.707824) (xy 74.560157 -81.669115)
			(xy 74.605515 -81.636664) (xy 74.655115 -81.611163) (xy 74.707899 -81.593156) (xy 74.762742 -81.583026)
			(xy 74.818476 -81.580989) (xy 74.873913 -81.587089) (xy 74.92787 -81.601195) (xy 74.979199 -81.623007)
			(xy 75.026805 -81.652061) (xy 75.069673 -81.687736) (xy 75.10689 -81.729273) (xy 75.137663 -81.775786)
			(xy 75.161335 -81.826283) (xy 75.177403 -81.87969) (xy 75.185523 -81.934866) (xy 75.186032 -81.962752)
			(xy 75.185523 -81.990638) (xy 75.177403 -82.045814) (xy 75.161335 -82.099221) (xy 75.137663 -82.149718)
			(xy 75.10689 -82.196231) (xy 75.069673 -82.237768) (xy 75.026805 -82.273443) (xy 74.979199 -82.302497)
			(xy 74.92787 -82.324309) (xy 74.873913 -82.338415) (xy 74.818476 -82.344515) (xy 74.762742 -82.342478)
			(xy 74.707899 -82.332348) (xy 74.655115 -82.314341) (xy 74.605515 -82.28884) (xy 74.560157 -82.256389)
			(xy 74.520008 -82.21768) (xy 74.485922 -82.173537) (xy 74.458626 -82.124902) (xy 74.438703 -82.072811)
			(xy 74.426577 -82.018374) (xy 74.422506 -81.962752) (xy 74.014838 -81.962752) (xy 74.014329 -81.990638)
			(xy 74.006209 -82.045814) (xy 73.990141 -82.099221) (xy 73.966469 -82.149718) (xy 73.935696 -82.196231)
			(xy 73.898479 -82.237768) (xy 73.855611 -82.273443) (xy 73.808005 -82.302497) (xy 73.756676 -82.324309)
			(xy 73.702719 -82.338415) (xy 73.647282 -82.344515) (xy 73.591548 -82.342478) (xy 73.536705 -82.332348)
			(xy 73.483921 -82.314341) (xy 73.434321 -82.28884) (xy 73.388963 -82.256389) (xy 73.348814 -82.21768)
			(xy 73.314728 -82.173537) (xy 73.287432 -82.124902) (xy 73.267509 -82.072811) (xy 73.255383 -82.018374)
			(xy 73.251312 -81.962752) (xy 72.90181 -81.962752) (xy 72.901301 -81.990638) (xy 72.893181 -82.045814)
			(xy 72.877113 -82.099221) (xy 72.853441 -82.149718) (xy 72.822668 -82.196231) (xy 72.785451 -82.237768)
			(xy 72.742583 -82.273443) (xy 72.694977 -82.302497) (xy 72.643648 -82.324309) (xy 72.589691 -82.338415)
			(xy 72.534254 -82.344515) (xy 72.47852 -82.342478) (xy 72.423677 -82.332348) (xy 72.370893 -82.314341)
			(xy 72.321293 -82.28884) (xy 72.275935 -82.256389) (xy 72.235786 -82.21768) (xy 72.2017 -82.173537)
			(xy 72.174404 -82.124902) (xy 72.154481 -82.072811) (xy 72.142355 -82.018374) (xy 72.138284 -81.962752)
			(xy 71.774304 -81.962752) (xy 71.773795 -81.990638) (xy 71.765675 -82.045814) (xy 71.749607 -82.099221)
			(xy 71.725935 -82.149718) (xy 71.695162 -82.196231) (xy 71.657945 -82.237768) (xy 71.615077 -82.273443)
			(xy 71.567471 -82.302497) (xy 71.516142 -82.324309) (xy 71.462185 -82.338415) (xy 71.406748 -82.344515)
			(xy 71.351014 -82.342478) (xy 71.296171 -82.332348) (xy 71.243387 -82.314341) (xy 71.193787 -82.28884)
			(xy 71.148429 -82.256389) (xy 71.10828 -82.21768) (xy 71.074194 -82.173537) (xy 71.046898 -82.124902)
			(xy 71.026975 -82.072811) (xy 71.014849 -82.018374) (xy 71.010778 -81.962752) (xy 64.692784 -81.962752)
			(xy 56.116474 -90.539062) (xy 56.101473 -90.554673) (xy 56.076486 -90.590025) (xy 56.057857 -90.629104)
			(xy 56.046126 -90.670776) (xy 56.041634 -90.713834) (xy 56.044509 -90.75703) (xy 56.05467 -90.799112)
			(xy 56.071821 -90.838861) (xy 56.095466 -90.875125) (xy 56.124919 -90.906854) (xy 56.141874 -90.920316)
			(xy 76.74356 -90.920316) (xy 78.081632 -89.582244) (xy 88.039448 -89.582244) (xy 90.646504 -86.975442)
			(xy 90.657856 -86.963295) (xy 90.674452 -86.9345) (xy 90.683052 -86.902397) (xy 90.683588 -86.88578)
			(xy 90.683588 -85.124544) (xy 91.637612 -84.170266) (xy 91.637612 -82.638646) (xy 91.634818 -82.625438)
			(xy 91.629604 -82.598739) (xy 91.625904 -82.544466) (xy 91.629949 -82.490218) (xy 91.641659 -82.437094)
			(xy 91.660795 -82.386172) (xy 91.686969 -82.338484) (xy 91.719651 -82.294997) (xy 91.758178 -82.256592)
			(xy 91.801769 -82.224049) (xy 91.84954 -82.198026) (xy 91.900522 -82.179053) (xy 91.953683 -82.167513)
			(xy 92.007944 -82.16364) (xy 92.062205 -82.167513) (xy 92.115366 -82.179053) (xy 92.166348 -82.198026)
			(xy 92.214119 -82.224049) (xy 92.25771 -82.256592) (xy 92.296237 -82.294997) (xy 92.328919 -82.338484)
			(xy 92.355093 -82.386172) (xy 92.374229 -82.437094) (xy 92.385939 -82.490218) (xy 92.389984 -82.544466)
			(xy 92.386284 -82.598739) (xy 92.38107 -82.625438) (xy 92.378276 -82.638646) (xy 92.378276 -84.230718)
			(xy 92.38107 -84.243926) (xy 92.386254 -84.270264) (xy 92.390035 -84.323809) (xy 92.386252 -84.377354)
			(xy 92.38107 -84.403692) (xy 92.378276 -84.4169) (xy 92.378276 -84.477098) (xy 92.335604 -84.519516)
			(xy 92.328238 -84.530946) (xy 92.313238 -84.553296) (xy 92.277952 -84.593944) (xy 92.237305 -84.629231)
			(xy 92.214954 -84.64423) (xy 92.203524 -84.651596) (xy 91.423744 -85.431376) (xy 91.423744 -87.24519)
			(xy 88.34628 -90.322908) (xy 78.388464 -90.322908) (xy 77.050392 -91.66098) (xy 31.649162 -91.66098)
			(xy 31.122112 -92.187776) (xy 31.119767 -92.208768) (xy 31.121243 -92.250979) (xy 31.129667 -92.292368)
			(xy 31.14481 -92.331797) (xy 31.166256 -92.368184) (xy 31.179516 -92.384626) (xy 31.206509 -92.417481)
			(xy 31.255119 -92.487255) (xy 31.297233 -92.561132) (xy 31.332507 -92.638508) (xy 31.360652 -92.718753)
			(xy 31.381438 -92.801211) (xy 31.394698 -92.885208) (xy 31.40032 -92.970059) (xy 31.398787 -93.033358)
			(xy 34.599874 -93.033358) (xy 34.599874 -92.946458) (xy 34.607892 -92.859929) (xy 34.62386 -92.774509)
			(xy 34.647641 -92.690927) (xy 34.679033 -92.609895) (xy 34.717767 -92.532106) (xy 34.763514 -92.458222)
			(xy 34.815883 -92.388875) (xy 34.874427 -92.324655) (xy 34.938647 -92.266111) (xy 35.007994 -92.213742)
			(xy 35.081878 -92.167995) (xy 35.159667 -92.129261) (xy 35.240699 -92.097869) (xy 35.324281 -92.074088)
			(xy 35.409701 -92.05812) (xy 35.49623 -92.050102) (xy 35.58313 -92.050102) (xy 35.669659 -92.05812)
			(xy 35.755079 -92.074088) (xy 35.838661 -92.097869) (xy 35.919693 -92.129261) (xy 35.997482 -92.167995)
			(xy 36.071366 -92.213742) (xy 36.140713 -92.266111) (xy 36.204933 -92.324655) (xy 36.263477 -92.388875)
			(xy 36.315846 -92.458222) (xy 36.361593 -92.532106) (xy 36.400327 -92.609895) (xy 36.431719 -92.690927)
			(xy 36.4555 -92.774509) (xy 36.471468 -92.859929) (xy 36.479486 -92.946458) (xy 36.479988 -92.989908)
			(xy 36.479486 -93.033358) (xy 36.471468 -93.119887) (xy 36.4555 -93.205307) (xy 36.431719 -93.288889)
			(xy 36.400327 -93.369921) (xy 36.361593 -93.44771) (xy 36.315846 -93.521594) (xy 36.263477 -93.590941)
			(xy 36.204933 -93.655161) (xy 36.140713 -93.713705) (xy 36.071366 -93.766074) (xy 35.997482 -93.811821)
			(xy 35.919693 -93.850555) (xy 35.838661 -93.881947) (xy 35.755079 -93.905728) (xy 35.669659 -93.921696)
			(xy 35.58313 -93.929714) (xy 35.49623 -93.929714) (xy 35.409701 -93.921696) (xy 35.324281 -93.905728)
			(xy 35.240699 -93.881947) (xy 35.159667 -93.850555) (xy 35.081878 -93.811821) (xy 35.007994 -93.766074)
			(xy 34.938647 -93.713705) (xy 34.874427 -93.655161) (xy 34.815883 -93.590941) (xy 34.763514 -93.521594)
			(xy 34.717767 -93.44771) (xy 34.679033 -93.369921) (xy 34.647641 -93.288889) (xy 34.62386 -93.205307)
			(xy 34.607892 -93.119887) (xy 34.599874 -93.033358) (xy 31.398787 -93.033358) (xy 31.398261 -93.055072)
			(xy 31.388537 -93.139551) (xy 31.371227 -93.222808) (xy 31.346472 -93.304163) (xy 31.3309 -93.34373)
			(xy 31.31369 -93.384734) (xy 31.272598 -93.463605) (xy 31.224243 -93.538243) (xy 31.169055 -93.607981)
			(xy 31.107528 -93.672196) (xy 31.040212 -93.730314) (xy 31.004256 -93.75648) (xy 30.968256 -93.781438)
			(xy 30.892431 -93.825312) (xy 30.812853 -93.861943) (xy 30.730214 -93.891016) (xy 30.645229 -93.912277)
			(xy 30.558635 -93.925542) (xy 30.471183 -93.930697) (xy 30.383631 -93.927697) (xy 30.296737 -93.916567)
			(xy 30.211254 -93.897405) (xy 30.127924 -93.870376) (xy 30.047469 -93.835714) (xy 29.970586 -93.79372)
			(xy 29.897942 -93.744758) (xy 29.830166 -93.689253) (xy 29.767845 -93.627685) (xy 29.739336 -93.594428)
			(xy 29.724908 -93.577951) (xy 29.691421 -93.549729) (xy 29.653593 -93.527663) (xy 29.612543 -93.512407)
			(xy 29.569486 -93.504411) (xy 29.525695 -93.503911) (xy 29.482467 -93.510924) (xy 29.44108 -93.525241)
			(xy 29.402759 -93.546439) (xy 29.368638 -93.573891) (xy 29.339725 -93.606784) (xy 29.316878 -93.644144)
			(xy 29.300771 -93.684868) (xy 29.291881 -93.72775) (xy 29.290772 -93.749622) (xy 29.290772 -94.770194)
			(xy 29.291928 -94.792065) (xy 29.300806 -94.83495) (xy 29.316903 -94.875679) (xy 29.339743 -94.913045)
			(xy 29.368651 -94.945943) (xy 29.402769 -94.973399) (xy 29.441089 -94.9946) (xy 29.482477 -95.008919)
			(xy 29.525706 -95.015932) (xy 29.569497 -95.015431) (xy 29.612554 -95.007431) (xy 29.653603 -94.992169)
			(xy 29.691428 -94.970097) (xy 29.724909 -94.941867) (xy 29.739336 -94.925388) (xy 29.767591 -94.892491)
			(xy 29.82922 -94.831474) (xy 29.896204 -94.77639) (xy 29.967976 -94.727708) (xy 30.043926 -94.685841)
			(xy 30.123407 -94.651144) (xy 30.205746 -94.623913) (xy 30.290242 -94.604379) (xy 30.376178 -94.592708)
			(xy 30.462823 -94.588999) (xy 30.549442 -94.593283) (xy 30.635298 -94.605525) (xy 30.719663 -94.625619)
			(xy 30.801819 -94.653396) (xy 30.881069 -94.68862) (xy 30.956739 -94.73099) (xy 31.028186 -94.780148)
			(xy 31.094803 -94.835675) (xy 31.156025 -94.8971) (xy 31.211331 -94.963901) (xy 31.260252 -95.035511)
			(xy 31.302372 -95.111321) (xy 31.337332 -95.190686) (xy 31.364837 -95.272934) (xy 31.384652 -95.357365)
			(xy 31.396609 -95.443261) (xy 31.400606 -95.529894) (xy 31.398601 -95.573358) (xy 34.599874 -95.573358)
			(xy 34.599874 -95.486458) (xy 34.607892 -95.399929) (xy 34.62386 -95.314509) (xy 34.647641 -95.230927)
			(xy 34.679033 -95.149895) (xy 34.717767 -95.072106) (xy 34.763514 -94.998222) (xy 34.815883 -94.928875)
			(xy 34.874427 -94.864655) (xy 34.938647 -94.806111) (xy 35.007994 -94.753742) (xy 35.081878 -94.707995)
			(xy 35.159667 -94.669261) (xy 35.240699 -94.637869) (xy 35.324281 -94.614088) (xy 35.409701 -94.59812)
			(xy 35.49623 -94.590102) (xy 35.58313 -94.590102) (xy 35.669659 -94.59812) (xy 35.755079 -94.614088)
			(xy 35.838661 -94.637869) (xy 35.919693 -94.669261) (xy 35.997482 -94.707995) (xy 36.071366 -94.753742)
			(xy 36.140713 -94.806111) (xy 36.204933 -94.864655) (xy 36.263477 -94.928875) (xy 36.315846 -94.998222)
			(xy 36.361593 -95.072106) (xy 36.400327 -95.149895) (xy 36.431719 -95.230927) (xy 36.4555 -95.314509)
			(xy 36.471468 -95.399929) (xy 36.479486 -95.486458) (xy 36.479988 -95.529908) (xy 36.479486 -95.573358)
			(xy 36.471468 -95.659887) (xy 36.4555 -95.745307) (xy 36.437073 -95.81007) (xy 39.818564 -95.81007)
			(xy 39.819054 -95.752663) (xy 39.826889 -95.638117) (xy 39.842523 -95.524372) (xy 39.865882 -95.41196)
			(xy 39.896859 -95.301403) (xy 39.935308 -95.193218) (xy 39.98105 -95.08791) (xy 40.033872 -94.985968)
			(xy 40.093527 -94.887869) (xy 40.159738 -94.794069) (xy 40.232196 -94.705007) (xy 40.310562 -94.621096)
			(xy 40.394473 -94.54273) (xy 40.483535 -94.470272) (xy 40.577335 -94.404061) (xy 40.675434 -94.344406)
			(xy 40.777376 -94.291584) (xy 40.882684 -94.245842) (xy 40.990869 -94.207393) (xy 41.101426 -94.176416)
			(xy 41.213838 -94.153057) (xy 41.327583 -94.137423) (xy 41.442129 -94.129588) (xy 41.556943 -94.129588)
			(xy 41.671489 -94.137423) (xy 41.785234 -94.153057) (xy 41.897646 -94.176416) (xy 42.008203 -94.207393)
			(xy 42.116388 -94.245842) (xy 42.221696 -94.291584) (xy 42.323638 -94.344406) (xy 42.421737 -94.404061)
			(xy 42.50107 -94.46006) (xy 43.327577 -94.46006) (xy 43.331612 -94.384356) (xy 43.343671 -94.309511)
			(xy 43.363617 -94.23637) (xy 43.391224 -94.165765) (xy 43.42618 -94.098494) (xy 43.468088 -94.035319)
			(xy 43.516474 -93.976957) (xy 43.57079 -93.924069) (xy 43.630419 -93.877254) (xy 43.694687 -93.837042)
			(xy 43.762864 -93.80389) (xy 43.83418 -93.778172) (xy 43.907825 -93.76018) (xy 43.982965 -93.750118)
			(xy 44.058749 -93.748099) (xy 44.134319 -93.754148) (xy 44.208817 -93.768195) (xy 44.2814 -93.790081)
			(xy 44.351246 -93.819558) (xy 44.417563 -93.856293) (xy 44.479599 -93.899868) (xy 44.536652 -93.94979)
			(xy 44.588076 -94.005494) (xy 44.633287 -94.066349) (xy 44.671774 -94.131664) (xy 44.7031 -94.2007)
			(xy 44.72691 -94.272675) (xy 44.742935 -94.346773) (xy 44.750994 -94.422154) (xy 44.751498 -94.46006)
			(xy 45.867577 -94.46006) (xy 45.871612 -94.384356) (xy 45.883671 -94.309511) (xy 45.903617 -94.23637)
			(xy 45.931224 -94.165765) (xy 45.96618 -94.098494) (xy 46.008088 -94.035319) (xy 46.056474 -93.976957)
			(xy 46.11079 -93.924069) (xy 46.170419 -93.877254) (xy 46.234687 -93.837042) (xy 46.302864 -93.80389)
			(xy 46.37418 -93.778172) (xy 46.447825 -93.76018) (xy 46.522965 -93.750118) (xy 46.598749 -93.748099)
			(xy 46.674319 -93.754148) (xy 46.748817 -93.768195) (xy 46.8214 -93.790081) (xy 46.891246 -93.819558)
			(xy 46.957563 -93.856293) (xy 47.019599 -93.899868) (xy 47.076652 -93.94979) (xy 47.128076 -94.005494)
			(xy 47.173287 -94.066349) (xy 47.211774 -94.131664) (xy 47.2431 -94.2007) (xy 47.26691 -94.272675)
			(xy 47.282935 -94.346773) (xy 47.290994 -94.422154) (xy 47.291498 -94.46006) (xy 48.407577 -94.46006)
			(xy 48.411612 -94.384356) (xy 48.423671 -94.309511) (xy 48.443617 -94.23637) (xy 48.471224 -94.165765)
			(xy 48.50618 -94.098494) (xy 48.548088 -94.035319) (xy 48.596474 -93.976957) (xy 48.65079 -93.924069)
			(xy 48.710419 -93.877254) (xy 48.774687 -93.837042) (xy 48.842864 -93.80389) (xy 48.91418 -93.778172)
			(xy 48.987825 -93.76018) (xy 49.062965 -93.750118) (xy 49.138749 -93.748099) (xy 49.214319 -93.754148)
			(xy 49.288817 -93.768195) (xy 49.3614 -93.790081) (xy 49.431246 -93.819558) (xy 49.497563 -93.856293)
			(xy 49.559599 -93.899868) (xy 49.616652 -93.94979) (xy 49.668076 -94.005494) (xy 49.713287 -94.066349)
			(xy 49.751774 -94.131664) (xy 49.7831 -94.2007) (xy 49.80691 -94.272675) (xy 49.822935 -94.346773)
			(xy 49.830994 -94.422154) (xy 49.831498 -94.46006) (xy 50.947577 -94.46006) (xy 50.951612 -94.384356)
			(xy 50.963671 -94.309511) (xy 50.983617 -94.23637) (xy 51.011224 -94.165765) (xy 51.04618 -94.098494)
			(xy 51.088088 -94.035319) (xy 51.136474 -93.976957) (xy 51.19079 -93.924069) (xy 51.250419 -93.877254)
			(xy 51.314687 -93.837042) (xy 51.382864 -93.80389) (xy 51.45418 -93.778172) (xy 51.527825 -93.76018)
			(xy 51.602965 -93.750118) (xy 51.678749 -93.748099) (xy 51.754319 -93.754148) (xy 51.828817 -93.768195)
			(xy 51.9014 -93.790081) (xy 51.971246 -93.819558) (xy 52.037563 -93.856293) (xy 52.099599 -93.899868)
			(xy 52.156652 -93.94979) (xy 52.208076 -94.005494) (xy 52.253287 -94.066349) (xy 52.291774 -94.131664)
			(xy 52.3231 -94.2007) (xy 52.34691 -94.272675) (xy 52.362935 -94.346773) (xy 52.370994 -94.422154)
			(xy 52.371498 -94.46006) (xy 53.487577 -94.46006) (xy 53.491612 -94.384356) (xy 53.503671 -94.309511)
			(xy 53.523617 -94.23637) (xy 53.551224 -94.165765) (xy 53.58618 -94.098494) (xy 53.628088 -94.035319)
			(xy 53.676474 -93.976957) (xy 53.73079 -93.924069) (xy 53.790419 -93.877254) (xy 53.854687 -93.837042)
			(xy 53.922864 -93.80389) (xy 53.99418 -93.778172) (xy 54.067825 -93.76018) (xy 54.142965 -93.750118)
			(xy 54.218749 -93.748099) (xy 54.294319 -93.754148) (xy 54.368817 -93.768195) (xy 54.4414 -93.790081)
			(xy 54.511246 -93.819558) (xy 54.577563 -93.856293) (xy 54.639599 -93.899868) (xy 54.696652 -93.94979)
			(xy 54.748076 -94.005494) (xy 54.793287 -94.066349) (xy 54.831774 -94.131664) (xy 54.8631 -94.2007)
			(xy 54.88691 -94.272675) (xy 54.902935 -94.346773) (xy 54.910994 -94.422154) (xy 54.911498 -94.46006)
			(xy 56.027577 -94.46006) (xy 56.031612 -94.384356) (xy 56.043671 -94.309511) (xy 56.063617 -94.23637)
			(xy 56.091224 -94.165765) (xy 56.12618 -94.098494) (xy 56.168088 -94.035319) (xy 56.216474 -93.976957)
			(xy 56.27079 -93.924069) (xy 56.330419 -93.877254) (xy 56.394687 -93.837042) (xy 56.462864 -93.80389)
			(xy 56.53418 -93.778172) (xy 56.607825 -93.76018) (xy 56.682965 -93.750118) (xy 56.758749 -93.748099)
			(xy 56.834319 -93.754148) (xy 56.908817 -93.768195) (xy 56.9814 -93.790081) (xy 57.051246 -93.819558)
			(xy 57.117563 -93.856293) (xy 57.179599 -93.899868) (xy 57.236652 -93.94979) (xy 57.288076 -94.005494)
			(xy 57.333287 -94.066349) (xy 57.371774 -94.131664) (xy 57.4031 -94.2007) (xy 57.42691 -94.272675)
			(xy 57.442935 -94.346773) (xy 57.450994 -94.422154) (xy 57.451498 -94.46006) (xy 58.567577 -94.46006)
			(xy 58.571612 -94.384356) (xy 58.583671 -94.309511) (xy 58.603617 -94.23637) (xy 58.631224 -94.165765)
			(xy 58.66618 -94.098494) (xy 58.708088 -94.035319) (xy 58.756474 -93.976957) (xy 58.81079 -93.924069)
			(xy 58.870419 -93.877254) (xy 58.934687 -93.837042) (xy 59.002864 -93.80389) (xy 59.07418 -93.778172)
			(xy 59.147825 -93.76018) (xy 59.222965 -93.750118) (xy 59.298749 -93.748099) (xy 59.374319 -93.754148)
			(xy 59.448817 -93.768195) (xy 59.5214 -93.790081) (xy 59.591246 -93.819558) (xy 59.657563 -93.856293)
			(xy 59.719599 -93.899868) (xy 59.776652 -93.94979) (xy 59.828076 -94.005494) (xy 59.873287 -94.066349)
			(xy 59.911774 -94.131664) (xy 59.9431 -94.2007) (xy 59.96691 -94.272675) (xy 59.982935 -94.346773)
			(xy 59.990994 -94.422154) (xy 59.991498 -94.46006) (xy 61.107577 -94.46006) (xy 61.111612 -94.384356)
			(xy 61.123671 -94.309511) (xy 61.143617 -94.23637) (xy 61.171224 -94.165765) (xy 61.20618 -94.098494)
			(xy 61.248088 -94.035319) (xy 61.296474 -93.976957) (xy 61.35079 -93.924069) (xy 61.410419 -93.877254)
			(xy 61.474687 -93.837042) (xy 61.542864 -93.80389) (xy 61.61418 -93.778172) (xy 61.687825 -93.76018)
			(xy 61.762965 -93.750118) (xy 61.838749 -93.748099) (xy 61.914319 -93.754148) (xy 61.988817 -93.768195)
			(xy 62.0614 -93.790081) (xy 62.131246 -93.819558) (xy 62.197563 -93.856293) (xy 62.259599 -93.899868)
			(xy 62.316652 -93.94979) (xy 62.368076 -94.005494) (xy 62.413287 -94.066349) (xy 62.451774 -94.131664)
			(xy 62.4831 -94.2007) (xy 62.50691 -94.272675) (xy 62.522935 -94.346773) (xy 62.530994 -94.422154)
			(xy 62.531498 -94.46006) (xy 62.530994 -94.497966) (xy 62.522935 -94.573347) (xy 62.50691 -94.647445)
			(xy 62.4831 -94.71942) (xy 62.451774 -94.788456) (xy 62.413287 -94.853771) (xy 62.368076 -94.914626)
			(xy 62.316652 -94.97033) (xy 62.259599 -95.020252) (xy 62.197563 -95.063827) (xy 62.131246 -95.100562)
			(xy 62.0614 -95.130039) (xy 61.988817 -95.151925) (xy 61.914319 -95.165972) (xy 61.838749 -95.172021)
			(xy 61.762965 -95.170002) (xy 61.687825 -95.15994) (xy 61.61418 -95.141948) (xy 61.542864 -95.11623)
			(xy 61.474687 -95.083078) (xy 61.410419 -95.042866) (xy 61.35079 -94.996051) (xy 61.296474 -94.943163)
			(xy 61.248088 -94.884801) (xy 61.20618 -94.821626) (xy 61.171224 -94.754355) (xy 61.143617 -94.68375)
			(xy 61.123671 -94.610609) (xy 61.111612 -94.535764) (xy 61.107577 -94.46006) (xy 59.991498 -94.46006)
			(xy 59.990994 -94.497966) (xy 59.982935 -94.573347) (xy 59.96691 -94.647445) (xy 59.9431 -94.71942)
			(xy 59.911774 -94.788456) (xy 59.873287 -94.853771) (xy 59.828076 -94.914626) (xy 59.776652 -94.97033)
			(xy 59.719599 -95.020252) (xy 59.657563 -95.063827) (xy 59.591246 -95.100562) (xy 59.5214 -95.130039)
			(xy 59.448817 -95.151925) (xy 59.374319 -95.165972) (xy 59.298749 -95.172021) (xy 59.222965 -95.170002)
			(xy 59.147825 -95.15994) (xy 59.07418 -95.141948) (xy 59.002864 -95.11623) (xy 58.934687 -95.083078)
			(xy 58.870419 -95.042866) (xy 58.81079 -94.996051) (xy 58.756474 -94.943163) (xy 58.708088 -94.884801)
			(xy 58.66618 -94.821626) (xy 58.631224 -94.754355) (xy 58.603617 -94.68375) (xy 58.583671 -94.610609)
			(xy 58.571612 -94.535764) (xy 58.567577 -94.46006) (xy 57.451498 -94.46006) (xy 57.450994 -94.497966)
			(xy 57.442935 -94.573347) (xy 57.42691 -94.647445) (xy 57.4031 -94.71942) (xy 57.371774 -94.788456)
			(xy 57.333287 -94.853771) (xy 57.288076 -94.914626) (xy 57.236652 -94.97033) (xy 57.179599 -95.020252)
			(xy 57.117563 -95.063827) (xy 57.051246 -95.100562) (xy 56.9814 -95.130039) (xy 56.908817 -95.151925)
			(xy 56.834319 -95.165972) (xy 56.758749 -95.172021) (xy 56.682965 -95.170002) (xy 56.607825 -95.15994)
			(xy 56.53418 -95.141948) (xy 56.462864 -95.11623) (xy 56.394687 -95.083078) (xy 56.330419 -95.042866)
			(xy 56.27079 -94.996051) (xy 56.216474 -94.943163) (xy 56.168088 -94.884801) (xy 56.12618 -94.821626)
			(xy 56.091224 -94.754355) (xy 56.063617 -94.68375) (xy 56.043671 -94.610609) (xy 56.031612 -94.535764)
			(xy 56.027577 -94.46006) (xy 54.911498 -94.46006) (xy 54.910994 -94.497966) (xy 54.902935 -94.573347)
			(xy 54.88691 -94.647445) (xy 54.8631 -94.71942) (xy 54.831774 -94.788456) (xy 54.793287 -94.853771)
			(xy 54.748076 -94.914626) (xy 54.696652 -94.97033) (xy 54.639599 -95.020252) (xy 54.577563 -95.063827)
			(xy 54.511246 -95.100562) (xy 54.4414 -95.130039) (xy 54.368817 -95.151925) (xy 54.294319 -95.165972)
			(xy 54.218749 -95.172021) (xy 54.142965 -95.170002) (xy 54.067825 -95.15994) (xy 53.99418 -95.141948)
			(xy 53.922864 -95.11623) (xy 53.854687 -95.083078) (xy 53.790419 -95.042866) (xy 53.73079 -94.996051)
			(xy 53.676474 -94.943163) (xy 53.628088 -94.884801) (xy 53.58618 -94.821626) (xy 53.551224 -94.754355)
			(xy 53.523617 -94.68375) (xy 53.503671 -94.610609) (xy 53.491612 -94.535764) (xy 53.487577 -94.46006)
			(xy 52.371498 -94.46006) (xy 52.370994 -94.497966) (xy 52.362935 -94.573347) (xy 52.34691 -94.647445)
			(xy 52.3231 -94.71942) (xy 52.291774 -94.788456) (xy 52.253287 -94.853771) (xy 52.208076 -94.914626)
			(xy 52.156652 -94.97033) (xy 52.099599 -95.020252) (xy 52.037563 -95.063827) (xy 51.971246 -95.100562)
			(xy 51.9014 -95.130039) (xy 51.828817 -95.151925) (xy 51.754319 -95.165972) (xy 51.678749 -95.172021)
			(xy 51.602965 -95.170002) (xy 51.527825 -95.15994) (xy 51.45418 -95.141948) (xy 51.382864 -95.11623)
			(xy 51.314687 -95.083078) (xy 51.250419 -95.042866) (xy 51.19079 -94.996051) (xy 51.136474 -94.943163)
			(xy 51.088088 -94.884801) (xy 51.04618 -94.821626) (xy 51.011224 -94.754355) (xy 50.983617 -94.68375)
			(xy 50.963671 -94.610609) (xy 50.951612 -94.535764) (xy 50.947577 -94.46006) (xy 49.831498 -94.46006)
			(xy 49.830994 -94.497966) (xy 49.822935 -94.573347) (xy 49.80691 -94.647445) (xy 49.7831 -94.71942)
			(xy 49.751774 -94.788456) (xy 49.713287 -94.853771) (xy 49.668076 -94.914626) (xy 49.616652 -94.97033)
			(xy 49.559599 -95.020252) (xy 49.497563 -95.063827) (xy 49.431246 -95.100562) (xy 49.3614 -95.130039)
			(xy 49.288817 -95.151925) (xy 49.214319 -95.165972) (xy 49.138749 -95.172021) (xy 49.062965 -95.170002)
			(xy 48.987825 -95.15994) (xy 48.91418 -95.141948) (xy 48.842864 -95.11623) (xy 48.774687 -95.083078)
			(xy 48.710419 -95.042866) (xy 48.65079 -94.996051) (xy 48.596474 -94.943163) (xy 48.548088 -94.884801)
			(xy 48.50618 -94.821626) (xy 48.471224 -94.754355) (xy 48.443617 -94.68375) (xy 48.423671 -94.610609)
			(xy 48.411612 -94.535764) (xy 48.407577 -94.46006) (xy 47.291498 -94.46006) (xy 47.290994 -94.497966)
			(xy 47.282935 -94.573347) (xy 47.26691 -94.647445) (xy 47.2431 -94.71942) (xy 47.211774 -94.788456)
			(xy 47.173287 -94.853771) (xy 47.128076 -94.914626) (xy 47.076652 -94.97033) (xy 47.019599 -95.020252)
			(xy 46.957563 -95.063827) (xy 46.891246 -95.100562) (xy 46.8214 -95.130039) (xy 46.748817 -95.151925)
			(xy 46.674319 -95.165972) (xy 46.598749 -95.172021) (xy 46.522965 -95.170002) (xy 46.447825 -95.15994)
			(xy 46.37418 -95.141948) (xy 46.302864 -95.11623) (xy 46.234687 -95.083078) (xy 46.170419 -95.042866)
			(xy 46.11079 -94.996051) (xy 46.056474 -94.943163) (xy 46.008088 -94.884801) (xy 45.96618 -94.821626)
			(xy 45.931224 -94.754355) (xy 45.903617 -94.68375) (xy 45.883671 -94.610609) (xy 45.871612 -94.535764)
			(xy 45.867577 -94.46006) (xy 44.751498 -94.46006) (xy 44.750994 -94.497966) (xy 44.742935 -94.573347)
			(xy 44.72691 -94.647445) (xy 44.7031 -94.71942) (xy 44.671774 -94.788456) (xy 44.633287 -94.853771)
			(xy 44.588076 -94.914626) (xy 44.536652 -94.97033) (xy 44.479599 -95.020252) (xy 44.417563 -95.063827)
			(xy 44.351246 -95.100562) (xy 44.2814 -95.130039) (xy 44.208817 -95.151925) (xy 44.134319 -95.165972)
			(xy 44.058749 -95.172021) (xy 43.982965 -95.170002) (xy 43.907825 -95.15994) (xy 43.83418 -95.141948)
			(xy 43.762864 -95.11623) (xy 43.694687 -95.083078) (xy 43.630419 -95.042866) (xy 43.57079 -94.996051)
			(xy 43.516474 -94.943163) (xy 43.468088 -94.884801) (xy 43.42618 -94.821626) (xy 43.391224 -94.754355)
			(xy 43.363617 -94.68375) (xy 43.343671 -94.610609) (xy 43.331612 -94.535764) (xy 43.327577 -94.46006)
			(xy 42.50107 -94.46006) (xy 42.515537 -94.470272) (xy 42.604599 -94.54273) (xy 42.68851 -94.621096)
			(xy 42.766876 -94.705007) (xy 42.839334 -94.794069) (xy 42.905545 -94.887869) (xy 42.9652 -94.985968)
			(xy 43.018022 -95.08791) (xy 43.063764 -95.193218) (xy 43.102213 -95.301403) (xy 43.13319 -95.41196)
			(xy 43.156549 -95.524372) (xy 43.172183 -95.638117) (xy 43.180018 -95.752663) (xy 43.180508 -95.81007)
			(xy 43.180381 -95.843251) (xy 43.177842 -95.909565) (xy 43.175428 -95.942658) (xy 43.170272 -96.000942)
			(xy 43.152948 -96.116671) (xy 43.127616 -96.230914) (xy 43.094401 -96.343119) (xy 43.053462 -96.452742)
			(xy 43.004999 -96.559253) (xy 42.949245 -96.662135) (xy 42.886471 -96.760891) (xy 42.816981 -96.855042)
			(xy 42.741111 -96.944132) (xy 42.659229 -97.027729) (xy 42.571732 -97.10543) (xy 42.500813 -97.16008)
			(xy 43.327577 -97.16008) (xy 43.331612 -97.084376) (xy 43.343671 -97.009531) (xy 43.363617 -96.93639)
			(xy 43.391224 -96.865785) (xy 43.42618 -96.798514) (xy 43.468088 -96.735339) (xy 43.516474 -96.676977)
			(xy 43.57079 -96.624089) (xy 43.630419 -96.577274) (xy 43.694687 -96.537062) (xy 43.762864 -96.50391)
			(xy 43.83418 -96.478192) (xy 43.907825 -96.4602) (xy 43.982965 -96.450138) (xy 44.058749 -96.448119)
			(xy 44.134319 -96.454168) (xy 44.208817 -96.468215) (xy 44.2814 -96.490101) (xy 44.351246 -96.519578)
			(xy 44.417563 -96.556313) (xy 44.479599 -96.599888) (xy 44.536652 -96.64981) (xy 44.588076 -96.705514)
			(xy 44.633287 -96.766369) (xy 44.671774 -96.831684) (xy 44.7031 -96.90072) (xy 44.72691 -96.972695)
			(xy 44.742935 -97.046793) (xy 44.750994 -97.122174) (xy 44.751498 -97.16008) (xy 45.867577 -97.16008)
			(xy 45.871612 -97.084376) (xy 45.883671 -97.009531) (xy 45.903617 -96.93639) (xy 45.931224 -96.865785)
			(xy 45.96618 -96.798514) (xy 46.008088 -96.735339) (xy 46.056474 -96.676977) (xy 46.11079 -96.624089)
			(xy 46.170419 -96.577274) (xy 46.234687 -96.537062) (xy 46.302864 -96.50391) (xy 46.37418 -96.478192)
			(xy 46.447825 -96.4602) (xy 46.522965 -96.450138) (xy 46.598749 -96.448119) (xy 46.674319 -96.454168)
			(xy 46.748817 -96.468215) (xy 46.8214 -96.490101) (xy 46.891246 -96.519578) (xy 46.957563 -96.556313)
			(xy 47.019599 -96.599888) (xy 47.076652 -96.64981) (xy 47.128076 -96.705514) (xy 47.173287 -96.766369)
			(xy 47.211774 -96.831684) (xy 47.2431 -96.90072) (xy 47.26691 -96.972695) (xy 47.282935 -97.046793)
			(xy 47.290994 -97.122174) (xy 47.291498 -97.16008) (xy 48.407577 -97.16008) (xy 48.411612 -97.084376)
			(xy 48.423671 -97.009531) (xy 48.443617 -96.93639) (xy 48.471224 -96.865785) (xy 48.50618 -96.798514)
			(xy 48.548088 -96.735339) (xy 48.596474 -96.676977) (xy 48.65079 -96.624089) (xy 48.710419 -96.577274)
			(xy 48.774687 -96.537062) (xy 48.842864 -96.50391) (xy 48.91418 -96.478192) (xy 48.987825 -96.4602)
			(xy 49.062965 -96.450138) (xy 49.138749 -96.448119) (xy 49.214319 -96.454168) (xy 49.288817 -96.468215)
			(xy 49.3614 -96.490101) (xy 49.431246 -96.519578) (xy 49.497563 -96.556313) (xy 49.559599 -96.599888)
			(xy 49.616652 -96.64981) (xy 49.668076 -96.705514) (xy 49.713287 -96.766369) (xy 49.751774 -96.831684)
			(xy 49.7831 -96.90072) (xy 49.80691 -96.972695) (xy 49.822935 -97.046793) (xy 49.830994 -97.122174)
			(xy 49.831498 -97.16008) (xy 50.947577 -97.16008) (xy 50.951612 -97.084376) (xy 50.963671 -97.009531)
			(xy 50.983617 -96.93639) (xy 51.011224 -96.865785) (xy 51.04618 -96.798514) (xy 51.088088 -96.735339)
			(xy 51.136474 -96.676977) (xy 51.19079 -96.624089) (xy 51.250419 -96.577274) (xy 51.314687 -96.537062)
			(xy 51.382864 -96.50391) (xy 51.45418 -96.478192) (xy 51.527825 -96.4602) (xy 51.602965 -96.450138)
			(xy 51.678749 -96.448119) (xy 51.754319 -96.454168) (xy 51.828817 -96.468215) (xy 51.9014 -96.490101)
			(xy 51.971246 -96.519578) (xy 52.037563 -96.556313) (xy 52.099599 -96.599888) (xy 52.156652 -96.64981)
			(xy 52.208076 -96.705514) (xy 52.253287 -96.766369) (xy 52.291774 -96.831684) (xy 52.3231 -96.90072)
			(xy 52.34691 -96.972695) (xy 52.362935 -97.046793) (xy 52.370994 -97.122174) (xy 52.371498 -97.16008)
			(xy 53.487577 -97.16008) (xy 53.491612 -97.084376) (xy 53.503671 -97.009531) (xy 53.523617 -96.93639)
			(xy 53.551224 -96.865785) (xy 53.58618 -96.798514) (xy 53.628088 -96.735339) (xy 53.676474 -96.676977)
			(xy 53.73079 -96.624089) (xy 53.790419 -96.577274) (xy 53.854687 -96.537062) (xy 53.922864 -96.50391)
			(xy 53.99418 -96.478192) (xy 54.067825 -96.4602) (xy 54.142965 -96.450138) (xy 54.218749 -96.448119)
			(xy 54.294319 -96.454168) (xy 54.368817 -96.468215) (xy 54.4414 -96.490101) (xy 54.511246 -96.519578)
			(xy 54.577563 -96.556313) (xy 54.639599 -96.599888) (xy 54.696652 -96.64981) (xy 54.748076 -96.705514)
			(xy 54.793287 -96.766369) (xy 54.831774 -96.831684) (xy 54.8631 -96.90072) (xy 54.88691 -96.972695)
			(xy 54.902935 -97.046793) (xy 54.910994 -97.122174) (xy 54.911498 -97.16008) (xy 56.027577 -97.16008)
			(xy 56.031612 -97.084376) (xy 56.043671 -97.009531) (xy 56.063617 -96.93639) (xy 56.091224 -96.865785)
			(xy 56.12618 -96.798514) (xy 56.168088 -96.735339) (xy 56.216474 -96.676977) (xy 56.27079 -96.624089)
			(xy 56.330419 -96.577274) (xy 56.394687 -96.537062) (xy 56.462864 -96.50391) (xy 56.53418 -96.478192)
			(xy 56.607825 -96.4602) (xy 56.682965 -96.450138) (xy 56.758749 -96.448119) (xy 56.834319 -96.454168)
			(xy 56.908817 -96.468215) (xy 56.9814 -96.490101) (xy 57.051246 -96.519578) (xy 57.117563 -96.556313)
			(xy 57.179599 -96.599888) (xy 57.236652 -96.64981) (xy 57.288076 -96.705514) (xy 57.333287 -96.766369)
			(xy 57.371774 -96.831684) (xy 57.4031 -96.90072) (xy 57.42691 -96.972695) (xy 57.442935 -97.046793)
			(xy 57.450994 -97.122174) (xy 57.451498 -97.16008) (xy 58.567577 -97.16008) (xy 58.571612 -97.084376)
			(xy 58.583671 -97.009531) (xy 58.603617 -96.93639) (xy 58.631224 -96.865785) (xy 58.66618 -96.798514)
			(xy 58.708088 -96.735339) (xy 58.756474 -96.676977) (xy 58.81079 -96.624089) (xy 58.870419 -96.577274)
			(xy 58.934687 -96.537062) (xy 59.002864 -96.50391) (xy 59.07418 -96.478192) (xy 59.147825 -96.4602)
			(xy 59.222965 -96.450138) (xy 59.298749 -96.448119) (xy 59.374319 -96.454168) (xy 59.448817 -96.468215)
			(xy 59.5214 -96.490101) (xy 59.591246 -96.519578) (xy 59.657563 -96.556313) (xy 59.719599 -96.599888)
			(xy 59.776652 -96.64981) (xy 59.828076 -96.705514) (xy 59.873287 -96.766369) (xy 59.911774 -96.831684)
			(xy 59.9431 -96.90072) (xy 59.96691 -96.972695) (xy 59.982935 -97.046793) (xy 59.990994 -97.122174)
			(xy 59.991498 -97.16008) (xy 61.107577 -97.16008) (xy 61.111612 -97.084376) (xy 61.123671 -97.009531)
			(xy 61.143617 -96.93639) (xy 61.171224 -96.865785) (xy 61.20618 -96.798514) (xy 61.248088 -96.735339)
			(xy 61.296474 -96.676977) (xy 61.35079 -96.624089) (xy 61.410419 -96.577274) (xy 61.474687 -96.537062)
			(xy 61.542864 -96.50391) (xy 61.61418 -96.478192) (xy 61.687825 -96.4602) (xy 61.762965 -96.450138)
			(xy 61.838749 -96.448119) (xy 61.914319 -96.454168) (xy 61.988817 -96.468215) (xy 62.0614 -96.490101)
			(xy 62.131246 -96.519578) (xy 62.197563 -96.556313) (xy 62.259599 -96.599888) (xy 62.316652 -96.64981)
			(xy 62.368076 -96.705514) (xy 62.413287 -96.766369) (xy 62.451774 -96.831684) (xy 62.4831 -96.90072)
			(xy 62.50691 -96.972695) (xy 62.522935 -97.046793) (xy 62.530994 -97.122174) (xy 62.531498 -97.16008)
			(xy 62.530994 -97.197986) (xy 62.522935 -97.273367) (xy 62.50691 -97.347465) (xy 62.4831 -97.41944)
			(xy 62.451774 -97.488476) (xy 62.413287 -97.553791) (xy 62.368076 -97.614646) (xy 62.316652 -97.67035)
			(xy 62.259599 -97.720272) (xy 62.197563 -97.763847) (xy 62.131246 -97.800582) (xy 62.0614 -97.830059)
			(xy 61.988817 -97.851945) (xy 61.914319 -97.865992) (xy 61.838749 -97.872041) (xy 61.762965 -97.870022)
			(xy 61.687825 -97.85996) (xy 61.61418 -97.841968) (xy 61.542864 -97.81625) (xy 61.474687 -97.783098)
			(xy 61.410419 -97.742886) (xy 61.35079 -97.696071) (xy 61.296474 -97.643183) (xy 61.248088 -97.584821)
			(xy 61.20618 -97.521646) (xy 61.171224 -97.454375) (xy 61.143617 -97.38377) (xy 61.123671 -97.310629)
			(xy 61.111612 -97.235784) (xy 61.107577 -97.16008) (xy 59.991498 -97.16008) (xy 59.990994 -97.197986)
			(xy 59.982935 -97.273367) (xy 59.96691 -97.347465) (xy 59.9431 -97.41944) (xy 59.911774 -97.488476)
			(xy 59.873287 -97.553791) (xy 59.828076 -97.614646) (xy 59.776652 -97.67035) (xy 59.719599 -97.720272)
			(xy 59.657563 -97.763847) (xy 59.591246 -97.800582) (xy 59.5214 -97.830059) (xy 59.448817 -97.851945)
			(xy 59.374319 -97.865992) (xy 59.298749 -97.872041) (xy 59.222965 -97.870022) (xy 59.147825 -97.85996)
			(xy 59.07418 -97.841968) (xy 59.002864 -97.81625) (xy 58.934687 -97.783098) (xy 58.870419 -97.742886)
			(xy 58.81079 -97.696071) (xy 58.756474 -97.643183) (xy 58.708088 -97.584821) (xy 58.66618 -97.521646)
			(xy 58.631224 -97.454375) (xy 58.603617 -97.38377) (xy 58.583671 -97.310629) (xy 58.571612 -97.235784)
			(xy 58.567577 -97.16008) (xy 57.451498 -97.16008) (xy 57.450994 -97.197986) (xy 57.442935 -97.273367)
			(xy 57.42691 -97.347465) (xy 57.4031 -97.41944) (xy 57.371774 -97.488476) (xy 57.333287 -97.553791)
			(xy 57.288076 -97.614646) (xy 57.236652 -97.67035) (xy 57.179599 -97.720272) (xy 57.117563 -97.763847)
			(xy 57.051246 -97.800582) (xy 56.9814 -97.830059) (xy 56.908817 -97.851945) (xy 56.834319 -97.865992)
			(xy 56.758749 -97.872041) (xy 56.682965 -97.870022) (xy 56.607825 -97.85996) (xy 56.53418 -97.841968)
			(xy 56.462864 -97.81625) (xy 56.394687 -97.783098) (xy 56.330419 -97.742886) (xy 56.27079 -97.696071)
			(xy 56.216474 -97.643183) (xy 56.168088 -97.584821) (xy 56.12618 -97.521646) (xy 56.091224 -97.454375)
			(xy 56.063617 -97.38377) (xy 56.043671 -97.310629) (xy 56.031612 -97.235784) (xy 56.027577 -97.16008)
			(xy 54.911498 -97.16008) (xy 54.910994 -97.197986) (xy 54.902935 -97.273367) (xy 54.88691 -97.347465)
			(xy 54.8631 -97.41944) (xy 54.831774 -97.488476) (xy 54.793287 -97.553791) (xy 54.748076 -97.614646)
			(xy 54.696652 -97.67035) (xy 54.639599 -97.720272) (xy 54.577563 -97.763847) (xy 54.511246 -97.800582)
			(xy 54.4414 -97.830059) (xy 54.368817 -97.851945) (xy 54.294319 -97.865992) (xy 54.218749 -97.872041)
			(xy 54.142965 -97.870022) (xy 54.067825 -97.85996) (xy 53.99418 -97.841968) (xy 53.922864 -97.81625)
			(xy 53.854687 -97.783098) (xy 53.790419 -97.742886) (xy 53.73079 -97.696071) (xy 53.676474 -97.643183)
			(xy 53.628088 -97.584821) (xy 53.58618 -97.521646) (xy 53.551224 -97.454375) (xy 53.523617 -97.38377)
			(xy 53.503671 -97.310629) (xy 53.491612 -97.235784) (xy 53.487577 -97.16008) (xy 52.371498 -97.16008)
			(xy 52.370994 -97.197986) (xy 52.362935 -97.273367) (xy 52.34691 -97.347465) (xy 52.3231 -97.41944)
			(xy 52.291774 -97.488476) (xy 52.253287 -97.553791) (xy 52.208076 -97.614646) (xy 52.156652 -97.67035)
			(xy 52.099599 -97.720272) (xy 52.037563 -97.763847) (xy 51.971246 -97.800582) (xy 51.9014 -97.830059)
			(xy 51.828817 -97.851945) (xy 51.754319 -97.865992) (xy 51.678749 -97.872041) (xy 51.602965 -97.870022)
			(xy 51.527825 -97.85996) (xy 51.45418 -97.841968) (xy 51.382864 -97.81625) (xy 51.314687 -97.783098)
			(xy 51.250419 -97.742886) (xy 51.19079 -97.696071) (xy 51.136474 -97.643183) (xy 51.088088 -97.584821)
			(xy 51.04618 -97.521646) (xy 51.011224 -97.454375) (xy 50.983617 -97.38377) (xy 50.963671 -97.310629)
			(xy 50.951612 -97.235784) (xy 50.947577 -97.16008) (xy 49.831498 -97.16008) (xy 49.830994 -97.197986)
			(xy 49.822935 -97.273367) (xy 49.80691 -97.347465) (xy 49.7831 -97.41944) (xy 49.751774 -97.488476)
			(xy 49.713287 -97.553791) (xy 49.668076 -97.614646) (xy 49.616652 -97.67035) (xy 49.559599 -97.720272)
			(xy 49.497563 -97.763847) (xy 49.431246 -97.800582) (xy 49.3614 -97.830059) (xy 49.288817 -97.851945)
			(xy 49.214319 -97.865992) (xy 49.138749 -97.872041) (xy 49.062965 -97.870022) (xy 48.987825 -97.85996)
			(xy 48.91418 -97.841968) (xy 48.842864 -97.81625) (xy 48.774687 -97.783098) (xy 48.710419 -97.742886)
			(xy 48.65079 -97.696071) (xy 48.596474 -97.643183) (xy 48.548088 -97.584821) (xy 48.50618 -97.521646)
			(xy 48.471224 -97.454375) (xy 48.443617 -97.38377) (xy 48.423671 -97.310629) (xy 48.411612 -97.235784)
			(xy 48.407577 -97.16008) (xy 47.291498 -97.16008) (xy 47.290994 -97.197986) (xy 47.282935 -97.273367)
			(xy 47.26691 -97.347465) (xy 47.2431 -97.41944) (xy 47.211774 -97.488476) (xy 47.173287 -97.553791)
			(xy 47.128076 -97.614646) (xy 47.076652 -97.67035) (xy 47.019599 -97.720272) (xy 46.957563 -97.763847)
			(xy 46.891246 -97.800582) (xy 46.8214 -97.830059) (xy 46.748817 -97.851945) (xy 46.674319 -97.865992)
			(xy 46.598749 -97.872041) (xy 46.522965 -97.870022) (xy 46.447825 -97.85996) (xy 46.37418 -97.841968)
			(xy 46.302864 -97.81625) (xy 46.234687 -97.783098) (xy 46.170419 -97.742886) (xy 46.11079 -97.696071)
			(xy 46.056474 -97.643183) (xy 46.008088 -97.584821) (xy 45.96618 -97.521646) (xy 45.931224 -97.454375)
			(xy 45.903617 -97.38377) (xy 45.883671 -97.310629) (xy 45.871612 -97.235784) (xy 45.867577 -97.16008)
			(xy 44.751498 -97.16008) (xy 44.750994 -97.197986) (xy 44.742935 -97.273367) (xy 44.72691 -97.347465)
			(xy 44.7031 -97.41944) (xy 44.671774 -97.488476) (xy 44.633287 -97.553791) (xy 44.588076 -97.614646)
			(xy 44.536652 -97.67035) (xy 44.479599 -97.720272) (xy 44.417563 -97.763847) (xy 44.351246 -97.800582)
			(xy 44.2814 -97.830059) (xy 44.208817 -97.851945) (xy 44.134319 -97.865992) (xy 44.058749 -97.872041)
			(xy 43.982965 -97.870022) (xy 43.907825 -97.85996) (xy 43.83418 -97.841968) (xy 43.762864 -97.81625)
			(xy 43.694687 -97.783098) (xy 43.630419 -97.742886) (xy 43.57079 -97.696071) (xy 43.516474 -97.643183)
			(xy 43.468088 -97.584821) (xy 43.42618 -97.521646) (xy 43.391224 -97.454375) (xy 43.363617 -97.38377)
			(xy 43.343671 -97.310629) (xy 43.331612 -97.235784) (xy 43.327577 -97.16008) (xy 42.500813 -97.16008)
			(xy 42.479042 -97.176857) (xy 42.381609 -97.241665) (xy 42.279905 -97.29954) (xy 42.174422 -97.350202)
			(xy 42.065671 -97.393404) (xy 41.954179 -97.428939) (xy 41.840485 -97.456634) (xy 41.725141 -97.476354)
			(xy 41.608704 -97.488005) (xy 41.491739 -97.49153) (xy 41.374812 -97.486912) (xy 41.258489 -97.474173)
			(xy 41.143334 -97.453375) (xy 41.029905 -97.424618) (xy 40.91875 -97.388042) (xy 40.810407 -97.343825)
			(xy 40.705403 -97.292179) (xy 40.604244 -97.233356) (xy 40.507421 -97.16764) (xy 40.415403 -97.095349)
			(xy 40.328636 -97.016834) (xy 40.247539 -96.932474) (xy 40.172506 -96.842679) (xy 40.103899 -96.747883)
			(xy 40.042051 -96.648544) (xy 39.987262 -96.545145) (xy 39.939796 -96.438186) (xy 39.899884 -96.328185)
			(xy 39.86772 -96.215674) (xy 39.843457 -96.101199) (xy 39.827215 -95.985313) (xy 39.819072 -95.868579)
			(xy 39.818564 -95.81007) (xy 36.437073 -95.81007) (xy 36.431719 -95.828889) (xy 36.400327 -95.909921)
			(xy 36.361593 -95.98771) (xy 36.315846 -96.061594) (xy 36.263477 -96.130941) (xy 36.204933 -96.195161)
			(xy 36.140713 -96.253705) (xy 36.071366 -96.306074) (xy 35.997482 -96.351821) (xy 35.919693 -96.390555)
			(xy 35.838661 -96.421947) (xy 35.755079 -96.445728) (xy 35.669659 -96.461696) (xy 35.58313 -96.469714)
			(xy 35.49623 -96.469714) (xy 35.409701 -96.461696) (xy 35.324281 -96.445728) (xy 35.240699 -96.421947)
			(xy 35.159667 -96.390555) (xy 35.081878 -96.351821) (xy 35.007994 -96.306074) (xy 34.938647 -96.253705)
			(xy 34.874427 -96.195161) (xy 34.815883 -96.130941) (xy 34.763514 -96.061594) (xy 34.717767 -95.98771)
			(xy 34.679033 -95.909921) (xy 34.647641 -95.828889) (xy 34.62386 -95.745307) (xy 34.607892 -95.659887)
			(xy 34.599874 -95.573358) (xy 31.398601 -95.573358) (xy 31.39661 -95.616526) (xy 31.384654 -95.702423)
			(xy 31.36484 -95.786854) (xy 31.337337 -95.869102) (xy 31.302377 -95.948468) (xy 31.260259 -96.024279)
			(xy 31.211339 -96.095889) (xy 31.156033 -96.162691) (xy 31.094812 -96.224117) (xy 31.028195 -96.279645)
			(xy 30.956749 -96.328803) (xy 30.88108 -96.371175) (xy 30.801831 -96.406399) (xy 30.719675 -96.434177)
			(xy 30.635311 -96.454273) (xy 30.549454 -96.466515) (xy 30.462835 -96.470801) (xy 30.37619 -96.467093)
			(xy 30.290254 -96.455423) (xy 30.205758 -96.43589) (xy 30.123419 -96.40866) (xy 30.043937 -96.373965)
			(xy 29.967987 -96.332098) (xy 29.896214 -96.283417) (xy 29.829229 -96.228334) (xy 29.767599 -96.167318)
			(xy 29.739336 -96.134428) (xy 29.724908 -96.117951) (xy 29.691421 -96.089729) (xy 29.653593 -96.067663)
			(xy 29.612543 -96.052407) (xy 29.569486 -96.044411) (xy 29.525695 -96.043911) (xy 29.482467 -96.050924)
			(xy 29.44108 -96.065241) (xy 29.402759 -96.086439) (xy 29.368638 -96.113891) (xy 29.339725 -96.146784)
			(xy 29.316878 -96.184144) (xy 29.300771 -96.224868) (xy 29.291881 -96.26775) (xy 29.290772 -96.289622)
			(xy 29.290772 -97.310194) (xy 29.291928 -97.332065) (xy 29.300806 -97.37495) (xy 29.316903 -97.415679)
			(xy 29.339743 -97.453045) (xy 29.368651 -97.485943) (xy 29.402769 -97.513399) (xy 29.441089 -97.5346)
			(xy 29.482477 -97.548919) (xy 29.525706 -97.555932) (xy 29.569497 -97.555431) (xy 29.612554 -97.547431)
			(xy 29.653603 -97.532169) (xy 29.691428 -97.510097) (xy 29.724909 -97.481867) (xy 29.739336 -97.465388)
			(xy 29.767591 -97.432491) (xy 29.82922 -97.371474) (xy 29.896204 -97.31639) (xy 29.967976 -97.267708)
			(xy 30.043926 -97.225841) (xy 30.123407 -97.191144) (xy 30.205746 -97.163913) (xy 30.290242 -97.144379)
			(xy 30.376178 -97.132708) (xy 30.462823 -97.128999) (xy 30.549442 -97.133283) (xy 30.635298 -97.145525)
			(xy 30.719663 -97.165619) (xy 30.801819 -97.193396) (xy 30.881069 -97.22862) (xy 30.956739 -97.27099)
			(xy 31.028186 -97.320148) (xy 31.094803 -97.375675) (xy 31.156025 -97.4371) (xy 31.211331 -97.503901)
			(xy 31.260252 -97.575511) (xy 31.302372 -97.651321) (xy 31.337332 -97.730686) (xy 31.364837 -97.812934)
			(xy 31.384652 -97.897365) (xy 31.396609 -97.983261) (xy 31.400606 -98.069894) (xy 31.398601 -98.113358)
			(xy 34.599874 -98.113358) (xy 34.599874 -98.026458) (xy 34.607892 -97.939929) (xy 34.62386 -97.854509)
			(xy 34.647641 -97.770927) (xy 34.679033 -97.689895) (xy 34.717767 -97.612106) (xy 34.763514 -97.538222)
			(xy 34.815883 -97.468875) (xy 34.874427 -97.404655) (xy 34.938647 -97.346111) (xy 35.007994 -97.293742)
			(xy 35.081878 -97.247995) (xy 35.159667 -97.209261) (xy 35.240699 -97.177869) (xy 35.324281 -97.154088)
			(xy 35.409701 -97.13812) (xy 35.49623 -97.130102) (xy 35.58313 -97.130102) (xy 35.669659 -97.13812)
			(xy 35.755079 -97.154088) (xy 35.838661 -97.177869) (xy 35.919693 -97.209261) (xy 35.997482 -97.247995)
			(xy 36.071366 -97.293742) (xy 36.140713 -97.346111) (xy 36.204933 -97.404655) (xy 36.263477 -97.468875)
			(xy 36.315846 -97.538222) (xy 36.361593 -97.612106) (xy 36.400327 -97.689895) (xy 36.431719 -97.770927)
			(xy 36.4555 -97.854509) (xy 36.471468 -97.939929) (xy 36.479486 -98.026458) (xy 36.479988 -98.069908)
			(xy 36.479486 -98.113358) (xy 36.471468 -98.199887) (xy 36.4555 -98.285307) (xy 36.431719 -98.368889)
			(xy 36.400327 -98.449921) (xy 36.361593 -98.52771) (xy 36.315846 -98.601594) (xy 36.263477 -98.670941)
			(xy 36.204933 -98.735161) (xy 36.140713 -98.793705) (xy 36.071366 -98.846074) (xy 35.997482 -98.891821)
			(xy 35.919693 -98.930555) (xy 35.838661 -98.961947) (xy 35.755079 -98.985728) (xy 35.669659 -99.001696)
			(xy 35.58313 -99.009714) (xy 35.49623 -99.009714) (xy 35.409701 -99.001696) (xy 35.324281 -98.985728)
			(xy 35.240699 -98.961947) (xy 35.159667 -98.930555) (xy 35.081878 -98.891821) (xy 35.007994 -98.846074)
			(xy 34.938647 -98.793705) (xy 34.874427 -98.735161) (xy 34.815883 -98.670941) (xy 34.763514 -98.601594)
			(xy 34.717767 -98.52771) (xy 34.679033 -98.449921) (xy 34.647641 -98.368889) (xy 34.62386 -98.285307)
			(xy 34.607892 -98.199887) (xy 34.599874 -98.113358) (xy 31.398601 -98.113358) (xy 31.39661 -98.156526)
			(xy 31.384654 -98.242423) (xy 31.36484 -98.326854) (xy 31.337337 -98.409102) (xy 31.302377 -98.488468)
			(xy 31.260259 -98.564279) (xy 31.211339 -98.635889) (xy 31.156033 -98.702691) (xy 31.094812 -98.764117)
			(xy 31.028195 -98.819645) (xy 30.956749 -98.868803) (xy 30.88108 -98.911175) (xy 30.801831 -98.946399)
			(xy 30.719675 -98.974177) (xy 30.635311 -98.994273) (xy 30.549454 -99.006515) (xy 30.462835 -99.010801)
			(xy 30.37619 -99.007093) (xy 30.290254 -98.995423) (xy 30.205758 -98.97589) (xy 30.123419 -98.94866)
			(xy 30.043937 -98.913965) (xy 29.967987 -98.872098) (xy 29.896214 -98.823417) (xy 29.829229 -98.768334)
			(xy 29.767599 -98.707318) (xy 29.739336 -98.674428) (xy 29.724908 -98.657951) (xy 29.691421 -98.629729)
			(xy 29.653593 -98.607663) (xy 29.612543 -98.592407) (xy 29.569486 -98.584411) (xy 29.525695 -98.583911)
			(xy 29.482467 -98.590924) (xy 29.44108 -98.605241) (xy 29.402759 -98.626439) (xy 29.368638 -98.653891)
			(xy 29.339725 -98.686784) (xy 29.316878 -98.724144) (xy 29.300771 -98.764868) (xy 29.291881 -98.80775)
			(xy 29.290772 -98.829622) (xy 29.290772 -100.07346) (xy 29.216858 -100.147374) (xy 29.216858 -100.252784)
			(xy 29.265118 -100.301044) (xy 29.27858 -100.309172) (xy 29.307282 -100.328222) (xy 29.328872 -100.344224)
			(xy 29.380688 -100.355654) (xy 29.49575 -100.332794) (xy 29.587698 -100.256848) (xy 29.59989 -100.229416)
			(xy 29.618449 -100.188738) (xy 29.662201 -100.110757) (xy 29.713162 -100.037285) (xy 29.770873 -99.968986)
			(xy 29.83481 -99.906478) (xy 29.904396 -99.850326) (xy 29.979001 -99.801038) (xy 30.018228 -99.779582)
			(xy 30.054894 -99.760594) (xy 30.130926 -99.728373) (xy 30.20949 -99.702943) (xy 30.289981 -99.684498)
			(xy 30.371779 -99.673182) (xy 30.454254 -99.669081) (xy 30.536772 -99.672227) (xy 30.57779 -99.676966)
			(xy 30.617916 -99.682471) (xy 30.697101 -99.69952) (xy 30.774522 -99.723329) (xy 30.849603 -99.753721)
			(xy 30.885892 -99.771708) (xy 30.92091 -99.789966) (xy 30.988056 -99.83155) (xy 31.020004 -99.854766)
			(xy 31.05189 -99.878945) (xy 31.111872 -99.931924) (xy 31.167137 -99.989808) (xy 31.217284 -100.052177)
			(xy 31.239968 -100.085144) (xy 31.263849 -100.12153) (xy 31.30554 -100.197934) (xy 31.339991 -100.277864)
			(xy 31.366909 -100.360637) (xy 31.386062 -100.445542) (xy 31.397287 -100.531854) (xy 31.400487 -100.618835)
			(xy 31.39856 -100.653358) (xy 34.599874 -100.653358) (xy 34.599874 -100.566458) (xy 34.607892 -100.479929)
			(xy 34.62386 -100.394509) (xy 34.647641 -100.310927) (xy 34.679033 -100.229895) (xy 34.717767 -100.152106)
			(xy 34.763514 -100.078222) (xy 34.815883 -100.008875) (xy 34.874427 -99.944655) (xy 34.938647 -99.886111)
			(xy 35.007994 -99.833742) (xy 35.081878 -99.787995) (xy 35.159667 -99.749261) (xy 35.240699 -99.717869)
			(xy 35.324281 -99.694088) (xy 35.409701 -99.67812) (xy 35.49623 -99.670102) (xy 35.58313 -99.670102)
			(xy 35.669659 -99.67812) (xy 35.755079 -99.694088) (xy 35.838661 -99.717869) (xy 35.919693 -99.749261)
			(xy 35.997482 -99.787995) (xy 36.071366 -99.833742) (xy 36.140713 -99.886111) (xy 36.204933 -99.944655)
			(xy 36.263477 -100.008875) (xy 36.315846 -100.078222) (xy 36.361593 -100.152106) (xy 36.400327 -100.229895)
			(xy 36.431719 -100.310927) (xy 36.4555 -100.394509) (xy 36.471468 -100.479929) (xy 36.479486 -100.566458)
			(xy 36.479988 -100.609908) (xy 36.479486 -100.653358) (xy 36.471468 -100.739887) (xy 36.4555 -100.825307)
			(xy 36.431719 -100.908889) (xy 36.400327 -100.989921) (xy 36.361593 -101.06771) (xy 36.315846 -101.141594)
			(xy 36.263477 -101.210941) (xy 36.204933 -101.275161) (xy 36.140713 -101.333705) (xy 36.071366 -101.386074)
			(xy 35.997482 -101.431821) (xy 35.919693 -101.470555) (xy 35.838661 -101.501947) (xy 35.755079 -101.525728)
			(xy 35.669659 -101.541696) (xy 35.58313 -101.549714) (xy 35.49623 -101.549714) (xy 35.409701 -101.541696)
			(xy 35.324281 -101.525728) (xy 35.240699 -101.501947) (xy 35.159667 -101.470555) (xy 35.081878 -101.431821)
			(xy 35.007994 -101.386074) (xy 34.938647 -101.333705) (xy 34.874427 -101.275161) (xy 34.815883 -101.210941)
			(xy 34.763514 -101.141594) (xy 34.717767 -101.06771) (xy 34.679033 -100.989921) (xy 34.647641 -100.908889)
			(xy 34.62386 -100.825307) (xy 34.607892 -100.739887) (xy 34.599874 -100.653358) (xy 31.39856 -100.653358)
			(xy 31.395636 -100.705738) (xy 31.382774 -100.791822) (xy 31.362011 -100.876348) (xy 31.333527 -100.958594)
			(xy 31.297563 -101.037856) (xy 31.254428 -101.113455) (xy 31.204492 -101.184744) (xy 31.148181 -101.251113)
			(xy 31.085978 -101.311995) (xy 31.018414 -101.366867) (xy 30.946069 -101.415261) (xy 30.869561 -101.456762)
			(xy 30.789545 -101.491014) (xy 30.706706 -101.517726) (xy 30.621753 -101.536668) (xy 30.535413 -101.547678)
			(xy 30.491938 -101.549708) (xy 30.452255 -101.550668) (xy 30.372969 -101.546711) (xy 30.2943 -101.536075)
			(xy 30.255464 -101.527864) (xy 30.215389 -101.518503) (xy 30.136917 -101.493683) (xy 30.060917 -101.462092)
			(xy 29.987973 -101.423973) (xy 29.918644 -101.379618) (xy 29.853461 -101.329368) (xy 29.822902 -101.301804)
			(xy 29.805791 -101.287284) (xy 29.767498 -101.263891) (xy 29.725692 -101.247588) (xy 29.681672 -101.238881)
			(xy 29.636807 -101.238042) (xy 29.592492 -101.245097) (xy 29.550105 -101.259825) (xy 29.510965 -101.28177)
			(xy 29.476287 -101.310249) (xy 29.447151 -101.344376) (xy 29.424462 -101.38309) (xy 29.408927 -101.425188)
			(xy 29.401027 -101.46936) (xy 29.4005 -101.491796) (xy 29.4005 -101.906578) (xy 39.461692 -101.906578)
			(xy 39.465763 -101.850956) (xy 39.477889 -101.796519) (xy 39.497812 -101.744428) (xy 39.525108 -101.695793)
			(xy 39.559194 -101.65165) (xy 39.599343 -101.612941) (xy 39.644701 -101.58049) (xy 39.694301 -101.554989)
			(xy 39.747085 -101.536982) (xy 39.801928 -101.526852) (xy 39.857662 -101.524815) (xy 39.913099 -101.530915)
			(xy 39.967056 -101.545021) (xy 40.018385 -101.566833) (xy 40.065991 -101.595887) (xy 40.108859 -101.631562)
			(xy 40.146076 -101.673099) (xy 40.176849 -101.719612) (xy 40.200521 -101.770109) (xy 40.216589 -101.823516)
			(xy 40.224709 -101.878692) (xy 40.225218 -101.906578) (xy 40.224709 -101.934464) (xy 40.216589 -101.98964)
			(xy 40.200521 -102.043047) (xy 40.176849 -102.093544) (xy 40.146076 -102.140057) (xy 40.108859 -102.181594)
			(xy 40.065991 -102.217269) (xy 40.018385 -102.246323) (xy 39.967056 -102.268135) (xy 39.913099 -102.282241)
			(xy 39.857662 -102.288341) (xy 39.801928 -102.286304) (xy 39.747085 -102.276174) (xy 39.694301 -102.258167)
			(xy 39.644701 -102.232666) (xy 39.599343 -102.200215) (xy 39.559194 -102.161506) (xy 39.525108 -102.117363)
			(xy 39.497812 -102.068728) (xy 39.477889 -102.016637) (xy 39.465763 -101.9622) (xy 39.461692 -101.906578)
			(xy 29.4005 -101.906578) (xy 29.4005 -102.26802) (xy 29.400972 -102.290466) (xy 29.408848 -102.334661)
			(xy 29.42437 -102.376783) (xy 29.447053 -102.415522) (xy 29.476192 -102.449671) (xy 29.51088 -102.478167)
			(xy 29.550036 -102.500122) (xy 29.592442 -102.514853) (xy 29.636776 -102.521902) (xy 29.681659 -102.521048)
			(xy 29.725694 -102.512319) (xy 29.767509 -102.495987) (xy 29.805802 -102.472559) (xy 29.822902 -102.458012)
			(xy 29.855271 -102.428887) (xy 29.924524 -102.376091) (xy 29.998361 -102.329924) (xy 30.07615 -102.290782)
			(xy 30.157225 -102.259) (xy 30.240891 -102.23485) (xy 30.326432 -102.218539) (xy 30.413114 -102.210206)
			(xy 30.500196 -102.209924) (xy 30.586931 -102.217695) (xy 30.672575 -102.233451) (xy 30.756396 -102.257059)
			(xy 30.837675 -102.288315) (xy 30.915717 -102.326952) (xy 30.989851 -102.37264) (xy 31.059444 -102.424985)
			(xy 31.123899 -102.483542) (xy 31.182664 -102.547806) (xy 31.235236 -102.617229) (xy 31.281163 -102.691215)
			(xy 31.320054 -102.76913) (xy 31.351574 -102.850308) (xy 31.375453 -102.934052) (xy 31.391487 -103.019645)
			(xy 31.399539 -103.106354) (xy 31.39954 -103.193358) (xy 34.599874 -103.193358) (xy 34.599874 -103.106458)
			(xy 34.607892 -103.019929) (xy 34.62386 -102.934509) (xy 34.647641 -102.850927) (xy 34.679033 -102.769895)
			(xy 34.717767 -102.692106) (xy 34.763514 -102.618222) (xy 34.815883 -102.548875) (xy 34.874427 -102.484655)
			(xy 34.938647 -102.426111) (xy 35.007994 -102.373742) (xy 35.081878 -102.327995) (xy 35.159667 -102.289261)
			(xy 35.240699 -102.257869) (xy 35.324281 -102.234088) (xy 35.409701 -102.21812) (xy 35.49623 -102.210102)
			(xy 35.58313 -102.210102) (xy 35.669659 -102.21812) (xy 35.755079 -102.234088) (xy 35.838661 -102.257869)
			(xy 35.919693 -102.289261) (xy 35.997482 -102.327995) (xy 36.071366 -102.373742) (xy 36.140713 -102.426111)
			(xy 36.204933 -102.484655) (xy 36.263477 -102.548875) (xy 36.315846 -102.618222) (xy 36.361593 -102.692106)
			(xy 36.400327 -102.769895) (xy 36.431719 -102.850927) (xy 36.4555 -102.934509) (xy 36.471468 -103.019929)
			(xy 36.479486 -103.106458) (xy 36.479988 -103.149908) (xy 36.479486 -103.193358) (xy 36.471468 -103.279887)
			(xy 36.4555 -103.365307) (xy 36.431719 -103.448889) (xy 36.402601 -103.52405) (xy 40.60774 -103.52405)
			(xy 40.611811 -103.468428) (xy 40.623937 -103.413991) (xy 40.64386 -103.3619) (xy 40.671156 -103.313265)
			(xy 40.705242 -103.269122) (xy 40.745391 -103.230413) (xy 40.790749 -103.197962) (xy 40.840349 -103.172461)
			(xy 40.893133 -103.154454) (xy 40.947976 -103.144324) (xy 41.00371 -103.142287) (xy 41.059147 -103.148387)
			(xy 41.113104 -103.162493) (xy 41.164433 -103.184305) (xy 41.212039 -103.213359) (xy 41.254907 -103.249034)
			(xy 41.292124 -103.290571) (xy 41.322897 -103.337084) (xy 41.346569 -103.387581) (xy 41.362637 -103.440988)
			(xy 41.370757 -103.496164) (xy 41.371266 -103.52405) (xy 41.370757 -103.551936) (xy 41.362637 -103.607112)
			(xy 41.346569 -103.660519) (xy 41.322897 -103.711016) (xy 41.292124 -103.757529) (xy 41.254907 -103.799066)
			(xy 41.212039 -103.834741) (xy 41.164433 -103.863795) (xy 41.113104 -103.885607) (xy 41.059147 -103.899713)
			(xy 41.00371 -103.905813) (xy 40.947976 -103.903776) (xy 40.893133 -103.893646) (xy 40.840349 -103.875639)
			(xy 40.790749 -103.850138) (xy 40.745391 -103.817687) (xy 40.705242 -103.778978) (xy 40.671156 -103.734835)
			(xy 40.64386 -103.6862) (xy 40.623937 -103.634109) (xy 40.611811 -103.579672) (xy 40.60774 -103.52405)
			(xy 36.402601 -103.52405) (xy 36.400327 -103.529921) (xy 36.361593 -103.60771) (xy 36.315846 -103.681594)
			(xy 36.263477 -103.750941) (xy 36.204933 -103.815161) (xy 36.140713 -103.873705) (xy 36.071366 -103.926074)
			(xy 35.997482 -103.971821) (xy 35.919693 -104.010555) (xy 35.838661 -104.041947) (xy 35.755079 -104.065728)
			(xy 35.669659 -104.081696) (xy 35.58313 -104.089714) (xy 35.49623 -104.089714) (xy 35.409701 -104.081696)
			(xy 35.324281 -104.065728) (xy 35.240699 -104.041947) (xy 35.159667 -104.010555) (xy 35.081878 -103.971821)
			(xy 35.007994 -103.926074) (xy 34.938647 -103.873705) (xy 34.874427 -103.815161) (xy 34.815883 -103.750941)
			(xy 34.763514 -103.681594) (xy 34.717767 -103.60771) (xy 34.679033 -103.529921) (xy 34.647641 -103.448889)
			(xy 34.62386 -103.365307) (xy 34.607892 -103.279887) (xy 34.599874 -103.193358) (xy 31.39954 -103.193358)
			(xy 31.39954 -103.193436) (xy 31.391489 -103.280145) (xy 31.375456 -103.365738) (xy 31.351577 -103.449482)
			(xy 31.320058 -103.53066) (xy 31.281169 -103.608576) (xy 31.235242 -103.682562) (xy 31.182671 -103.751985)
			(xy 31.123907 -103.816251) (xy 31.059453 -103.874808) (xy 30.98986 -103.927154) (xy 30.915726 -103.972843)
			(xy 30.837685 -104.011481) (xy 30.756406 -104.042738) (xy 30.672586 -104.066346) (xy 30.586941 -104.082104)
			(xy 30.500207 -104.089875) (xy 30.413125 -104.089594) (xy 30.326443 -104.081263) (xy 30.240902 -104.064953)
			(xy 30.157235 -104.040804) (xy 30.07616 -104.009022) (xy 29.99837 -103.969881) (xy 29.924533 -103.923715)
			(xy 29.85528 -103.87092) (xy 29.822902 -103.841804) (xy 29.805791 -103.827284) (xy 29.767498 -103.803891)
			(xy 29.725692 -103.787588) (xy 29.681672 -103.778881) (xy 29.636807 -103.778042) (xy 29.592492 -103.785097)
			(xy 29.550105 -103.799825) (xy 29.510965 -103.82177) (xy 29.476287 -103.850249) (xy 29.447151 -103.884376)
			(xy 29.424462 -103.92309) (xy 29.408927 -103.965188) (xy 29.401027 -104.00936) (xy 29.4005 -104.031796)
			(xy 29.4005 -104.648762) (xy 29.734764 -104.983026) (xy 29.831792 -104.988106) (xy 29.869638 -104.957626)
			(xy 29.903826 -104.930702) (xy 29.976343 -104.882588) (xy 30.052996 -104.841379) (xy 30.133129 -104.80743)
			(xy 30.216055 -104.78103) (xy 30.301067 -104.762405) (xy 30.387435 -104.751715) (xy 30.474422 -104.749051)
			(xy 30.561283 -104.754436) (xy 30.647274 -104.767823) (xy 30.731661 -104.789099) (xy 30.813721 -104.818081)
			(xy 30.892752 -104.854521) (xy 30.968078 -104.898107) (xy 31.039054 -104.948468) (xy 31.105074 -105.00517)
			(xy 31.165572 -105.067731) (xy 31.220031 -105.135613) (xy 31.267984 -105.208237) (xy 31.309022 -105.284982)
			(xy 31.342793 -105.36519) (xy 31.369009 -105.448175) (xy 31.387445 -105.533227) (xy 31.39313 -105.57637)
			(xy 31.39313 -105.57764) (xy 31.397642 -105.618752) (xy 31.400309 -105.701422) (xy 31.398883 -105.733358)
			(xy 34.599874 -105.733358) (xy 34.599874 -105.646458) (xy 34.607892 -105.559929) (xy 34.62386 -105.474509)
			(xy 34.647641 -105.390927) (xy 34.679033 -105.309895) (xy 34.717767 -105.232106) (xy 34.763514 -105.158222)
			(xy 34.815883 -105.088875) (xy 34.874427 -105.024655) (xy 34.938647 -104.966111) (xy 35.007994 -104.913742)
			(xy 35.081878 -104.867995) (xy 35.159667 -104.829261) (xy 35.240699 -104.797869) (xy 35.324281 -104.774088)
			(xy 35.409701 -104.75812) (xy 35.49623 -104.750102) (xy 35.58313 -104.750102) (xy 35.669659 -104.75812)
			(xy 35.755079 -104.774088) (xy 35.838661 -104.797869) (xy 35.919693 -104.829261) (xy 35.997482 -104.867995)
			(xy 36.071366 -104.913742) (xy 36.140713 -104.966111) (xy 36.204933 -105.024655) (xy 36.263477 -105.088875)
			(xy 36.315846 -105.158222) (xy 36.361593 -105.232106) (xy 36.400327 -105.309895) (xy 36.431719 -105.390927)
			(xy 36.4555 -105.474509) (xy 36.471468 -105.559929) (xy 36.479486 -105.646458) (xy 36.479988 -105.689908)
			(xy 36.479486 -105.733358) (xy 36.471468 -105.819887) (xy 36.4555 -105.905307) (xy 36.431719 -105.988889)
			(xy 36.400327 -106.069921) (xy 36.361593 -106.14771) (xy 36.315846 -106.221594) (xy 36.263477 -106.290941)
			(xy 36.204933 -106.355161) (xy 36.140713 -106.413705) (xy 36.071366 -106.466074) (xy 35.997482 -106.511821)
			(xy 35.919693 -106.550555) (xy 35.838661 -106.581947) (xy 35.755079 -106.605728) (xy 35.669659 -106.621696)
			(xy 35.58313 -106.629714) (xy 35.49623 -106.629714) (xy 35.409701 -106.621696) (xy 35.324281 -106.605728)
			(xy 35.240699 -106.581947) (xy 35.159667 -106.550555) (xy 35.081878 -106.511821) (xy 35.007994 -106.466074)
			(xy 34.938647 -106.413705) (xy 34.874427 -106.355161) (xy 34.815883 -106.290941) (xy 34.763514 -106.221594)
			(xy 34.717767 -106.14771) (xy 34.679033 -106.069921) (xy 34.647641 -105.988889) (xy 34.62386 -105.905307)
			(xy 34.607892 -105.819887) (xy 34.599874 -105.733358) (xy 31.398883 -105.733358) (xy 31.398464 -105.74274)
			(xy 31.396039 -105.780004) (xy 31.385997 -105.854007) (xy 31.378398 -105.890568) (xy 31.369043 -105.931278)
			(xy 31.344048 -106.010989) (xy 31.312078 -106.088167) (xy 31.273386 -106.162204) (xy 31.228278 -106.232516)
			(xy 31.177108 -106.298548) (xy 31.149036 -106.32948) (xy 31.118949 -106.361167) (xy 31.05382 -106.419429)
			(xy 31.018988 -106.445812) (xy 30.986677 -106.469194) (xy 30.918766 -106.511032) (xy 30.883352 -106.529378)
			(xy 30.846188 -106.547627) (xy 30.769272 -106.578287) (xy 30.689958 -106.602067) (xy 30.608862 -106.618783)
			(xy 30.52661 -106.628307) (xy 30.443839 -106.630563) (xy 30.361191 -106.625536) (xy 30.279304 -106.613263)
			(xy 30.198813 -106.59384) (xy 30.12034 -106.567417) (xy 30.082236 -106.551222) (xy 30.061444 -106.543185)
			(xy 30.017891 -106.533702) (xy 29.973351 -106.531958) (xy 29.92919 -106.538008) (xy 29.88676 -106.551666)
			(xy 29.847362 -106.572513) (xy 29.812203 -106.599911) (xy 29.78236 -106.63302) (xy 29.758747 -106.670825)
			(xy 29.742088 -106.712169) (xy 29.732894 -106.755784) (xy 29.731716 -106.778044) (xy 29.731716 -106.900726)
			(xy 40.57726 -106.900726) (xy 40.581331 -106.845104) (xy 40.593457 -106.790667) (xy 40.61338 -106.738576)
			(xy 40.640676 -106.689941) (xy 40.674762 -106.645798) (xy 40.714911 -106.607089) (xy 40.760269 -106.574638)
			(xy 40.809869 -106.549137) (xy 40.862653 -106.53113) (xy 40.917496 -106.521) (xy 40.97323 -106.518963)
			(xy 41.028667 -106.525063) (xy 41.082624 -106.539169) (xy 41.133953 -106.560981) (xy 41.181559 -106.590035)
			(xy 41.224427 -106.62571) (xy 41.261644 -106.667247) (xy 41.292417 -106.71376) (xy 41.316089 -106.764257)
			(xy 41.332157 -106.817664) (xy 41.340277 -106.87284) (xy 41.340786 -106.900726) (xy 41.340277 -106.928612)
			(xy 41.332157 -106.983788) (xy 41.316089 -107.037195) (xy 41.292417 -107.087692) (xy 41.261644 -107.134205)
			(xy 41.238099 -107.160483) (xy 47.373784 -107.160483) (xy 47.373784 -107.079373) (xy 47.381734 -106.998654)
			(xy 47.397557 -106.919103) (xy 47.421102 -106.841487) (xy 47.452141 -106.766551) (xy 47.490376 -106.695019)
			(xy 47.535438 -106.627579) (xy 47.586893 -106.56488) (xy 47.644246 -106.507527) (xy 47.706945 -106.456072)
			(xy 47.774385 -106.41101) (xy 47.845917 -106.372775) (xy 47.920853 -106.341736) (xy 47.998469 -106.318191)
			(xy 48.07802 -106.302368) (xy 48.158739 -106.294418) (xy 48.239849 -106.294418) (xy 48.320568 -106.302368)
			(xy 48.400119 -106.318191) (xy 48.477735 -106.341736) (xy 48.552671 -106.372775) (xy 48.624203 -106.41101)
			(xy 48.691643 -106.456072) (xy 48.754342 -106.507527) (xy 48.811695 -106.56488) (xy 48.86315 -106.627579)
			(xy 48.908212 -106.695019) (xy 48.946447 -106.766551) (xy 48.977486 -106.841487) (xy 49.001031 -106.919103)
			(xy 49.016854 -106.998654) (xy 49.024804 -107.079373) (xy 49.025302 -107.119928) (xy 49.024804 -107.160483)
			(xy 50.873904 -107.160483) (xy 50.873904 -107.079373) (xy 50.881854 -106.998654) (xy 50.897677 -106.919103)
			(xy 50.921222 -106.841487) (xy 50.952261 -106.766551) (xy 50.990496 -106.695019) (xy 51.035558 -106.627579)
			(xy 51.087013 -106.56488) (xy 51.144366 -106.507527) (xy 51.207065 -106.456072) (xy 51.274505 -106.41101)
			(xy 51.346037 -106.372775) (xy 51.420973 -106.341736) (xy 51.498589 -106.318191) (xy 51.57814 -106.302368)
			(xy 51.658859 -106.294418) (xy 51.739969 -106.294418) (xy 51.820688 -106.302368) (xy 51.900239 -106.318191)
			(xy 51.977855 -106.341736) (xy 52.052791 -106.372775) (xy 52.124323 -106.41101) (xy 52.191763 -106.456072)
			(xy 52.254462 -106.507527) (xy 52.311815 -106.56488) (xy 52.36327 -106.627579) (xy 52.408332 -106.695019)
			(xy 52.446567 -106.766551) (xy 52.477606 -106.841487) (xy 52.501151 -106.919103) (xy 52.516974 -106.998654)
			(xy 52.524924 -107.079373) (xy 52.525422 -107.119928) (xy 52.524924 -107.160483) (xy 52.516974 -107.241202)
			(xy 52.501151 -107.320753) (xy 52.477606 -107.398369) (xy 52.446567 -107.473305) (xy 52.408332 -107.544837)
			(xy 52.36327 -107.612277) (xy 52.311815 -107.674976) (xy 52.254462 -107.732329) (xy 52.191763 -107.783784)
			(xy 52.124323 -107.828846) (xy 52.052791 -107.867081) (xy 51.977855 -107.89812) (xy 51.900239 -107.921665)
			(xy 51.820688 -107.937488) (xy 51.739969 -107.945438) (xy 51.658859 -107.945438) (xy 51.57814 -107.937488)
			(xy 51.498589 -107.921665) (xy 51.420973 -107.89812) (xy 51.346037 -107.867081) (xy 51.274505 -107.828846)
			(xy 51.207065 -107.783784) (xy 51.144366 -107.732329) (xy 51.087013 -107.674976) (xy 51.035558 -107.612277)
			(xy 50.990496 -107.544837) (xy 50.952261 -107.473305) (xy 50.921222 -107.398369) (xy 50.897677 -107.320753)
			(xy 50.881854 -107.241202) (xy 50.873904 -107.160483) (xy 49.024804 -107.160483) (xy 49.016854 -107.241202)
			(xy 49.001031 -107.320753) (xy 48.977486 -107.398369) (xy 48.946447 -107.473305) (xy 48.908212 -107.544837)
			(xy 48.86315 -107.612277) (xy 48.811695 -107.674976) (xy 48.754342 -107.732329) (xy 48.691643 -107.783784)
			(xy 48.624203 -107.828846) (xy 48.552671 -107.867081) (xy 48.477735 -107.89812) (xy 48.400119 -107.921665)
			(xy 48.320568 -107.937488) (xy 48.239849 -107.945438) (xy 48.158739 -107.945438) (xy 48.07802 -107.937488)
			(xy 47.998469 -107.921665) (xy 47.920853 -107.89812) (xy 47.845917 -107.867081) (xy 47.774385 -107.828846)
			(xy 47.706945 -107.783784) (xy 47.644246 -107.732329) (xy 47.586893 -107.674976) (xy 47.535438 -107.612277)
			(xy 47.490376 -107.544837) (xy 47.452141 -107.473305) (xy 47.421102 -107.398369) (xy 47.397557 -107.320753)
			(xy 47.381734 -107.241202) (xy 47.373784 -107.160483) (xy 41.238099 -107.160483) (xy 41.224427 -107.175742)
			(xy 41.181559 -107.211417) (xy 41.133953 -107.240471) (xy 41.082624 -107.262283) (xy 41.028667 -107.276389)
			(xy 40.97323 -107.282489) (xy 40.917496 -107.280452) (xy 40.862653 -107.270322) (xy 40.809869 -107.252315)
			(xy 40.760269 -107.226814) (xy 40.714911 -107.194363) (xy 40.674762 -107.155654) (xy 40.640676 -107.111511)
			(xy 40.61338 -107.062876) (xy 40.593457 -107.010785) (xy 40.581331 -106.956348) (xy 40.57726 -106.900726)
			(xy 29.731716 -106.900726) (xy 29.731716 -107.141772) (xy 29.732889 -107.164038) (xy 29.74206 -107.207669)
			(xy 29.758703 -107.249031) (xy 29.782309 -107.286854) (xy 29.812152 -107.319977) (xy 29.847317 -107.347385)
			(xy 29.886725 -107.368236) (xy 29.929168 -107.381891) (xy 29.973341 -107.38793) (xy 30.017891 -107.386169)
			(xy 30.06145 -107.376661) (xy 30.082236 -107.368594) (xy 30.12218 -107.351634) (xy 30.20454 -107.324271)
			(xy 30.28907 -107.304612) (xy 30.375052 -107.292827) (xy 30.461755 -107.289014) (xy 30.548439 -107.293205)
			(xy 30.634369 -107.305366) (xy 30.718813 -107.325393) (xy 30.801052 -107.353116) (xy 30.880387 -107.388298)
			(xy 30.956143 -107.43064) (xy 31.027675 -107.479783) (xy 31.094375 -107.535307) (xy 31.155675 -107.596741)
			(xy 31.211054 -107.663562) (xy 31.26004 -107.735201) (xy 31.302217 -107.811049) (xy 31.337226 -107.89046)
			(xy 31.364769 -107.97276) (xy 31.384612 -108.057247) (xy 31.396586 -108.143203) (xy 31.400589 -108.229897)
			(xy 31.398582 -108.273358) (xy 34.599874 -108.273358) (xy 34.599874 -108.186458) (xy 34.607892 -108.099929)
			(xy 34.62386 -108.014509) (xy 34.647641 -107.930927) (xy 34.679033 -107.849895) (xy 34.717767 -107.772106)
			(xy 34.763514 -107.698222) (xy 34.815883 -107.628875) (xy 34.874427 -107.564655) (xy 34.938647 -107.506111)
			(xy 35.007994 -107.453742) (xy 35.081878 -107.407995) (xy 35.159667 -107.369261) (xy 35.240699 -107.337869)
			(xy 35.324281 -107.314088) (xy 35.409701 -107.29812) (xy 35.49623 -107.290102) (xy 35.58313 -107.290102)
			(xy 35.669659 -107.29812) (xy 35.755079 -107.314088) (xy 35.838661 -107.337869) (xy 35.919693 -107.369261)
			(xy 35.997482 -107.407995) (xy 36.071366 -107.453742) (xy 36.140713 -107.506111) (xy 36.204933 -107.564655)
			(xy 36.263477 -107.628875) (xy 36.315846 -107.698222) (xy 36.361593 -107.772106) (xy 36.400327 -107.849895)
			(xy 36.431719 -107.930927) (xy 36.4555 -108.014509) (xy 36.471468 -108.099929) (xy 36.479486 -108.186458)
			(xy 36.479988 -108.229908) (xy 36.479486 -108.273358) (xy 36.471468 -108.359887) (xy 36.4555 -108.445307)
			(xy 36.431719 -108.528889) (xy 36.400327 -108.609921) (xy 36.361593 -108.68771) (xy 36.315846 -108.761594)
			(xy 36.263477 -108.830941) (xy 36.204933 -108.895161) (xy 36.140713 -108.953705) (xy 36.071366 -109.006074)
			(xy 35.997482 -109.051821) (xy 35.919693 -109.090555) (xy 35.838661 -109.121947) (xy 35.755079 -109.145728)
			(xy 35.669659 -109.161696) (xy 35.58313 -109.169714) (xy 35.49623 -109.169714) (xy 35.409701 -109.161696)
			(xy 35.324281 -109.145728) (xy 35.240699 -109.121947) (xy 35.159667 -109.090555) (xy 35.081878 -109.051821)
			(xy 35.007994 -109.006074) (xy 34.938647 -108.953705) (xy 34.874427 -108.895161) (xy 34.815883 -108.830941)
			(xy 34.763514 -108.761594) (xy 34.717767 -108.68771) (xy 34.679033 -108.609921) (xy 34.647641 -108.528889)
			(xy 34.62386 -108.445307) (xy 34.607892 -108.359887) (xy 34.599874 -108.273358) (xy 31.398582 -108.273358)
			(xy 31.396586 -108.316591) (xy 31.384613 -108.402547) (xy 31.364771 -108.487034) (xy 31.337229 -108.569334)
			(xy 31.30222 -108.648745) (xy 31.260043 -108.724594) (xy 31.211058 -108.796233) (xy 31.155679 -108.863054)
			(xy 31.09438 -108.924489) (xy 31.02768 -108.980013) (xy 30.956148 -109.029156) (xy 30.880393 -109.071499)
			(xy 30.801058 -109.106682) (xy 30.718819 -109.134405) (xy 30.634375 -109.154432) (xy 30.548446 -109.166594)
			(xy 30.461761 -109.170786) (xy 30.375059 -109.166974) (xy 30.289077 -109.155189) (xy 30.204546 -109.135531)
			(xy 30.122186 -109.108169) (xy 30.082236 -109.091222) (xy 30.061444 -109.083185) (xy 30.017891 -109.073702)
			(xy 29.973351 -109.071958) (xy 29.92919 -109.078008) (xy 29.88676 -109.091666) (xy 29.847362 -109.112513)
			(xy 29.812203 -109.139911) (xy 29.78236 -109.17302) (xy 29.758747 -109.210825) (xy 29.742088 -109.252169)
			(xy 29.732894 -109.295784) (xy 29.731716 -109.318044) (xy 29.731716 -109.681772) (xy 29.732889 -109.704038)
			(xy 29.74206 -109.747669) (xy 29.758703 -109.789031) (xy 29.782309 -109.826854) (xy 29.812152 -109.859977)
			(xy 29.847317 -109.887385) (xy 29.886725 -109.908236) (xy 29.929168 -109.921891) (xy 29.973341 -109.92793)
			(xy 30.017891 -109.926169) (xy 30.06145 -109.916661) (xy 30.082236 -109.908594) (xy 30.121832 -109.891755)
			(xy 30.203464 -109.864538) (xy 30.287241 -109.844894) (xy 30.372463 -109.832986) (xy 30.458417 -109.828915)
			(xy 30.544382 -109.832715) (xy 30.629642 -109.844354) (xy 30.713481 -109.863734) (xy 30.795198 -109.890693)
			(xy 30.874111 -109.925006) (xy 30.949558 -109.966386) (xy 31.020908 -110.014486) (xy 31.087566 -110.068905)
			(xy 31.148972 -110.129186) (xy 31.204613 -110.194826) (xy 31.254024 -110.265275) (xy 31.296792 -110.339945)
			(xy 31.332558 -110.418209) (xy 31.361024 -110.499414) (xy 31.38195 -110.582881) (xy 31.395163 -110.66791)
			(xy 31.400551 -110.753791) (xy 31.398833 -110.813358) (xy 34.599874 -110.813358) (xy 34.599874 -110.726458)
			(xy 34.607892 -110.639929) (xy 34.62386 -110.554509) (xy 34.647641 -110.470927) (xy 34.679033 -110.389895)
			(xy 34.717767 -110.312106) (xy 34.763514 -110.238222) (xy 34.815883 -110.168875) (xy 34.874427 -110.104655)
			(xy 34.938647 -110.046111) (xy 35.007994 -109.993742) (xy 35.081878 -109.947995) (xy 35.159667 -109.909261)
			(xy 35.240699 -109.877869) (xy 35.324281 -109.854088) (xy 35.409701 -109.83812) (xy 35.49623 -109.830102)
			(xy 35.58313 -109.830102) (xy 35.669659 -109.83812) (xy 35.755079 -109.854088) (xy 35.838661 -109.877869)
			(xy 35.919693 -109.909261) (xy 35.997482 -109.947995) (xy 36.039685 -109.974126) (xy 39.95496 -109.974126)
			(xy 39.959031 -109.918504) (xy 39.971157 -109.864067) (xy 39.99108 -109.811976) (xy 40.018376 -109.763341)
			(xy 40.052462 -109.719198) (xy 40.092611 -109.680489) (xy 40.137969 -109.648038) (xy 40.187569 -109.622537)
			(xy 40.240353 -109.60453) (xy 40.295196 -109.5944) (xy 40.35093 -109.592363) (xy 40.406367 -109.598463)
			(xy 40.460324 -109.612569) (xy 40.511653 -109.634381) (xy 40.559259 -109.663435) (xy 40.602127 -109.69911)
			(xy 40.639344 -109.740647) (xy 40.670117 -109.78716) (xy 40.693789 -109.837657) (xy 40.709857 -109.891064)
			(xy 40.717408 -109.942376) (xy 72.430892 -109.942376) (xy 72.434963 -109.886754) (xy 72.447089 -109.832317)
			(xy 72.467012 -109.780226) (xy 72.494308 -109.731591) (xy 72.528394 -109.687448) (xy 72.568543 -109.648739)
			(xy 72.613901 -109.616288) (xy 72.663501 -109.590787) (xy 72.716285 -109.57278) (xy 72.771128 -109.56265)
			(xy 72.826862 -109.560613) (xy 72.882299 -109.566713) (xy 72.936256 -109.580819) (xy 72.987585 -109.602631)
			(xy 73.035191 -109.631685) (xy 73.078059 -109.66736) (xy 73.115276 -109.708897) (xy 73.146049 -109.75541)
			(xy 73.169721 -109.805907) (xy 73.185789 -109.859314) (xy 73.193909 -109.91449) (xy 73.194418 -109.942376)
			(xy 73.53249 -109.942376) (xy 73.536561 -109.886754) (xy 73.548687 -109.832317) (xy 73.56861 -109.780226)
			(xy 73.595906 -109.731591) (xy 73.629992 -109.687448) (xy 73.670141 -109.648739) (xy 73.715499 -109.616288)
			(xy 73.765099 -109.590787) (xy 73.817883 -109.57278) (xy 73.872726 -109.56265) (xy 73.92846 -109.560613)
			(xy 73.983897 -109.566713) (xy 74.037854 -109.580819) (xy 74.089183 -109.602631) (xy 74.136789 -109.631685)
			(xy 74.179657 -109.66736) (xy 74.216874 -109.708897) (xy 74.247647 -109.75541) (xy 74.271319 -109.805907)
			(xy 74.287387 -109.859314) (xy 74.295507 -109.91449) (xy 74.296016 -109.942376) (xy 74.295507 -109.970262)
			(xy 74.287387 -110.025438) (xy 74.271319 -110.078845) (xy 74.247647 -110.129342) (xy 74.216874 -110.175855)
			(xy 74.179657 -110.217392) (xy 74.136789 -110.253067) (xy 74.089183 -110.282121) (xy 74.037854 -110.303933)
			(xy 73.983897 -110.318039) (xy 73.92846 -110.324139) (xy 73.872726 -110.322102) (xy 73.817883 -110.311972)
			(xy 73.765099 -110.293965) (xy 73.715499 -110.268464) (xy 73.670141 -110.236013) (xy 73.629992 -110.197304)
			(xy 73.595906 -110.153161) (xy 73.56861 -110.104526) (xy 73.548687 -110.052435) (xy 73.536561 -109.997998)
			(xy 73.53249 -109.942376) (xy 73.194418 -109.942376) (xy 73.193909 -109.970262) (xy 73.185789 -110.025438)
			(xy 73.169721 -110.078845) (xy 73.146049 -110.129342) (xy 73.115276 -110.175855) (xy 73.078059 -110.217392)
			(xy 73.035191 -110.253067) (xy 72.987585 -110.282121) (xy 72.936256 -110.303933) (xy 72.882299 -110.318039)
			(xy 72.826862 -110.324139) (xy 72.771128 -110.322102) (xy 72.716285 -110.311972) (xy 72.663501 -110.293965)
			(xy 72.613901 -110.268464) (xy 72.568543 -110.236013) (xy 72.528394 -110.197304) (xy 72.494308 -110.153161)
			(xy 72.467012 -110.104526) (xy 72.447089 -110.052435) (xy 72.434963 -109.997998) (xy 72.430892 -109.942376)
			(xy 40.717408 -109.942376) (xy 40.717977 -109.94624) (xy 40.718486 -109.974126) (xy 40.717977 -110.002012)
			(xy 40.709857 -110.057188) (xy 40.693789 -110.110595) (xy 40.670117 -110.161092) (xy 40.639344 -110.207605)
			(xy 40.602127 -110.249142) (xy 40.559259 -110.284817) (xy 40.511653 -110.313871) (xy 40.460324 -110.335683)
			(xy 40.406367 -110.349789) (xy 40.35093 -110.355889) (xy 40.295196 -110.353852) (xy 40.240353 -110.343722)
			(xy 40.187569 -110.325715) (xy 40.137969 -110.300214) (xy 40.092611 -110.267763) (xy 40.052462 -110.229054)
			(xy 40.018376 -110.184911) (xy 39.99108 -110.136276) (xy 39.971157 -110.084185) (xy 39.959031 -110.029748)
			(xy 39.95496 -109.974126) (xy 36.039685 -109.974126) (xy 36.071366 -109.993742) (xy 36.140713 -110.046111)
			(xy 36.204933 -110.104655) (xy 36.263477 -110.168875) (xy 36.315846 -110.238222) (xy 36.361593 -110.312106)
			(xy 36.400327 -110.389895) (xy 36.431719 -110.470927) (xy 36.4555 -110.554509) (xy 36.471468 -110.639929)
			(xy 36.479486 -110.726458) (xy 36.479988 -110.769908) (xy 36.479791 -110.786926) (xy 71.136508 -110.786926)
			(xy 71.140579 -110.731304) (xy 71.152705 -110.676867) (xy 71.172628 -110.624776) (xy 71.199924 -110.576141)
			(xy 71.23401 -110.531998) (xy 71.274159 -110.493289) (xy 71.319517 -110.460838) (xy 71.369117 -110.435337)
			(xy 71.421901 -110.41733) (xy 71.476744 -110.4072) (xy 71.532478 -110.405163) (xy 71.587915 -110.411263)
			(xy 71.641872 -110.425369) (xy 71.693201 -110.447181) (xy 71.740807 -110.476235) (xy 71.783675 -110.51191)
			(xy 71.820892 -110.553447) (xy 71.851665 -110.59996) (xy 71.875337 -110.650457) (xy 71.891405 -110.703864)
			(xy 71.899525 -110.75904) (xy 71.900034 -110.786926) (xy 71.899525 -110.814812) (xy 71.891405 -110.869988)
			(xy 71.875337 -110.923395) (xy 71.851665 -110.973892) (xy 71.820892 -111.020405) (xy 71.783675 -111.061942)
			(xy 71.740807 -111.097617) (xy 71.693201 -111.126671) (xy 71.641872 -111.148483) (xy 71.587915 -111.162589)
			(xy 71.532478 -111.168689) (xy 71.476744 -111.166652) (xy 71.421901 -111.156522) (xy 71.369117 -111.138515)
			(xy 71.319517 -111.113014) (xy 71.274159 -111.080563) (xy 71.23401 -111.041854) (xy 71.199924 -110.997711)
			(xy 71.172628 -110.949076) (xy 71.152705 -110.896985) (xy 71.140579 -110.842548) (xy 71.136508 -110.786926)
			(xy 36.479791 -110.786926) (xy 36.479486 -110.813358) (xy 36.471468 -110.899887) (xy 36.4555 -110.985307)
			(xy 36.431719 -111.068889) (xy 36.400327 -111.149921) (xy 36.361593 -111.22771) (xy 36.315846 -111.301594)
			(xy 36.263477 -111.370941) (xy 36.204933 -111.435161) (xy 36.140713 -111.493705) (xy 36.071366 -111.546074)
			(xy 36.026148 -111.574072) (xy 40.008808 -111.574072) (xy 40.012879 -111.51845) (xy 40.025005 -111.464013)
			(xy 40.044928 -111.411922) (xy 40.072224 -111.363287) (xy 40.10631 -111.319144) (xy 40.146459 -111.280435)
			(xy 40.191817 -111.247984) (xy 40.241417 -111.222483) (xy 40.294201 -111.204476) (xy 40.349044 -111.194346)
			(xy 40.404778 -111.192309) (xy 40.460215 -111.198409) (xy 40.514172 -111.212515) (xy 40.565501 -111.234327)
			(xy 40.613107 -111.263381) (xy 40.655975 -111.299056) (xy 40.693192 -111.340593) (xy 40.723965 -111.387106)
			(xy 40.747637 -111.437603) (xy 40.763705 -111.49101) (xy 40.771825 -111.546186) (xy 40.772334 -111.574072)
			(xy 40.771825 -111.601958) (xy 40.763705 -111.657134) (xy 40.747637 -111.710541) (xy 40.723965 -111.761038)
			(xy 40.693192 -111.807551) (xy 40.655975 -111.849088) (xy 40.613107 -111.884763) (xy 40.565501 -111.913817)
			(xy 40.514172 -111.935629) (xy 40.460215 -111.949735) (xy 40.404778 -111.955835) (xy 40.349044 -111.953798)
			(xy 40.294201 -111.943668) (xy 40.241417 -111.925661) (xy 40.191817 -111.90016) (xy 40.146459 -111.867709)
			(xy 40.10631 -111.829) (xy 40.072224 -111.784857) (xy 40.044928 -111.736222) (xy 40.025005 -111.684131)
			(xy 40.012879 -111.629694) (xy 40.008808 -111.574072) (xy 36.026148 -111.574072) (xy 35.997482 -111.591821)
			(xy 35.919693 -111.630555) (xy 35.838661 -111.661947) (xy 35.755079 -111.685728) (xy 35.669659 -111.701696)
			(xy 35.58313 -111.709714) (xy 35.49623 -111.709714) (xy 35.409701 -111.701696) (xy 35.324281 -111.685728)
			(xy 35.240699 -111.661947) (xy 35.159667 -111.630555) (xy 35.081878 -111.591821) (xy 35.007994 -111.546074)
			(xy 34.938647 -111.493705) (xy 34.874427 -111.435161) (xy 34.815883 -111.370941) (xy 34.763514 -111.301594)
			(xy 34.717767 -111.22771) (xy 34.679033 -111.149921) (xy 34.647641 -111.068889) (xy 34.62386 -110.985307)
			(xy 34.607892 -110.899887) (xy 34.599874 -110.813358) (xy 31.398833 -110.813358) (xy 31.39807 -110.839805)
			(xy 31.38774 -110.925233) (xy 31.369648 -111.009359) (xy 31.343945 -111.09148) (xy 31.310846 -111.17091)
			(xy 31.270628 -111.246982) (xy 31.223627 -111.319062) (xy 31.197296 -111.353092) (xy 31.170917 -111.385709)
			(xy 31.113228 -111.44662) (xy 31.050344 -111.502151) (xy 30.982764 -111.551861) (xy 30.911025 -111.595355)
			(xy 30.835698 -111.632287) (xy 30.757382 -111.662363) (xy 30.676697 -111.685345) (xy 30.594287 -111.70105)
			(xy 30.510805 -111.709354) (xy 30.426916 -111.710189) (xy 30.343286 -111.70355) (xy 30.260579 -111.689489)
			(xy 30.219904 -111.679228) (xy 30.181352 -111.668627) (xy 30.106047 -111.641736) (xy 30.033298 -111.608547)
			(xy 29.96363 -111.5693) (xy 29.930344 -111.547148) (xy 29.917425 -111.538877) (xy 29.888706 -111.528125)
			(xy 29.858251 -111.524543) (xy 29.827821 -111.528339) (xy 29.799178 -111.539294) (xy 29.773981 -111.556772)
			(xy 29.753689 -111.579763) (xy 29.739474 -111.606936) (xy 29.732162 -111.636717) (xy 29.731716 -111.65205)
			(xy 29.731716 -111.795052) (xy 29.4005 -112.126268) (xy 29.4005 -112.668558) (xy 29.400954 -112.683805)
			(xy 29.408199 -112.713425) (xy 29.422261 -112.740483) (xy 29.442339 -112.763434) (xy 29.467287 -112.780969)
			(xy 29.495682 -112.792087) (xy 29.510736 -112.794542) (xy 29.531497 -112.796872) (xy 29.57325 -112.795527)
			(xy 29.614221 -112.787375) (xy 29.653308 -112.772635) (xy 29.68946 -112.751704) (xy 29.721704 -112.725144)
			(xy 29.73578 -112.709706) (xy 29.763898 -112.676555) (xy 29.825324 -112.615038) (xy 29.892165 -112.559453)
			(xy 29.963852 -112.510274) (xy 30.039772 -112.467922) (xy 30.119276 -112.432758) (xy 30.201687 -112.405082)
			(xy 30.2863 -112.38513) (xy 30.372394 -112.373073) (xy 30.459233 -112.369014) (xy 30.546076 -112.372987)
			(xy 30.632181 -112.384959) (xy 30.716815 -112.404826) (xy 30.799253 -112.43242) (xy 30.878792 -112.467506)
			(xy 30.954754 -112.509782) (xy 31.026489 -112.55889) (xy 31.093386 -112.614408) (xy 31.154873 -112.675864)
			(xy 31.210425 -112.742733) (xy 31.259569 -112.814444) (xy 31.301883 -112.890384) (xy 31.337009 -112.969906)
			(xy 31.364644 -113.05233) (xy 31.384555 -113.136953) (xy 31.396569 -113.223053) (xy 31.400586 -113.309894)
			(xy 31.398576 -113.353358) (xy 34.599874 -113.353358) (xy 34.599874 -113.266458) (xy 34.607892 -113.179929)
			(xy 34.62386 -113.094509) (xy 34.647641 -113.010927) (xy 34.679033 -112.929895) (xy 34.717767 -112.852106)
			(xy 34.763514 -112.778222) (xy 34.815883 -112.708875) (xy 34.874427 -112.644655) (xy 34.938647 -112.586111)
			(xy 35.007994 -112.533742) (xy 35.081878 -112.487995) (xy 35.159667 -112.449261) (xy 35.240699 -112.417869)
			(xy 35.324281 -112.394088) (xy 35.409701 -112.37812) (xy 35.49623 -112.370102) (xy 35.58313 -112.370102)
			(xy 35.669659 -112.37812) (xy 35.755079 -112.394088) (xy 35.838661 -112.417869) (xy 35.919693 -112.449261)
			(xy 35.997482 -112.487995) (xy 36.071366 -112.533742) (xy 36.140713 -112.586111) (xy 36.204933 -112.644655)
			(xy 36.263477 -112.708875) (xy 36.315846 -112.778222) (xy 36.361593 -112.852106) (xy 36.400327 -112.929895)
			(xy 36.431719 -113.010927) (xy 36.4555 -113.094509) (xy 36.471468 -113.179929) (xy 36.479486 -113.266458)
			(xy 36.479988 -113.309908) (xy 36.479486 -113.353358) (xy 36.471468 -113.439887) (xy 36.4555 -113.525307)
			(xy 36.431719 -113.608889) (xy 36.400327 -113.689921) (xy 36.361593 -113.76771) (xy 36.315846 -113.841594)
			(xy 36.263477 -113.910941) (xy 36.204933 -113.975161) (xy 36.140713 -114.033705) (xy 36.071366 -114.086074)
			(xy 35.997482 -114.131821) (xy 35.919693 -114.170555) (xy 35.838661 -114.201947) (xy 35.755079 -114.225728)
			(xy 35.669659 -114.241696) (xy 35.58313 -114.249714) (xy 35.49623 -114.249714) (xy 35.409701 -114.241696)
			(xy 35.324281 -114.225728) (xy 35.240699 -114.201947) (xy 35.159667 -114.170555) (xy 35.081878 -114.131821)
			(xy 35.007994 -114.086074) (xy 34.938647 -114.033705) (xy 34.874427 -113.975161) (xy 34.815883 -113.910941)
			(xy 34.763514 -113.841594) (xy 34.717767 -113.76771) (xy 34.679033 -113.689921) (xy 34.647641 -113.608889)
			(xy 34.62386 -113.525307) (xy 34.607892 -113.439887) (xy 34.599874 -113.353358) (xy 31.398576 -113.353358)
			(xy 31.39657 -113.396735) (xy 31.384557 -113.482835) (xy 31.364648 -113.567458) (xy 31.337013 -113.649883)
			(xy 31.301889 -113.729405) (xy 31.259575 -113.805346) (xy 31.210433 -113.877057) (xy 31.154881 -113.943927)
			(xy 31.093395 -114.005383) (xy 31.026499 -114.060903) (xy 30.954764 -114.110011) (xy 30.878803 -114.152289)
			(xy 30.799264 -114.187375) (xy 30.716826 -114.21497) (xy 30.632194 -114.234839) (xy 30.546088 -114.246812)
			(xy 30.459245 -114.250786) (xy 30.372406 -114.246728) (xy 30.286312 -114.234672) (xy 30.201699 -114.214721)
			(xy 30.119288 -114.187046) (xy 30.039783 -114.151883) (xy 29.963862 -114.109532) (xy 29.892175 -114.060355)
			(xy 29.825333 -114.00477) (xy 29.763906 -113.943254) (xy 29.73578 -113.91011) (xy 29.721738 -113.894635)
			(xy 29.689504 -113.86805) (xy 29.653349 -113.847107) (xy 29.61425 -113.832373) (xy 29.573265 -113.824245)
			(xy 29.531502 -113.822944) (xy 29.510736 -113.825274) (xy 29.495673 -113.827723) (xy 29.467249 -113.838805)
			(xy 29.442274 -113.856327) (xy 29.422182 -113.879285) (xy 29.408124 -113.906361) (xy 29.400907 -113.936003)
			(xy 29.4005 -113.951258) (xy 29.4005 -115.208558) (xy 29.400954 -115.223805) (xy 29.408199 -115.253425)
			(xy 29.422261 -115.280483) (xy 29.442339 -115.303434) (xy 29.467287 -115.320969) (xy 29.495682 -115.332087)
			(xy 29.510736 -115.334542) (xy 29.531497 -115.336872) (xy 29.57325 -115.335527) (xy 29.614221 -115.327375)
			(xy 29.653308 -115.312635) (xy 29.68946 -115.291704) (xy 29.721704 -115.265144) (xy 29.73578 -115.249706)
			(xy 29.763898 -115.216555) (xy 29.825324 -115.155038) (xy 29.892165 -115.099453) (xy 29.963852 -115.050274)
			(xy 30.039772 -115.007922) (xy 30.119276 -114.972758) (xy 30.201687 -114.945082) (xy 30.2863 -114.92513)
			(xy 30.372394 -114.913073) (xy 30.459233 -114.909014) (xy 30.546076 -114.912987) (xy 30.632181 -114.924959)
			(xy 30.716815 -114.944826) (xy 30.799253 -114.97242) (xy 30.878792 -115.007506) (xy 30.954754 -115.049782)
			(xy 31.026489 -115.09889) (xy 31.093386 -115.154408) (xy 31.154873 -115.215864) (xy 31.210425 -115.282733)
			(xy 31.259569 -115.354444) (xy 31.301883 -115.430384) (xy 31.337009 -115.509906) (xy 31.364644 -115.59233)
			(xy 31.384555 -115.676953) (xy 31.396569 -115.763053) (xy 31.400586 -115.849894) (xy 31.398576 -115.893358)
			(xy 34.599874 -115.893358) (xy 34.599874 -115.806458) (xy 34.607892 -115.719929) (xy 34.62386 -115.634509)
			(xy 34.647641 -115.550927) (xy 34.679033 -115.469895) (xy 34.717767 -115.392106) (xy 34.763514 -115.318222)
			(xy 34.815883 -115.248875) (xy 34.874427 -115.184655) (xy 34.938647 -115.126111) (xy 35.007994 -115.073742)
			(xy 35.081878 -115.027995) (xy 35.159667 -114.989261) (xy 35.240699 -114.957869) (xy 35.324281 -114.934088)
			(xy 35.409701 -114.91812) (xy 35.49623 -114.910102) (xy 35.58313 -114.910102) (xy 35.669659 -114.91812)
			(xy 35.755079 -114.934088) (xy 35.838661 -114.957869) (xy 35.919693 -114.989261) (xy 35.997482 -115.027995)
			(xy 36.071366 -115.073742) (xy 36.140713 -115.126111) (xy 36.204933 -115.184655) (xy 36.263477 -115.248875)
			(xy 36.315846 -115.318222) (xy 36.361593 -115.392106) (xy 36.400327 -115.469895) (xy 36.431719 -115.550927)
			(xy 36.4555 -115.634509) (xy 36.471468 -115.719929) (xy 36.479486 -115.806458) (xy 36.479988 -115.849908)
			(xy 36.479486 -115.893358) (xy 36.471468 -115.979887) (xy 36.4555 -116.065307) (xy 36.431719 -116.148889)
			(xy 36.400327 -116.229921) (xy 36.361593 -116.30771) (xy 36.315846 -116.381594) (xy 36.263477 -116.450941)
			(xy 36.204933 -116.515161) (xy 36.140713 -116.573705) (xy 36.071366 -116.626074) (xy 35.997482 -116.671821)
			(xy 35.919693 -116.710555) (xy 35.838661 -116.741947) (xy 35.755079 -116.765728) (xy 35.669659 -116.781696)
			(xy 35.58313 -116.789714) (xy 35.49623 -116.789714) (xy 35.409701 -116.781696) (xy 35.324281 -116.765728)
			(xy 35.240699 -116.741947) (xy 35.159667 -116.710555) (xy 35.081878 -116.671821) (xy 35.007994 -116.626074)
			(xy 34.938647 -116.573705) (xy 34.874427 -116.515161) (xy 34.815883 -116.450941) (xy 34.763514 -116.381594)
			(xy 34.717767 -116.30771) (xy 34.679033 -116.229921) (xy 34.647641 -116.148889) (xy 34.62386 -116.065307)
			(xy 34.607892 -115.979887) (xy 34.599874 -115.893358) (xy 31.398576 -115.893358) (xy 31.39657 -115.936735)
			(xy 31.384557 -116.022835) (xy 31.364648 -116.107458) (xy 31.337013 -116.189883) (xy 31.301889 -116.269405)
			(xy 31.259575 -116.345346) (xy 31.210433 -116.417057) (xy 31.154881 -116.483927) (xy 31.093395 -116.545383)
			(xy 31.026499 -116.600903) (xy 30.954764 -116.650011) (xy 30.878803 -116.692289) (xy 30.799264 -116.727375)
			(xy 30.716826 -116.75497) (xy 30.632194 -116.774839) (xy 30.546088 -116.786812) (xy 30.459245 -116.790786)
			(xy 30.372406 -116.786728) (xy 30.286312 -116.774672) (xy 30.201699 -116.754721) (xy 30.119288 -116.727046)
			(xy 30.039783 -116.691883) (xy 29.963862 -116.649532) (xy 29.892175 -116.600355) (xy 29.825333 -116.54477)
			(xy 29.763906 -116.483254) (xy 29.73578 -116.45011) (xy 29.721738 -116.434635) (xy 29.689504 -116.40805)
			(xy 29.653349 -116.387107) (xy 29.61425 -116.372373) (xy 29.573265 -116.364245) (xy 29.531502 -116.362944)
			(xy 29.510736 -116.365274) (xy 29.495673 -116.367723) (xy 29.467249 -116.378805) (xy 29.442274 -116.396327)
			(xy 29.422182 -116.419285) (xy 29.408124 -116.446361) (xy 29.400907 -116.476003) (xy 29.4005 -116.491258)
			(xy 29.4005 -117.275426) (xy 39.351236 -117.275426) (xy 39.355121 -117.221063) (xy 39.366703 -117.167807)
			(xy 39.385747 -117.116741) (xy 39.411865 -117.068905) (xy 39.444526 -117.025273) (xy 39.483063 -116.986734)
			(xy 39.526694 -116.954072) (xy 39.574529 -116.927953) (xy 39.625594 -116.908907) (xy 39.67885 -116.897323)
			(xy 39.733213 -116.893436) (xy 39.787576 -116.897326) (xy 39.840831 -116.908914) (xy 39.891895 -116.927963)
			(xy 39.939728 -116.954086) (xy 39.96182 -116.970048) (xy 39.980832 -116.983644) (xy 40.022715 -117.004376)
			(xy 40.067683 -117.017102) (xy 40.11422 -117.021392) (xy 40.160757 -117.017102) (xy 40.205725 -117.004376)
			(xy 40.247608 -116.983644) (xy 40.26662 -116.970048) (xy 40.288749 -116.954149) (xy 40.33657 -116.928037)
			(xy 40.387621 -116.908997) (xy 40.440862 -116.897416) (xy 40.49521 -116.893531) (xy 40.549557 -116.897419)
			(xy 40.602797 -116.909003) (xy 40.653847 -116.928045) (xy 40.701667 -116.95416) (xy 40.745284 -116.986814)
			(xy 40.78381 -117.025343) (xy 40.81646 -117.068963) (xy 40.841655 -117.115111) (xy 57.923274 -117.115111)
			(xy 57.92716 -117.060755) (xy 57.938743 -117.007505) (xy 57.957786 -116.956446) (xy 57.983902 -116.908617)
			(xy 58.016559 -116.864992) (xy 58.055093 -116.826458) (xy 58.098719 -116.793801) (xy 58.146548 -116.767685)
			(xy 58.197607 -116.748642) (xy 58.250857 -116.73706) (xy 58.305213 -116.733174) (xy 58.359568 -116.737063)
			(xy 58.412817 -116.748649) (xy 58.463875 -116.767696) (xy 58.511703 -116.793815) (xy 58.533792 -116.809774)
			(xy 58.552804 -116.82337) (xy 58.594687 -116.844102) (xy 58.639655 -116.856828) (xy 58.686192 -116.861118)
			(xy 58.732729 -116.856828) (xy 58.777697 -116.844102) (xy 58.81958 -116.82337) (xy 58.838592 -116.809774)
			(xy 58.860697 -116.793838) (xy 58.908522 -116.767718) (xy 58.959578 -116.748671) (xy 59.012824 -116.737084)
			(xy 59.067178 -116.733193) (xy 59.121532 -116.737078) (xy 59.17478 -116.748659) (xy 59.225838 -116.7677)
			(xy 59.273666 -116.793814) (xy 59.317291 -116.826469) (xy 59.355823 -116.865001) (xy 59.38848 -116.908625)
			(xy 59.414596 -116.956452) (xy 59.433638 -117.007509) (xy 59.445221 -117.060757) (xy 59.449107 -117.115111)
			(xy 59.445218 -117.169465) (xy 59.433632 -117.222712) (xy 59.414587 -117.273768) (xy 59.388468 -117.321594)
			(xy 59.355809 -117.365215) (xy 59.317274 -117.403745) (xy 59.273648 -117.436398) (xy 59.225818 -117.462509)
			(xy 59.17476 -117.481548) (xy 59.121511 -117.493125) (xy 59.067157 -117.497007) (xy 59.012803 -117.493113)
			(xy 58.959557 -117.481523) (xy 58.908503 -117.462473) (xy 58.860679 -117.436351) (xy 58.838592 -117.42039)
			(xy 58.81958 -117.406794) (xy 58.777697 -117.386062) (xy 58.732729 -117.373336) (xy 58.686192 -117.369046)
			(xy 58.639655 -117.373336) (xy 58.594687 -117.386062) (xy 58.552804 -117.406794) (xy 58.533792 -117.42039)
			(xy 58.511721 -117.436374) (xy 58.463895 -117.462495) (xy 58.412838 -117.481545) (xy 58.35959 -117.493133)
			(xy 58.305234 -117.497026) (xy 58.250878 -117.493143) (xy 58.197628 -117.481564) (xy 58.146568 -117.462524)
			(xy 58.098737 -117.436411) (xy 58.055109 -117.403756) (xy 58.016574 -117.365225) (xy 57.983914 -117.321601)
			(xy 57.957795 -117.273774) (xy 57.938749 -117.222715) (xy 57.927163 -117.169467) (xy 57.923274 -117.115111)
			(xy 40.841655 -117.115111) (xy 40.84257 -117.116786) (xy 40.861608 -117.167837) (xy 40.873186 -117.221079)
			(xy 40.877069 -117.275426) (xy 40.873178 -117.329773) (xy 40.861593 -117.383013) (xy 40.842548 -117.434062)
			(xy 40.816431 -117.481881) (xy 40.783775 -117.525497) (xy 40.745244 -117.564021) (xy 40.701623 -117.596669)
			(xy 40.653799 -117.622777) (xy 40.640038 -117.627908) (xy 67.11137 -117.627908) (xy 67.115441 -117.572286)
			(xy 67.127567 -117.517849) (xy 67.14749 -117.465758) (xy 67.174786 -117.417123) (xy 67.208872 -117.37298)
			(xy 67.249021 -117.334271) (xy 67.294379 -117.30182) (xy 67.343979 -117.276319) (xy 67.396763 -117.258312)
			(xy 67.451606 -117.248182) (xy 67.50734 -117.246145) (xy 67.562777 -117.252245) (xy 67.616734 -117.266351)
			(xy 67.668063 -117.288163) (xy 67.715669 -117.317217) (xy 67.758537 -117.352892) (xy 67.795754 -117.394429)
			(xy 67.826527 -117.440942) (xy 67.850199 -117.491439) (xy 67.866267 -117.544846) (xy 67.874387 -117.600022)
			(xy 67.874882 -117.627146) (xy 69.465696 -117.627146) (xy 69.469767 -117.571524) (xy 69.481893 -117.517087)
			(xy 69.501816 -117.464996) (xy 69.529112 -117.416361) (xy 69.563198 -117.372218) (xy 69.603347 -117.333509)
			(xy 69.648705 -117.301058) (xy 69.698305 -117.275557) (xy 69.751089 -117.25755) (xy 69.805932 -117.24742)
			(xy 69.861666 -117.245383) (xy 69.917103 -117.251483) (xy 69.97106 -117.265589) (xy 70.022389 -117.287401)
			(xy 70.069995 -117.316455) (xy 70.112863 -117.35213) (xy 70.15008 -117.393667) (xy 70.180853 -117.44018)
			(xy 70.204525 -117.490677) (xy 70.220593 -117.544084) (xy 70.228713 -117.59926) (xy 70.229222 -117.627146)
			(xy 70.228713 -117.655032) (xy 70.220593 -117.710208) (xy 70.204525 -117.763615) (xy 70.180853 -117.814112)
			(xy 70.15008 -117.860625) (xy 70.112863 -117.902162) (xy 70.069995 -117.937837) (xy 70.022389 -117.966891)
			(xy 69.97106 -117.988703) (xy 69.917103 -118.002809) (xy 69.861666 -118.008909) (xy 69.805932 -118.006872)
			(xy 69.751089 -117.996742) (xy 69.698305 -117.978735) (xy 69.648705 -117.953234) (xy 69.603347 -117.920783)
			(xy 69.563198 -117.882074) (xy 69.529112 -117.837931) (xy 69.501816 -117.789296) (xy 69.481893 -117.737205)
			(xy 69.469767 -117.682768) (xy 69.465696 -117.627146) (xy 67.874882 -117.627146) (xy 67.874896 -117.627908)
			(xy 67.874387 -117.655794) (xy 67.866267 -117.71097) (xy 67.850199 -117.764377) (xy 67.826527 -117.814874)
			(xy 67.795754 -117.861387) (xy 67.758537 -117.902924) (xy 67.715669 -117.938599) (xy 67.668063 -117.967653)
			(xy 67.616734 -117.989465) (xy 67.562777 -118.003571) (xy 67.50734 -118.009671) (xy 67.451606 -118.007634)
			(xy 67.396763 -117.997504) (xy 67.343979 -117.979497) (xy 67.294379 -117.953996) (xy 67.249021 -117.921545)
			(xy 67.208872 -117.882836) (xy 67.174786 -117.838693) (xy 67.14749 -117.790058) (xy 67.127567 -117.737967)
			(xy 67.115441 -117.68353) (xy 67.11137 -117.627908) (xy 40.640038 -117.627908) (xy 40.602747 -117.641812)
			(xy 40.549505 -117.653388) (xy 40.495157 -117.657269) (xy 40.44081 -117.653376) (xy 40.387571 -117.641788)
			(xy 40.336522 -117.622741) (xy 40.288705 -117.596622) (xy 40.26662 -117.580664) (xy 40.247608 -117.567068)
			(xy 40.205725 -117.546336) (xy 40.160757 -117.53361) (xy 40.11422 -117.52932) (xy 40.067683 -117.53361)
			(xy 40.022715 -117.546336) (xy 39.980832 -117.567068) (xy 39.96182 -117.580664) (xy 39.939773 -117.596685)
			(xy 39.891943 -117.622815) (xy 39.840882 -117.641871) (xy 39.787628 -117.653466) (xy 39.733266 -117.657364)
			(xy 39.678903 -117.653485) (xy 39.625645 -117.641908) (xy 39.574577 -117.622869) (xy 39.526738 -117.596756)
			(xy 39.483103 -117.5641) (xy 39.44456 -117.525567) (xy 39.411894 -117.481939) (xy 39.385769 -117.434107)
			(xy 39.366718 -117.383044) (xy 39.355128 -117.329789) (xy 39.351236 -117.275426) (xy 29.4005 -117.275426)
			(xy 29.4005 -117.748558) (xy 29.400954 -117.763805) (xy 29.408199 -117.793425) (xy 29.422261 -117.820483)
			(xy 29.442339 -117.843434) (xy 29.467287 -117.860969) (xy 29.495682 -117.872087) (xy 29.510736 -117.874542)
			(xy 29.531497 -117.876872) (xy 29.57325 -117.875527) (xy 29.614221 -117.867375) (xy 29.653308 -117.852635)
			(xy 29.68946 -117.831704) (xy 29.721704 -117.805144) (xy 29.73578 -117.789706) (xy 29.763898 -117.756555)
			(xy 29.825324 -117.695038) (xy 29.892165 -117.639453) (xy 29.963852 -117.590274) (xy 30.039772 -117.547922)
			(xy 30.119276 -117.512758) (xy 30.201687 -117.485082) (xy 30.2863 -117.46513) (xy 30.372394 -117.453073)
			(xy 30.459233 -117.449014) (xy 30.546076 -117.452987) (xy 30.632181 -117.464959) (xy 30.716815 -117.484826)
			(xy 30.799253 -117.51242) (xy 30.878792 -117.547506) (xy 30.954754 -117.589782) (xy 31.026489 -117.63889)
			(xy 31.093386 -117.694408) (xy 31.154873 -117.755864) (xy 31.210425 -117.822733) (xy 31.259569 -117.894444)
			(xy 31.301883 -117.970384) (xy 31.337009 -118.049906) (xy 31.364644 -118.13233) (xy 31.384555 -118.216953)
			(xy 31.396569 -118.303053) (xy 31.400586 -118.389894) (xy 31.398576 -118.433358) (xy 34.599874 -118.433358)
			(xy 34.599874 -118.346458) (xy 34.607892 -118.259929) (xy 34.62386 -118.174509) (xy 34.647641 -118.090927)
			(xy 34.679033 -118.009895) (xy 34.717767 -117.932106) (xy 34.763514 -117.858222) (xy 34.815883 -117.788875)
			(xy 34.874427 -117.724655) (xy 34.938647 -117.666111) (xy 35.007994 -117.613742) (xy 35.081878 -117.567995)
			(xy 35.159667 -117.529261) (xy 35.240699 -117.497869) (xy 35.324281 -117.474088) (xy 35.409701 -117.45812)
			(xy 35.49623 -117.450102) (xy 35.58313 -117.450102) (xy 35.669659 -117.45812) (xy 35.755079 -117.474088)
			(xy 35.838661 -117.497869) (xy 35.919693 -117.529261) (xy 35.997482 -117.567995) (xy 36.071366 -117.613742)
			(xy 36.140713 -117.666111) (xy 36.204933 -117.724655) (xy 36.263477 -117.788875) (xy 36.315846 -117.858222)
			(xy 36.361593 -117.932106) (xy 36.400327 -118.009895) (xy 36.431719 -118.090927) (xy 36.4555 -118.174509)
			(xy 36.471468 -118.259929) (xy 36.479486 -118.346458) (xy 36.479988 -118.389908) (xy 36.479486 -118.433358)
			(xy 36.471468 -118.519887) (xy 36.4555 -118.605307) (xy 36.431719 -118.688889) (xy 36.400327 -118.769921)
			(xy 36.361593 -118.84771) (xy 36.315846 -118.921594) (xy 36.263477 -118.990941) (xy 36.204933 -119.055161)
			(xy 36.145862 -119.109011) (xy 39.351257 -119.109011) (xy 39.355144 -119.054651) (xy 39.366727 -119.001398)
			(xy 39.385772 -118.950335) (xy 39.411891 -118.902503) (xy 39.444551 -118.858875) (xy 39.483089 -118.82034)
			(xy 39.526718 -118.787681) (xy 39.574551 -118.761565) (xy 39.625615 -118.742522) (xy 39.678869 -118.730941)
			(xy 39.733229 -118.727057) (xy 39.787588 -118.730949) (xy 39.84084 -118.742539) (xy 39.891901 -118.761589)
			(xy 39.93973 -118.787712) (xy 39.96182 -118.803674) (xy 39.980832 -118.81727) (xy 40.022715 -118.838002)
			(xy 40.067683 -118.850728) (xy 40.11422 -118.855018) (xy 40.160757 -118.850728) (xy 40.205725 -118.838002)
			(xy 40.247608 -118.81727) (xy 40.26662 -118.803674) (xy 40.288725 -118.78774) (xy 40.336548 -118.761625)
			(xy 40.387601 -118.742582) (xy 40.440844 -118.730998) (xy 40.495194 -118.72711) (xy 40.549544 -118.730996)
			(xy 40.602788 -118.742578) (xy 40.653842 -118.76162) (xy 40.701666 -118.787734) (xy 40.745286 -118.820388)
			(xy 40.783815 -118.858918) (xy 40.816469 -118.902539) (xy 40.841671 -118.948695) (xy 57.923295 -118.948695)
			(xy 57.927183 -118.894342) (xy 57.938767 -118.841096) (xy 57.957811 -118.790041) (xy 57.983928 -118.742215)
			(xy 58.016585 -118.698594) (xy 58.055119 -118.660064) (xy 58.098743 -118.62741) (xy 58.146571 -118.601298)
			(xy 58.197628 -118.582258) (xy 58.250875 -118.570678) (xy 58.305228 -118.566795) (xy 58.359581 -118.570686)
			(xy 58.412826 -118.582274) (xy 58.463881 -118.601321) (xy 58.511705 -118.627441) (xy 58.533792 -118.6434)
			(xy 58.552804 -118.656996) (xy 58.594687 -118.677728) (xy 58.639655 -118.690454) (xy 58.686192 -118.694744)
			(xy 58.732729 -118.690454) (xy 58.777697 -118.677728) (xy 58.81958 -118.656996) (xy 58.838592 -118.6434)
			(xy 58.860673 -118.627429) (xy 58.908499 -118.601306) (xy 58.959557 -118.582255) (xy 59.012806 -118.570665)
			(xy 59.067163 -118.566772) (xy 59.12152 -118.570655) (xy 59.174771 -118.582234) (xy 59.225833 -118.601274)
			(xy 59.273664 -118.627388) (xy 59.317292 -118.660044) (xy 59.355829 -118.698576) (xy 59.388489 -118.7422)
			(xy 59.414608 -118.790029) (xy 59.433654 -118.841088) (xy 59.445239 -118.894338) (xy 59.449128 -118.948695)
			(xy 60.16427 -118.948695) (xy 60.168158 -118.894337) (xy 60.179744 -118.841085) (xy 60.198791 -118.790024)
			(xy 60.224912 -118.742194) (xy 60.257573 -118.698569) (xy 60.296112 -118.660036) (xy 60.339742 -118.627381)
			(xy 60.387576 -118.601267) (xy 60.43864 -118.582228) (xy 60.491893 -118.57065) (xy 60.546252 -118.56677)
			(xy 60.60061 -118.570665) (xy 60.653861 -118.582258) (xy 60.704919 -118.601311) (xy 60.752746 -118.627437)
			(xy 60.774834 -118.6434) (xy 60.793846 -118.656996) (xy 60.835729 -118.677728) (xy 60.880697 -118.690454)
			(xy 60.927234 -118.694744) (xy 60.973771 -118.690454) (xy 61.018739 -118.677728) (xy 61.060622 -118.656996)
			(xy 61.079634 -118.6434) (xy 61.101714 -118.627432) (xy 61.149538 -118.601316) (xy 61.200591 -118.582271)
			(xy 61.253835 -118.570687) (xy 61.308186 -118.566797) (xy 61.362538 -118.570683) (xy 61.415783 -118.582264)
			(xy 61.466838 -118.601305) (xy 61.514663 -118.627418) (xy 61.558286 -118.660071) (xy 61.596817 -118.6986)
			(xy 61.629473 -118.742221) (xy 61.655588 -118.790045) (xy 61.674631 -118.841099) (xy 61.686215 -118.894344)
			(xy 61.690103 -118.948695) (xy 62.068279 -118.948695) (xy 62.072168 -118.894339) (xy 62.083753 -118.841089)
			(xy 62.102799 -118.79003) (xy 62.128918 -118.742202) (xy 62.161578 -118.698578) (xy 62.200114 -118.660047)
			(xy 62.243743 -118.627392) (xy 62.291574 -118.601279) (xy 62.342635 -118.582239) (xy 62.395886 -118.570661)
			(xy 62.450243 -118.566779) (xy 62.504599 -118.570673) (xy 62.557848 -118.582264) (xy 62.608904 -118.601315)
			(xy 62.65673 -118.627439) (xy 62.678818 -118.6434) (xy 62.69783 -118.656996) (xy 62.739713 -118.677728)
			(xy 62.784681 -118.690454) (xy 62.831218 -118.694744) (xy 62.877755 -118.690454) (xy 62.922723 -118.677728)
			(xy 62.964606 -118.656996) (xy 62.983618 -118.6434) (xy 63.005698 -118.627431) (xy 63.053523 -118.601312)
			(xy 63.104578 -118.582265) (xy 63.157824 -118.570679) (xy 63.212177 -118.566788) (xy 63.266531 -118.570672)
			(xy 63.319779 -118.582253) (xy 63.370836 -118.601293) (xy 63.418664 -118.627406) (xy 63.462288 -118.660061)
			(xy 63.500821 -118.698591) (xy 63.533479 -118.742213) (xy 63.559595 -118.790039) (xy 63.57864 -118.841095)
			(xy 63.590224 -118.894342) (xy 63.594112 -118.948695) (xy 63.590225 -119.003049) (xy 63.578642 -119.056296)
			(xy 63.559599 -119.107352) (xy 63.533484 -119.155179) (xy 63.500828 -119.198802) (xy 63.462296 -119.237333)
			(xy 63.418672 -119.269988) (xy 63.370845 -119.296103) (xy 63.319788 -119.315145) (xy 63.26654 -119.326726)
			(xy 63.212187 -119.330612) (xy 63.157834 -119.326723) (xy 63.104587 -119.315137) (xy 63.053532 -119.296092)
			(xy 63.005706 -119.269974) (xy 62.983618 -119.254016) (xy 62.964606 -119.24042) (xy 62.922723 -119.219688)
			(xy 62.877755 -119.206962) (xy 62.831218 -119.202672) (xy 62.784681 -119.206962) (xy 62.739713 -119.219688)
			(xy 62.69783 -119.24042) (xy 62.678818 -119.254016) (xy 62.656722 -119.269967) (xy 62.608896 -119.296089)
			(xy 62.557838 -119.315139) (xy 62.50459 -119.326728) (xy 62.450233 -119.330621) (xy 62.395877 -119.326738)
			(xy 62.342626 -119.315158) (xy 62.291565 -119.296117) (xy 62.243734 -119.270003) (xy 62.200107 -119.237347)
			(xy 62.161572 -119.198815) (xy 62.128913 -119.15519) (xy 62.102795 -119.107361) (xy 62.08375 -119.056302)
			(xy 62.072166 -119.003052) (xy 62.068279 -118.948695) (xy 61.690103 -118.948695) (xy 61.686216 -119.003046)
			(xy 61.674634 -119.056291) (xy 61.655592 -119.107346) (xy 61.629478 -119.155171) (xy 61.596823 -119.198792)
			(xy 61.558293 -119.237323) (xy 61.514671 -119.269977) (xy 61.466847 -119.296091) (xy 61.415792 -119.315133)
			(xy 61.362547 -119.326716) (xy 61.308196 -119.330603) (xy 61.253845 -119.326715) (xy 61.2006 -119.315131)
			(xy 61.149546 -119.296088) (xy 61.101722 -119.269973) (xy 61.079634 -119.254016) (xy 61.060622 -119.24042)
			(xy 61.018739 -119.219688) (xy 60.973771 -119.206962) (xy 60.927234 -119.202672) (xy 60.880697 -119.206962)
			(xy 60.835729 -119.219688) (xy 60.793846 -119.24042) (xy 60.774834 -119.254016) (xy 60.752738 -119.269968)
			(xy 60.70491 -119.296093) (xy 60.653851 -119.315145) (xy 60.600601 -119.326736) (xy 60.546243 -119.33063)
			(xy 60.491884 -119.326748) (xy 60.43863 -119.315169) (xy 60.387567 -119.296129) (xy 60.339734 -119.270014)
			(xy 60.296105 -119.237358) (xy 60.257567 -119.198824) (xy 60.224906 -119.155198) (xy 60.198787 -119.107367)
			(xy 60.179741 -119.056306) (xy 60.168157 -119.003054) (xy 60.16427 -118.948695) (xy 59.449128 -118.948695)
			(xy 59.445241 -119.003052) (xy 59.433657 -119.056303) (xy 59.414612 -119.107362) (xy 59.388494 -119.155192)
			(xy 59.355835 -119.198817) (xy 59.3173 -119.23735) (xy 59.273672 -119.270007) (xy 59.225841 -119.296122)
			(xy 59.17478 -119.315163) (xy 59.121529 -119.326744) (xy 59.067172 -119.330628) (xy 59.012816 -119.326736)
			(xy 58.959566 -119.315147) (xy 58.908508 -119.296098) (xy 58.860681 -119.269977) (xy 58.838592 -119.254016)
			(xy 58.81958 -119.24042) (xy 58.777697 -119.219688) (xy 58.732729 -119.206962) (xy 58.686192 -119.202672)
			(xy 58.639655 -119.206962) (xy 58.594687 -119.219688) (xy 58.552804 -119.24042) (xy 58.533792 -119.254016)
			(xy 58.511697 -119.269964) (xy 58.463872 -119.296083) (xy 58.412817 -119.315129) (xy 58.359571 -119.326715)
			(xy 58.305219 -119.330605) (xy 58.250866 -119.32672) (xy 58.197619 -119.31514) (xy 58.146562 -119.296098)
			(xy 58.098735 -119.269985) (xy 58.055111 -119.23733) (xy 58.016579 -119.198799) (xy 57.983923 -119.155177)
			(xy 57.957807 -119.107351) (xy 57.938764 -119.056295) (xy 57.927182 -119.003048) (xy 57.923295 -118.948695)
			(xy 40.841671 -118.948695) (xy 40.842582 -118.950363) (xy 40.861623 -119.001417) (xy 40.873204 -119.054661)
			(xy 40.87709 -119.109011) (xy 40.873201 -119.163361) (xy 40.861617 -119.216604) (xy 40.842573 -119.267657)
			(xy 40.816457 -119.31548) (xy 40.783801 -119.359099) (xy 40.74527 -119.397626) (xy 40.701647 -119.430278)
			(xy 40.653822 -119.456389) (xy 40.602767 -119.475428) (xy 40.549523 -119.487007) (xy 40.495173 -119.49089)
			(xy 40.440823 -119.486999) (xy 40.38758 -119.475412) (xy 40.336528 -119.456366) (xy 40.288706 -119.430248)
			(xy 40.26662 -119.41429) (xy 40.247608 -119.400694) (xy 40.205725 -119.379962) (xy 40.160757 -119.367236)
			(xy 40.11422 -119.362946) (xy 40.067683 -119.367236) (xy 40.022715 -119.379962) (xy 39.980832 -119.400694)
			(xy 39.96182 -119.41429) (xy 39.939748 -119.430276) (xy 39.89192 -119.456402) (xy 39.840861 -119.475455)
			(xy 39.787609 -119.487048) (xy 39.73325 -119.490943) (xy 39.67889 -119.487062) (xy 39.625636 -119.475484)
			(xy 39.574571 -119.456444) (xy 39.526736 -119.43033) (xy 39.483105 -119.397674) (xy 39.444566 -119.359141)
			(xy 39.411903 -119.315515) (xy 39.385781 -119.267684) (xy 39.366734 -119.216623) (xy 39.355147 -119.16337)
			(xy 39.351257 -119.109011) (xy 36.145862 -119.109011) (xy 36.140713 -119.113705) (xy 36.071366 -119.166074)
			(xy 35.997482 -119.211821) (xy 35.919693 -119.250555) (xy 35.838661 -119.281947) (xy 35.755079 -119.305728)
			(xy 35.669659 -119.321696) (xy 35.58313 -119.329714) (xy 35.49623 -119.329714) (xy 35.409701 -119.321696)
			(xy 35.324281 -119.305728) (xy 35.240699 -119.281947) (xy 35.159667 -119.250555) (xy 35.081878 -119.211821)
			(xy 35.007994 -119.166074) (xy 34.938647 -119.113705) (xy 34.874427 -119.055161) (xy 34.815883 -118.990941)
			(xy 34.763514 -118.921594) (xy 34.717767 -118.84771) (xy 34.679033 -118.769921) (xy 34.647641 -118.688889)
			(xy 34.62386 -118.605307) (xy 34.607892 -118.519887) (xy 34.599874 -118.433358) (xy 31.398576 -118.433358)
			(xy 31.39657 -118.476735) (xy 31.384557 -118.562835) (xy 31.364648 -118.647458) (xy 31.337013 -118.729883)
			(xy 31.301889 -118.809405) (xy 31.259575 -118.885346) (xy 31.210433 -118.957057) (xy 31.154881 -119.023927)
			(xy 31.093395 -119.085383) (xy 31.026499 -119.140903) (xy 30.954764 -119.190011) (xy 30.878803 -119.232289)
			(xy 30.799264 -119.267375) (xy 30.716826 -119.29497) (xy 30.632194 -119.314839) (xy 30.546088 -119.326812)
			(xy 30.459245 -119.330786) (xy 30.372406 -119.326728) (xy 30.286312 -119.314672) (xy 30.201699 -119.294721)
			(xy 30.119288 -119.267046) (xy 30.039783 -119.231883) (xy 29.963862 -119.189532) (xy 29.892175 -119.140355)
			(xy 29.825333 -119.08477) (xy 29.763906 -119.023254) (xy 29.73578 -118.99011) (xy 29.721738 -118.974635)
			(xy 29.689504 -118.94805) (xy 29.653349 -118.927107) (xy 29.61425 -118.912373) (xy 29.573265 -118.904245)
			(xy 29.531502 -118.902944) (xy 29.510736 -118.905274) (xy 29.495673 -118.907723) (xy 29.467249 -118.918805)
			(xy 29.442274 -118.936327) (xy 29.422182 -118.959285) (xy 29.408124 -118.986361) (xy 29.400907 -119.016003)
			(xy 29.4005 -119.031258) (xy 29.4005 -120.288558) (xy 29.400954 -120.303805) (xy 29.408199 -120.333425)
			(xy 29.422261 -120.360483) (xy 29.442339 -120.383434) (xy 29.467287 -120.400969) (xy 29.495682 -120.412087)
			(xy 29.510736 -120.414542) (xy 29.531497 -120.416872) (xy 29.57325 -120.415527) (xy 29.614221 -120.407375)
			(xy 29.653308 -120.392635) (xy 29.68946 -120.371704) (xy 29.721704 -120.345144) (xy 29.73578 -120.329706)
			(xy 29.763898 -120.296555) (xy 29.825324 -120.235038) (xy 29.892165 -120.179453) (xy 29.963852 -120.130274)
			(xy 30.039772 -120.087922) (xy 30.119276 -120.052758) (xy 30.201687 -120.025082) (xy 30.2863 -120.00513)
			(xy 30.372394 -119.993073) (xy 30.459233 -119.989014) (xy 30.546076 -119.992987) (xy 30.632181 -120.004959)
			(xy 30.716815 -120.024826) (xy 30.799253 -120.05242) (xy 30.878792 -120.087506) (xy 30.954754 -120.129782)
			(xy 31.026489 -120.17889) (xy 31.093386 -120.234408) (xy 31.154873 -120.295864) (xy 31.210425 -120.362733)
			(xy 31.259569 -120.434444) (xy 31.301883 -120.510384) (xy 31.337009 -120.589906) (xy 31.364644 -120.67233)
			(xy 31.384555 -120.756953) (xy 31.396569 -120.843053) (xy 31.400586 -120.929894) (xy 31.398576 -120.973358)
			(xy 34.599874 -120.973358) (xy 34.599874 -120.886458) (xy 34.607892 -120.799929) (xy 34.62386 -120.714509)
			(xy 34.647641 -120.630927) (xy 34.679033 -120.549895) (xy 34.717767 -120.472106) (xy 34.763514 -120.398222)
			(xy 34.815883 -120.328875) (xy 34.874427 -120.264655) (xy 34.938647 -120.206111) (xy 35.007994 -120.153742)
			(xy 35.081878 -120.107995) (xy 35.159667 -120.069261) (xy 35.240699 -120.037869) (xy 35.324281 -120.014088)
			(xy 35.409701 -119.99812) (xy 35.49623 -119.990102) (xy 35.58313 -119.990102) (xy 35.669659 -119.99812)
			(xy 35.755079 -120.014088) (xy 35.838661 -120.037869) (xy 35.919693 -120.069261) (xy 35.997482 -120.107995)
			(xy 36.071366 -120.153742) (xy 36.140713 -120.206111) (xy 36.204933 -120.264655) (xy 36.250573 -120.31472)
			(xy 67.11518 -120.31472) (xy 67.119251 -120.259098) (xy 67.131377 -120.204661) (xy 67.1513 -120.15257)
			(xy 67.178596 -120.103935) (xy 67.212682 -120.059792) (xy 67.252831 -120.021083) (xy 67.298189 -119.988632)
			(xy 67.347789 -119.963131) (xy 67.400573 -119.945124) (xy 67.455416 -119.934994) (xy 67.51115 -119.932957)
			(xy 67.566587 -119.939057) (xy 67.620544 -119.953163) (xy 67.671873 -119.974975) (xy 67.719479 -120.004029)
			(xy 67.762347 -120.039704) (xy 67.799564 -120.081241) (xy 67.830337 -120.127754) (xy 67.854009 -120.178251)
			(xy 67.870077 -120.231658) (xy 67.878197 -120.286834) (xy 67.878706 -120.31472) (xy 67.878197 -120.342606)
			(xy 67.870077 -120.397782) (xy 67.854009 -120.451189) (xy 67.830337 -120.501686) (xy 67.799564 -120.548199)
			(xy 67.762347 -120.589736) (xy 67.719479 -120.625411) (xy 67.671873 -120.654465) (xy 67.620544 -120.676277)
			(xy 67.566587 -120.690383) (xy 67.51115 -120.696483) (xy 67.455416 -120.694446) (xy 67.400573 -120.684316)
			(xy 67.347789 -120.666309) (xy 67.298189 -120.640808) (xy 67.252831 -120.608357) (xy 67.212682 -120.569648)
			(xy 67.178596 -120.525505) (xy 67.1513 -120.47687) (xy 67.131377 -120.424779) (xy 67.119251 -120.370342)
			(xy 67.11518 -120.31472) (xy 36.250573 -120.31472) (xy 36.263477 -120.328875) (xy 36.315846 -120.398222)
			(xy 36.361593 -120.472106) (xy 36.400327 -120.549895) (xy 36.431719 -120.630927) (xy 36.4555 -120.714509)
			(xy 36.471468 -120.799929) (xy 36.479486 -120.886458) (xy 36.479988 -120.929908) (xy 36.479486 -120.973358)
			(xy 36.476101 -121.009889) (xy 39.351286 -121.009889) (xy 39.355175 -120.955534) (xy 39.366761 -120.902285)
			(xy 39.385808 -120.851228) (xy 39.411927 -120.803401) (xy 39.444587 -120.759778) (xy 39.483124 -120.721247)
			(xy 39.526752 -120.688594) (xy 39.574583 -120.662482) (xy 39.625644 -120.643444) (xy 39.678894 -120.631867)
			(xy 39.73325 -120.627986) (xy 39.787605 -120.631881) (xy 39.840853 -120.643472) (xy 39.891908 -120.662524)
			(xy 39.939733 -120.688648) (xy 39.96182 -120.70461) (xy 39.980832 -120.718206) (xy 40.022715 -120.738938)
			(xy 40.067683 -120.751664) (xy 40.11422 -120.755954) (xy 40.160757 -120.751664) (xy 40.205725 -120.738938)
			(xy 40.247608 -120.718206) (xy 40.26662 -120.70461) (xy 40.288691 -120.688627) (xy 40.336516 -120.662508)
			(xy 40.387572 -120.64346) (xy 40.440819 -120.631873) (xy 40.495173 -120.627981) (xy 40.549527 -120.631865)
			(xy 40.602776 -120.643445) (xy 40.653834 -120.662485) (xy 40.701663 -120.688598) (xy 40.745289 -120.721252)
			(xy 40.783823 -120.759782) (xy 40.816482 -120.803405) (xy 40.841694 -120.849574) (xy 57.923323 -120.849574)
			(xy 57.927215 -120.795225) (xy 57.938801 -120.741984) (xy 57.957847 -120.690933) (xy 57.983964 -120.643113)
			(xy 58.016621 -120.599496) (xy 58.055154 -120.560971) (xy 58.098777 -120.528323) (xy 58.146602 -120.502215)
			(xy 58.197657 -120.483179) (xy 58.250901 -120.471604) (xy 58.30525 -120.467723) (xy 58.359598 -120.471618)
			(xy 58.412839 -120.483207) (xy 58.463888 -120.502256) (xy 58.511707 -120.528377) (xy 58.533792 -120.544336)
			(xy 58.552804 -120.557932) (xy 58.594687 -120.578664) (xy 58.639655 -120.59139) (xy 58.686192 -120.59568)
			(xy 58.732729 -120.59139) (xy 58.777697 -120.578664) (xy 58.81958 -120.557932) (xy 58.838592 -120.544336)
			(xy 58.860639 -120.528316) (xy 58.908468 -120.502188) (xy 58.959528 -120.483134) (xy 59.012781 -120.47154)
			(xy 59.067141 -120.467643) (xy 59.121503 -120.471523) (xy 59.174759 -120.4831) (xy 59.225825 -120.502139)
			(xy 59.273662 -120.528252) (xy 59.317295 -120.560908) (xy 59.355836 -120.599441) (xy 59.388502 -120.643067)
			(xy 59.414625 -120.690897) (xy 59.433676 -120.741959) (xy 59.445265 -120.795213) (xy 59.449157 -120.849574)
			(xy 60.164298 -120.849574) (xy 60.16819 -120.795219) (xy 60.179778 -120.741972) (xy 60.198826 -120.690917)
			(xy 60.224947 -120.643092) (xy 60.257609 -120.599471) (xy 60.296147 -120.560944) (xy 60.339776 -120.528293)
			(xy 60.387608 -120.502185) (xy 60.438668 -120.48315) (xy 60.491918 -120.471576) (xy 60.546274 -120.467698)
			(xy 60.600628 -120.471597) (xy 60.653873 -120.483191) (xy 60.704927 -120.502246) (xy 60.752748 -120.528373)
			(xy 60.774834 -120.544336) (xy 60.793846 -120.557932) (xy 60.835729 -120.578664) (xy 60.880697 -120.59139)
			(xy 60.927234 -120.59568) (xy 60.973771 -120.59139) (xy 61.018739 -120.578664) (xy 61.060622 -120.557932)
			(xy 61.079634 -120.544336) (xy 61.10168 -120.52832) (xy 61.149506 -120.502199) (xy 61.200562 -120.48315)
			(xy 61.25381 -120.471561) (xy 61.308165 -120.467669) (xy 61.362521 -120.471551) (xy 61.41577 -120.48313)
			(xy 61.46683 -120.502169) (xy 61.514661 -120.528282) (xy 61.558288 -120.560935) (xy 61.596825 -120.599465)
			(xy 61.629485 -120.643087) (xy 61.655605 -120.690914) (xy 61.674653 -120.741971) (xy 61.68624 -120.795219)
			(xy 61.690131 -120.849574) (xy 62.068308 -120.849574) (xy 62.072199 -120.795222) (xy 62.083787 -120.741977)
			(xy 62.102834 -120.690923) (xy 62.128954 -120.6431) (xy 62.161614 -120.599481) (xy 62.20015 -120.560954)
			(xy 62.243776 -120.528304) (xy 62.291606 -120.502196) (xy 62.342664 -120.483161) (xy 62.395912 -120.471586)
			(xy 62.450265 -120.467708) (xy 62.504616 -120.471605) (xy 62.55786 -120.483197) (xy 62.608912 -120.50225)
			(xy 62.656733 -120.528374) (xy 62.678818 -120.544336) (xy 62.69783 -120.557932) (xy 62.739713 -120.578664)
			(xy 62.784681 -120.59139) (xy 62.831218 -120.59568) (xy 62.877755 -120.59139) (xy 62.922723 -120.578664)
			(xy 62.964606 -120.557932) (xy 62.983618 -120.544336) (xy 63.005664 -120.528318) (xy 63.053491 -120.502195)
			(xy 63.104549 -120.483144) (xy 63.157799 -120.471553) (xy 63.212156 -120.467659) (xy 63.266514 -120.471541)
			(xy 63.319766 -120.483119) (xy 63.370828 -120.502158) (xy 63.418661 -120.52827) (xy 63.462291 -120.560925)
			(xy 63.500829 -120.599456) (xy 63.533491 -120.643079) (xy 63.559613 -120.690908) (xy 63.578661 -120.741966)
			(xy 63.590249 -120.795216) (xy 63.594141 -120.849574) (xy 63.590257 -120.903931) (xy 63.578676 -120.957183)
			(xy 63.559635 -121.008244) (xy 63.53352 -121.056076) (xy 63.500864 -121.099704) (xy 63.462331 -121.138241)
			(xy 63.418706 -121.170901) (xy 63.370876 -121.19702) (xy 63.363809 -121.199656) (xy 72.868035 -121.199656)
			(xy 72.872042 -120.996906) (xy 72.884055 -120.794472) (xy 72.904056 -120.592671) (xy 72.932015 -120.391817)
			(xy 72.967886 -120.192225) (xy 73.011615 -119.994206) (xy 73.063133 -119.798069) (xy 73.122359 -119.604121)
			(xy 73.189201 -119.412663) (xy 73.263555 -119.223996) (xy 73.345304 -119.038414) (xy 73.434322 -118.856206)
			(xy 73.530468 -118.677657) (xy 73.633593 -118.503046) (xy 73.743536 -118.332646) (xy 73.860125 -118.166722)
			(xy 73.983178 -118.005533) (xy 74.112503 -117.849332) (xy 74.247898 -117.698362) (xy 74.389151 -117.552858)
			(xy 74.536043 -117.413049) (xy 74.688343 -117.279152) (xy 74.845814 -117.151377) (xy 75.008211 -117.029922)
			(xy 75.175278 -116.914978) (xy 75.346757 -116.806724) (xy 75.522378 -116.705329) (xy 75.701868 -116.610951)
			(xy 75.884946 -116.523739) (xy 76.071327 -116.443827) (xy 76.26072 -116.37134) (xy 76.452828 -116.306393)
			(xy 76.647352 -116.249085) (xy 76.843988 -116.199508) (xy 77.04243 -116.157737) (xy 77.242367 -116.123839)
			(xy 77.443486 -116.097867) (xy 77.645475 -116.07986) (xy 77.848018 -116.069847) (xy 78.050798 -116.067843)
			(xy 78.253499 -116.073853) (xy 78.455804 -116.087865) (xy 78.657398 -116.10986) (xy 78.857965 -116.139801)
			(xy 79.057193 -116.177642) (xy 79.254771 -116.223325) (xy 79.450389 -116.276778) (xy 79.643743 -116.337917)
			(xy 79.834531 -116.406648) (xy 80.022454 -116.482862) (xy 80.20722 -116.566441) (xy 80.388539 -116.657254)
			(xy 80.56613 -116.755159) (xy 80.739713 -116.860004) (xy 80.909019 -116.971625) (xy 81.073784 -117.089847)
			(xy 81.233749 -117.214487) (xy 81.388665 -117.345348) (xy 81.53829 -117.482228) (xy 81.68239 -117.624912)
			(xy 81.820742 -117.773178) (xy 81.953127 -117.926794) (xy 82.079341 -118.085519) (xy 82.199185 -118.249108)
			(xy 82.312473 -118.417303) (xy 82.419028 -118.589842) (xy 82.518683 -118.766457) (xy 82.611283 -118.94687)
			(xy 82.696683 -119.130801) (xy 82.77475 -119.317962) (xy 82.845362 -119.508062) (xy 82.908408 -119.700802)
			(xy 82.963791 -119.895883) (xy 83.011423 -120.093) (xy 83.051231 -120.291844) (xy 83.083153 -120.492106)
			(xy 83.107137 -120.693472) (xy 83.123148 -120.895629) (xy 83.131159 -121.098261) (xy 83.13166 -121.199656)
			(xy 83.131159 -121.301051) (xy 83.123148 -121.503683) (xy 83.107137 -121.70584) (xy 83.083153 -121.907206)
			(xy 83.051231 -122.107468) (xy 83.011423 -122.306312) (xy 82.963791 -122.503429) (xy 82.908408 -122.69851)
			(xy 82.845362 -122.89125) (xy 82.77475 -123.08135) (xy 82.696683 -123.268511) (xy 82.611283 -123.452442)
			(xy 82.518683 -123.632855) (xy 82.419028 -123.80947) (xy 82.312473 -123.982009) (xy 82.199185 -124.150204)
			(xy 82.079341 -124.313793) (xy 81.953127 -124.472518) (xy 81.820742 -124.626134) (xy 81.68239 -124.7744)
			(xy 81.53829 -124.917084) (xy 81.388665 -125.053964) (xy 81.233749 -125.184825) (xy 81.073784 -125.309465)
			(xy 80.909019 -125.427687) (xy 80.739713 -125.539308) (xy 80.56613 -125.644153) (xy 80.388539 -125.742058)
			(xy 80.20722 -125.832871) (xy 80.022454 -125.91645) (xy 79.834531 -125.992664) (xy 79.643743 -126.061395)
			(xy 79.450389 -126.122534) (xy 79.254771 -126.175987) (xy 79.057193 -126.22167) (xy 78.857965 -126.259511)
			(xy 78.657398 -126.289452) (xy 78.455804 -126.311447) (xy 78.253499 -126.325459) (xy 78.050798 -126.331469)
			(xy 77.848018 -126.329465) (xy 77.645475 -126.319452) (xy 77.443486 -126.301445) (xy 77.242367 -126.275473)
			(xy 77.04243 -126.241575) (xy 76.843988 -126.199804) (xy 76.647352 -126.150227) (xy 76.452828 -126.092919)
			(xy 76.26072 -126.027972) (xy 76.071327 -125.955485) (xy 75.884946 -125.875573) (xy 75.701868 -125.788361)
			(xy 75.522378 -125.693983) (xy 75.346757 -125.592588) (xy 75.175278 -125.484334) (xy 75.008211 -125.36939)
			(xy 74.845814 -125.247935) (xy 74.688343 -125.12016) (xy 74.536043 -124.986263) (xy 74.389151 -124.846454)
			(xy 74.247898 -124.70095) (xy 74.112503 -124.54998) (xy 73.983178 -124.393779) (xy 73.860125 -124.23259)
			(xy 73.743536 -124.066666) (xy 73.633593 -123.896266) (xy 73.530468 -123.721655) (xy 73.434322 -123.543106)
			(xy 73.345304 -123.360898) (xy 73.263555 -123.175316) (xy 73.189201 -122.986649) (xy 73.122359 -122.795191)
			(xy 73.063133 -122.601243) (xy 73.011615 -122.405106) (xy 72.967886 -122.207087) (xy 72.932015 -122.007495)
			(xy 72.904056 -121.806641) (xy 72.884055 -121.60484) (xy 72.872042 -121.402406) (xy 72.868035 -121.199656)
			(xy 63.363809 -121.199656) (xy 63.319817 -121.216066) (xy 63.266566 -121.227652) (xy 63.212209 -121.231541)
			(xy 63.157851 -121.227654) (xy 63.1046 -121.216071) (xy 63.053539 -121.197027) (xy 63.005709 -121.17091)
			(xy 62.983618 -121.154952) (xy 62.964606 -121.141356) (xy 62.922723 -121.120624) (xy 62.877755 -121.107898)
			(xy 62.831218 -121.103608) (xy 62.784681 -121.107898) (xy 62.739713 -121.120624) (xy 62.69783 -121.141356)
			(xy 62.678818 -121.154952) (xy 62.656688 -121.170854) (xy 62.608864 -121.196972) (xy 62.55781 -121.216017)
			(xy 62.504564 -121.227603) (xy 62.450212 -121.231492) (xy 62.395859 -121.227606) (xy 62.342613 -121.216024)
			(xy 62.291558 -121.196982) (xy 62.243732 -121.170867) (xy 62.20011 -121.138211) (xy 62.161579 -121.099679)
			(xy 62.128925 -121.056056) (xy 62.102812 -121.008229) (xy 62.083772 -120.957173) (xy 62.072192 -120.903926)
			(xy 62.068308 -120.849574) (xy 61.690131 -120.849574) (xy 61.686248 -120.903929) (xy 61.674667 -120.957179)
			(xy 61.655627 -121.008238) (xy 61.629514 -121.056068) (xy 61.596859 -121.099695) (xy 61.558328 -121.13823)
			(xy 61.514705 -121.17089) (xy 61.466878 -121.197009) (xy 61.415821 -121.216055) (xy 61.362573 -121.227641)
			(xy 61.308218 -121.231531) (xy 61.253862 -121.227646) (xy 61.200613 -121.216065) (xy 61.149554 -121.197023)
			(xy 61.101725 -121.170909) (xy 61.079634 -121.154952) (xy 61.060622 -121.141356) (xy 61.018739 -121.120624)
			(xy 60.973771 -121.107898) (xy 60.927234 -121.103608) (xy 60.880697 -121.107898) (xy 60.835729 -121.120624)
			(xy 60.793846 -121.141356) (xy 60.774834 -121.154952) (xy 60.752704 -121.170855) (xy 60.704879 -121.196976)
			(xy 60.653823 -121.216024) (xy 60.600575 -121.227611) (xy 60.546221 -121.231502) (xy 60.491866 -121.227617)
			(xy 60.438618 -121.216035) (xy 60.38756 -121.196993) (xy 60.339732 -121.170878) (xy 60.296107 -121.138222)
			(xy 60.257575 -121.099689) (xy 60.224919 -121.056064) (xy 60.198804 -121.008235) (xy 60.179763 -120.957177)
			(xy 60.168182 -120.903928) (xy 60.164298 -120.849574) (xy 59.449157 -120.849574) (xy 59.445272 -120.903935)
			(xy 59.43369 -120.95719) (xy 59.414647 -121.008255) (xy 59.38853 -121.056089) (xy 59.355871 -121.09972)
			(xy 59.317335 -121.138258) (xy 59.273706 -121.170919) (xy 59.225873 -121.197039) (xy 59.174809 -121.216085)
			(xy 59.121555 -121.227669) (xy 59.067194 -121.231557) (xy 59.012833 -121.227667) (xy 58.959579 -121.216081)
			(xy 58.908516 -121.197034) (xy 58.860684 -121.170913) (xy 58.838592 -121.154952) (xy 58.81958 -121.141356)
			(xy 58.777697 -121.120624) (xy 58.732729 -121.107898) (xy 58.686192 -121.103608) (xy 58.639655 -121.107898)
			(xy 58.594687 -121.120624) (xy 58.552804 -121.141356) (xy 58.533792 -121.154952) (xy 58.511663 -121.170852)
			(xy 58.46384 -121.196966) (xy 58.412788 -121.216007) (xy 58.359546 -121.22759) (xy 58.305197 -121.231477)
			(xy 58.250848 -121.227589) (xy 58.197606 -121.216006) (xy 58.146554 -121.196963) (xy 58.098732 -121.170849)
			(xy 58.055114 -121.138194) (xy 58.016587 -121.099664) (xy 57.983935 -121.056043) (xy 57.957825 -121.008219)
			(xy 57.938786 -120.957166) (xy 57.927207 -120.903923) (xy 57.923323 -120.849574) (xy 40.841694 -120.849574)
			(xy 40.842599 -120.851231) (xy 40.861645 -120.902288) (xy 40.87323 -120.955535) (xy 40.877119 -121.009889)
			(xy 40.873233 -121.064244) (xy 40.861651 -121.117492) (xy 40.842608 -121.168549) (xy 40.816493 -121.216377)
			(xy 40.783837 -121.260001) (xy 40.745305 -121.298534) (xy 40.701681 -121.331191) (xy 40.653854 -121.357306)
			(xy 40.602796 -121.376349) (xy 40.549548 -121.387932) (xy 40.495194 -121.391819) (xy 40.44084 -121.387931)
			(xy 40.387592 -121.376346) (xy 40.336536 -121.357301) (xy 40.288709 -121.331184) (xy 40.26662 -121.315226)
			(xy 40.247608 -121.30163) (xy 40.205725 -121.280898) (xy 40.160757 -121.268172) (xy 40.11422 -121.263882)
			(xy 40.067683 -121.268172) (xy 40.022715 -121.280898) (xy 39.980832 -121.30163) (xy 39.96182 -121.315226)
			(xy 39.939714 -121.331163) (xy 39.891889 -121.357285) (xy 39.840832 -121.376334) (xy 39.787584 -121.387922)
			(xy 39.733229 -121.391814) (xy 39.678873 -121.38793) (xy 39.625623 -121.37635) (xy 39.574563 -121.357309)
			(xy 39.526734 -121.331194) (xy 39.483108 -121.298538) (xy 39.444573 -121.260006) (xy 39.411915 -121.216381)
			(xy 39.385799 -121.168553) (xy 39.366755 -121.117494) (xy 39.355172 -121.064245) (xy 39.351286 -121.009889)
			(xy 36.476101 -121.009889) (xy 36.471468 -121.059887) (xy 36.4555 -121.145307) (xy 36.431719 -121.228889)
			(xy 36.400327 -121.309921) (xy 36.361593 -121.38771) (xy 36.315846 -121.461594) (xy 36.263477 -121.530941)
			(xy 36.204933 -121.595161) (xy 36.140713 -121.653705) (xy 36.071366 -121.706074) (xy 35.997482 -121.751821)
			(xy 35.919693 -121.790555) (xy 35.838661 -121.821947) (xy 35.755079 -121.845728) (xy 35.669659 -121.861696)
			(xy 35.58313 -121.869714) (xy 35.49623 -121.869714) (xy 35.409701 -121.861696) (xy 35.324281 -121.845728)
			(xy 35.240699 -121.821947) (xy 35.159667 -121.790555) (xy 35.081878 -121.751821) (xy 35.007994 -121.706074)
			(xy 34.938647 -121.653705) (xy 34.874427 -121.595161) (xy 34.815883 -121.530941) (xy 34.763514 -121.461594)
			(xy 34.717767 -121.38771) (xy 34.679033 -121.309921) (xy 34.647641 -121.228889) (xy 34.62386 -121.145307)
			(xy 34.607892 -121.059887) (xy 34.599874 -120.973358) (xy 31.398576 -120.973358) (xy 31.39657 -121.016735)
			(xy 31.384557 -121.102835) (xy 31.364648 -121.187458) (xy 31.337013 -121.269883) (xy 31.301889 -121.349405)
			(xy 31.259575 -121.425346) (xy 31.210433 -121.497057) (xy 31.154881 -121.563927) (xy 31.093395 -121.625383)
			(xy 31.026499 -121.680903) (xy 30.954764 -121.730011) (xy 30.878803 -121.772289) (xy 30.799264 -121.807375)
			(xy 30.716826 -121.83497) (xy 30.632194 -121.854839) (xy 30.546088 -121.866812) (xy 30.459245 -121.870786)
			(xy 30.372406 -121.866728) (xy 30.286312 -121.854672) (xy 30.201699 -121.834721) (xy 30.119288 -121.807046)
			(xy 30.039783 -121.771883) (xy 29.963862 -121.729532) (xy 29.892175 -121.680355) (xy 29.825333 -121.62477)
			(xy 29.763906 -121.563254) (xy 29.73578 -121.53011) (xy 29.721738 -121.514635) (xy 29.689504 -121.48805)
			(xy 29.653349 -121.467107) (xy 29.61425 -121.452373) (xy 29.573265 -121.444245) (xy 29.531502 -121.442944)
			(xy 29.510736 -121.445274) (xy 29.495673 -121.447723) (xy 29.467249 -121.458805) (xy 29.442274 -121.476327)
			(xy 29.422182 -121.499285) (xy 29.408124 -121.526361) (xy 29.400907 -121.556003) (xy 29.4005 -121.571258)
			(xy 29.4005 -122.828558) (xy 29.400954 -122.843805) (xy 29.408199 -122.873425) (xy 29.422261 -122.900483)
			(xy 29.442339 -122.923434) (xy 29.467287 -122.940969) (xy 29.495682 -122.952087) (xy 29.510736 -122.954542)
			(xy 29.531497 -122.956872) (xy 29.57325 -122.955527) (xy 29.614221 -122.947375) (xy 29.653308 -122.932635)
			(xy 29.68946 -122.911704) (xy 29.721704 -122.885144) (xy 29.73578 -122.869706) (xy 29.763898 -122.836555)
			(xy 29.825324 -122.775038) (xy 29.892165 -122.719453) (xy 29.963852 -122.670274) (xy 30.039772 -122.627922)
			(xy 30.119276 -122.592758) (xy 30.201687 -122.565082) (xy 30.2863 -122.54513) (xy 30.372394 -122.533073)
			(xy 30.459233 -122.529014) (xy 30.546076 -122.532987) (xy 30.632181 -122.544959) (xy 30.716815 -122.564826)
			(xy 30.799253 -122.59242) (xy 30.878792 -122.627506) (xy 30.954754 -122.669782) (xy 31.026489 -122.71889)
			(xy 31.093386 -122.774408) (xy 31.154873 -122.835864) (xy 31.210425 -122.902733) (xy 31.259569 -122.974444)
			(xy 31.301883 -123.050384) (xy 31.337009 -123.129906) (xy 31.364644 -123.21233) (xy 31.384555 -123.296953)
			(xy 31.396569 -123.383053) (xy 31.400586 -123.469894) (xy 31.398576 -123.513358) (xy 34.599874 -123.513358)
			(xy 34.599874 -123.426458) (xy 34.607892 -123.339929) (xy 34.62386 -123.254509) (xy 34.647641 -123.170927)
			(xy 34.679033 -123.089895) (xy 34.717767 -123.012106) (xy 34.763514 -122.938222) (xy 34.815883 -122.868875)
			(xy 34.874427 -122.804655) (xy 34.938647 -122.746111) (xy 35.007994 -122.693742) (xy 35.081878 -122.647995)
			(xy 35.159667 -122.609261) (xy 35.240699 -122.577869) (xy 35.324281 -122.554088) (xy 35.409701 -122.53812)
			(xy 35.49623 -122.530102) (xy 35.58313 -122.530102) (xy 35.669659 -122.53812) (xy 35.755079 -122.554088)
			(xy 35.838661 -122.577869) (xy 35.919693 -122.609261) (xy 35.997482 -122.647995) (xy 36.0572 -122.684971)
			(xy 39.35131 -122.684971) (xy 39.355202 -122.630619) (xy 39.366789 -122.577375) (xy 39.385837 -122.526321)
			(xy 39.411957 -122.478498) (xy 39.444617 -122.43488) (xy 39.483153 -122.396354) (xy 39.52678 -122.363704)
			(xy 39.574609 -122.337597) (xy 39.625668 -122.318562) (xy 39.678915 -122.306988) (xy 39.733268 -122.30311)
			(xy 39.78762 -122.307007) (xy 39.840863 -122.3186) (xy 39.891915 -122.337653) (xy 39.939735 -122.363778)
			(xy 39.96182 -122.37974) (xy 39.980832 -122.393336) (xy 40.022715 -122.414068) (xy 40.067683 -122.426794)
			(xy 40.11422 -122.431084) (xy 40.160757 -122.426794) (xy 40.205725 -122.414068) (xy 40.247608 -122.393336)
			(xy 40.26662 -122.37974) (xy 40.288663 -122.363717) (xy 40.33649 -122.337593) (xy 40.387548 -122.318542)
			(xy 40.440797 -122.306951) (xy 40.495155 -122.303057) (xy 40.549513 -122.306938) (xy 40.602765 -122.318516)
			(xy 40.653828 -122.337555) (xy 40.701661 -122.363668) (xy 40.745291 -122.396322) (xy 40.783829 -122.434853)
			(xy 40.816492 -122.478477) (xy 40.841801 -122.524816) (xy 57.923267 -122.524816) (xy 57.927153 -122.470459)
			(xy 57.938735 -122.417208) (xy 57.957778 -122.366148) (xy 57.983894 -122.318318) (xy 58.016551 -122.274691)
			(xy 58.055085 -122.236156) (xy 58.098711 -122.203498) (xy 58.146541 -122.177381) (xy 58.197601 -122.158337)
			(xy 58.250851 -122.146754) (xy 58.305208 -122.142867) (xy 58.359565 -122.146756) (xy 58.412814 -122.158342)
			(xy 58.463874 -122.177388) (xy 58.511702 -122.203507) (xy 58.533792 -122.219466) (xy 58.552804 -122.233062)
			(xy 58.594687 -122.253794) (xy 58.639655 -122.26652) (xy 58.686192 -122.27081) (xy 58.732729 -122.26652)
			(xy 58.777697 -122.253794) (xy 58.81958 -122.233062) (xy 58.838592 -122.219466) (xy 58.860705 -122.20354)
			(xy 58.908529 -122.177422) (xy 58.959584 -122.158376) (xy 59.01283 -122.14679) (xy 59.067183 -122.142899)
			(xy 59.121536 -122.146785) (xy 59.174783 -122.158366) (xy 59.22584 -122.177408) (xy 59.273667 -122.203522)
			(xy 59.31729 -122.236177) (xy 59.355822 -122.274709) (xy 59.388477 -122.318332) (xy 59.414592 -122.366159)
			(xy 59.433634 -122.417215) (xy 59.445215 -122.470462) (xy 59.449101 -122.524816) (xy 60.164242 -122.524816)
			(xy 60.168128 -122.470453) (xy 60.179712 -122.417197) (xy 60.198758 -122.366131) (xy 60.224878 -122.318297)
			(xy 60.25754 -122.274666) (xy 60.296079 -122.236129) (xy 60.33971 -122.203469) (xy 60.387546 -122.177351)
			(xy 60.438612 -122.158308) (xy 60.491869 -122.146726) (xy 60.546232 -122.142842) (xy 60.600594 -122.146735)
			(xy 60.653849 -122.158326) (xy 60.704912 -122.177378) (xy 60.752743 -122.203503) (xy 60.774834 -122.219466)
			(xy 60.793846 -122.233062) (xy 60.835729 -122.253794) (xy 60.880697 -122.26652) (xy 60.927234 -122.27081)
			(xy 60.973771 -122.26652) (xy 61.018739 -122.253794) (xy 61.060622 -122.233062) (xy 61.079634 -122.219466)
			(xy 61.101746 -122.203544) (xy 61.149567 -122.177432) (xy 61.200618 -122.158392) (xy 61.25386 -122.146811)
			(xy 61.308207 -122.142925) (xy 61.362554 -122.146813) (xy 61.415795 -122.158396) (xy 61.466845 -122.177438)
			(xy 61.514666 -122.203551) (xy 61.558283 -122.236205) (xy 61.59681 -122.274734) (xy 61.629461 -122.318353)
			(xy 61.655572 -122.366175) (xy 61.674611 -122.417227) (xy 61.68619 -122.470468) (xy 61.690075 -122.524816)
			(xy 62.068252 -122.524816) (xy 62.072138 -122.470455) (xy 62.083721 -122.417201) (xy 62.102766 -122.366138)
			(xy 62.128884 -122.318305) (xy 62.161544 -122.274676) (xy 62.200081 -122.236139) (xy 62.243711 -122.20348)
			(xy 62.291544 -122.177363) (xy 62.342608 -122.158319) (xy 62.395862 -122.146737) (xy 62.450223 -122.142852)
			(xy 62.504583 -122.146743) (xy 62.557836 -122.158332) (xy 62.608897 -122.177382) (xy 62.656728 -122.203505)
			(xy 62.678818 -122.219466) (xy 62.69783 -122.233062) (xy 62.739713 -122.253794) (xy 62.784681 -122.26652)
			(xy 62.831218 -122.27081) (xy 62.877755 -122.26652) (xy 62.922723 -122.253794) (xy 62.964606 -122.233062)
			(xy 62.983618 -122.219466) (xy 63.00573 -122.203543) (xy 63.053553 -122.177428) (xy 63.104605 -122.158386)
			(xy 63.157848 -122.146803) (xy 63.212198 -122.142915) (xy 63.266547 -122.146802) (xy 63.31979 -122.158384)
			(xy 63.370843 -122.177426) (xy 63.418666 -122.20354) (xy 63.462286 -122.236194) (xy 63.500814 -122.274724)
			(xy 63.533467 -122.318345) (xy 63.559579 -122.366169) (xy 63.578619 -122.417222) (xy 63.5902 -122.470466)
			(xy 63.594085 -122.524816) (xy 63.590195 -122.579165) (xy 63.578611 -122.632407) (xy 63.559566 -122.683459)
			(xy 63.53345 -122.731281) (xy 63.500794 -122.774899) (xy 63.462262 -122.813426) (xy 63.41864 -122.846077)
			(xy 63.370815 -122.872187) (xy 63.31976 -122.891224) (xy 63.266516 -122.902802) (xy 63.212167 -122.906685)
			(xy 63.157817 -122.902793) (xy 63.104575 -122.891206) (xy 63.053524 -122.872159) (xy 63.005704 -122.84604)
			(xy 62.983618 -122.830082) (xy 62.964606 -122.816486) (xy 62.922723 -122.795754) (xy 62.877755 -122.783028)
			(xy 62.831218 -122.778738) (xy 62.784681 -122.783028) (xy 62.739713 -122.795754) (xy 62.69783 -122.816486)
			(xy 62.678818 -122.830082) (xy 62.656754 -122.846079) (xy 62.608926 -122.872206) (xy 62.557866 -122.891259)
			(xy 62.504614 -122.902852) (xy 62.450254 -122.906748) (xy 62.395893 -122.902868) (xy 62.342638 -122.89129)
			(xy 62.291573 -122.87225) (xy 62.243737 -122.846137) (xy 62.200105 -122.813481) (xy 62.161564 -122.774948)
			(xy 62.128901 -122.731322) (xy 62.102779 -122.683491) (xy 62.08373 -122.632429) (xy 62.072142 -122.579176)
			(xy 62.068252 -122.524816) (xy 61.690075 -122.524816) (xy 61.686186 -122.579163) (xy 61.674602 -122.632403)
			(xy 61.655559 -122.683453) (xy 61.629444 -122.731273) (xy 61.596789 -122.77489) (xy 61.55826 -122.813415)
			(xy 61.51464 -122.846065) (xy 61.466817 -122.872175) (xy 61.415765 -122.891213) (xy 61.362523 -122.902792)
			(xy 61.308176 -122.906675) (xy 61.253829 -122.902785) (xy 61.200588 -122.891199) (xy 61.149539 -122.872155)
			(xy 61.10172 -122.846039) (xy 61.079634 -122.830082) (xy 61.060622 -122.816486) (xy 61.018739 -122.795754)
			(xy 60.973771 -122.783028) (xy 60.927234 -122.778738) (xy 60.880697 -122.783028) (xy 60.835729 -122.795754)
			(xy 60.793846 -122.816486) (xy 60.774834 -122.830082) (xy 60.752769 -122.84608) (xy 60.70494 -122.872209)
			(xy 60.653879 -122.891266) (xy 60.600625 -122.90286) (xy 60.546263 -122.906758) (xy 60.4919 -122.902878)
			(xy 60.438642 -122.891301) (xy 60.387575 -122.872262) (xy 60.339737 -122.846148) (xy 60.296102 -122.813492)
			(xy 60.25756 -122.774957) (xy 60.224894 -122.73133) (xy 60.198771 -122.683497) (xy 60.179721 -122.632433)
			(xy 60.168133 -122.579178) (xy 60.164242 -122.524816) (xy 59.449101 -122.524816) (xy 59.445211 -122.579168)
			(xy 59.433625 -122.632414) (xy 59.414579 -122.683469) (xy 59.38846 -122.731294) (xy 59.355801 -122.774915)
			(xy 59.317266 -122.813443) (xy 59.27364 -122.846095) (xy 59.225811 -122.872205) (xy 59.174753 -122.891243)
			(xy 59.121505 -122.90282) (xy 59.067152 -122.906701) (xy 59.012799 -122.902806) (xy 58.959554 -122.891216)
			(xy 58.908501 -122.872165) (xy 58.860678 -122.846043) (xy 58.838592 -122.830082) (xy 58.81958 -122.816486)
			(xy 58.777697 -122.795754) (xy 58.732729 -122.783028) (xy 58.686192 -122.778738) (xy 58.639655 -122.783028)
			(xy 58.594687 -122.795754) (xy 58.552804 -122.816486) (xy 58.533792 -122.830082) (xy 58.511728 -122.846076)
			(xy 58.463902 -122.872199) (xy 58.412844 -122.891249) (xy 58.359595 -122.902839) (xy 58.305239 -122.906733)
			(xy 58.250882 -122.90285) (xy 58.197631 -122.891271) (xy 58.146569 -122.872232) (xy 58.098737 -122.846119)
			(xy 58.055109 -122.813464) (xy 58.016572 -122.774932) (xy 57.983911 -122.731309) (xy 57.957791 -122.683481)
			(xy 57.938744 -122.632422) (xy 57.927158 -122.579172) (xy 57.923267 -122.524816) (xy 40.841801 -122.524816)
			(xy 40.842614 -122.526305) (xy 40.861663 -122.577364) (xy 40.873251 -122.630614) (xy 40.877143 -122.684971)
			(xy 40.873259 -122.739329) (xy 40.861679 -122.792581) (xy 40.842638 -122.843643) (xy 40.816523 -122.891475)
			(xy 40.783867 -122.935103) (xy 40.745334 -122.97364) (xy 40.701709 -123.006301) (xy 40.65388 -123.032421)
			(xy 40.60282 -123.051467) (xy 40.54957 -123.063053) (xy 40.495212 -123.066943) (xy 40.440854 -123.063057)
			(xy 40.387603 -123.051474) (xy 40.336542 -123.032431) (xy 40.288711 -123.006314) (xy 40.26662 -122.990356)
			(xy 40.247608 -122.97676) (xy 40.205725 -122.956028) (xy 40.160757 -122.943302) (xy 40.11422 -122.939012)
			(xy 40.067683 -122.943302) (xy 40.022715 -122.956028) (xy 39.980832 -122.97676) (xy 39.96182 -122.990356)
			(xy 39.939686 -123.006253) (xy 39.891862 -123.032371) (xy 39.840808 -123.051416) (xy 39.787563 -123.063001)
			(xy 39.733211 -123.06689) (xy 39.678858 -123.063004) (xy 39.625612 -123.051422) (xy 39.574557 -123.032379)
			(xy 39.526731 -123.006264) (xy 39.48311 -122.973608) (xy 39.44458 -122.935077) (xy 39.411926 -122.891453)
			(xy 39.385813 -122.843626) (xy 39.366773 -122.79257) (xy 39.355193 -122.739324) (xy 39.35131 -122.684971)
			(xy 36.0572 -122.684971) (xy 36.071366 -122.693742) (xy 36.140713 -122.746111) (xy 36.204933 -122.804655)
			(xy 36.263477 -122.868875) (xy 36.315846 -122.938222) (xy 36.361593 -123.012106) (xy 36.400327 -123.089895)
			(xy 36.431719 -123.170927) (xy 36.4555 -123.254509) (xy 36.471468 -123.339929) (xy 36.479486 -123.426458)
			(xy 36.479988 -123.469908) (xy 36.479486 -123.513358) (xy 36.471468 -123.599887) (xy 36.4555 -123.685307)
			(xy 36.431719 -123.768889) (xy 36.400327 -123.849921) (xy 36.361593 -123.92771) (xy 36.315846 -124.001594)
			(xy 36.263477 -124.070941) (xy 36.204933 -124.135161) (xy 36.140713 -124.193705) (xy 36.071366 -124.246074)
			(xy 35.997482 -124.291821) (xy 35.919693 -124.330555) (xy 35.838661 -124.361947) (xy 35.755079 -124.385728)
			(xy 35.669659 -124.401696) (xy 35.58313 -124.409714) (xy 35.49623 -124.409714) (xy 35.409701 -124.401696)
			(xy 35.324281 -124.385728) (xy 35.240699 -124.361947) (xy 35.159667 -124.330555) (xy 35.081878 -124.291821)
			(xy 35.007994 -124.246074) (xy 34.938647 -124.193705) (xy 34.874427 -124.135161) (xy 34.815883 -124.070941)
			(xy 34.763514 -124.001594) (xy 34.717767 -123.92771) (xy 34.679033 -123.849921) (xy 34.647641 -123.768889)
			(xy 34.62386 -123.685307) (xy 34.607892 -123.599887) (xy 34.599874 -123.513358) (xy 31.398576 -123.513358)
			(xy 31.39657 -123.556735) (xy 31.384557 -123.642835) (xy 31.364648 -123.727458) (xy 31.337013 -123.809883)
			(xy 31.301889 -123.889405) (xy 31.259575 -123.965346) (xy 31.210433 -124.037057) (xy 31.154881 -124.103927)
			(xy 31.093395 -124.165383) (xy 31.026499 -124.220903) (xy 30.954764 -124.270011) (xy 30.878803 -124.312289)
			(xy 30.799264 -124.347375) (xy 30.716826 -124.37497) (xy 30.632194 -124.394839) (xy 30.546088 -124.406812)
			(xy 30.459245 -124.410786) (xy 30.372406 -124.406728) (xy 30.286312 -124.394672) (xy 30.201699 -124.374721)
			(xy 30.119288 -124.347046) (xy 30.039783 -124.311883) (xy 29.963862 -124.269532) (xy 29.892175 -124.220355)
			(xy 29.825333 -124.16477) (xy 29.763906 -124.103254) (xy 29.73578 -124.07011) (xy 29.721738 -124.054635)
			(xy 29.689504 -124.02805) (xy 29.653349 -124.007107) (xy 29.61425 -123.992373) (xy 29.573265 -123.984245)
			(xy 29.531502 -123.982944) (xy 29.510736 -123.985274) (xy 29.495673 -123.987723) (xy 29.467249 -123.998805)
			(xy 29.442274 -124.016327) (xy 29.422182 -124.039285) (xy 29.408124 -124.066361) (xy 29.400907 -124.096003)
			(xy 29.4005 -124.111258) (xy 29.4005 -124.696188) (xy 39.307908 -124.696188) (xy 39.311797 -124.641837)
			(xy 39.323382 -124.588594) (xy 39.342426 -124.53754) (xy 39.368542 -124.489717) (xy 39.401199 -124.446098)
			(xy 39.439731 -124.40757) (xy 39.483354 -124.374919) (xy 39.53118 -124.348808) (xy 39.582236 -124.329769)
			(xy 39.635481 -124.318191) (xy 39.689832 -124.314308) (xy 39.744182 -124.3182) (xy 39.797426 -124.329787)
			(xy 39.848478 -124.348834) (xy 39.8963 -124.374953) (xy 39.918386 -124.390912) (xy 39.937398 -124.404508)
			(xy 39.979281 -124.42524) (xy 40.024249 -124.437966) (xy 40.070786 -124.442256) (xy 40.117323 -124.437966)
			(xy 40.162291 -124.42524) (xy 40.204174 -124.404508) (xy 40.223186 -124.390912) (xy 40.245256 -124.374924)
			(xy 40.293083 -124.348798) (xy 40.344142 -124.329746) (xy 40.397393 -124.318154) (xy 40.451752 -124.314259)
			(xy 40.506112 -124.31814) (xy 40.559365 -124.329719) (xy 40.610429 -124.348758) (xy 40.658263 -124.374872)
			(xy 40.701894 -124.407528) (xy 40.740433 -124.44606) (xy 40.773096 -124.489686) (xy 40.798319 -124.535872)
			(xy 57.879945 -124.535872) (xy 57.883836 -124.481529) (xy 57.895421 -124.428292) (xy 57.914465 -124.377246)
			(xy 57.940579 -124.329429) (xy 57.973233 -124.285816) (xy 58.011761 -124.247294) (xy 58.055379 -124.214647)
			(xy 58.1032 -124.18854) (xy 58.154249 -124.169505) (xy 58.207487 -124.157928) (xy 58.261832 -124.154045)
			(xy 58.316175 -124.157937) (xy 58.369412 -124.169522) (xy 58.420458 -124.188567) (xy 58.468274 -124.214682)
			(xy 58.490358 -124.230638) (xy 58.50937 -124.244234) (xy 58.551253 -124.264966) (xy 58.596221 -124.277692)
			(xy 58.642758 -124.281982) (xy 58.689295 -124.277692) (xy 58.734263 -124.264966) (xy 58.776146 -124.244234)
			(xy 58.795158 -124.230638) (xy 58.817204 -124.214612) (xy 58.865035 -124.188479) (xy 58.916099 -124.169419)
			(xy 58.969355 -124.157821) (xy 59.02372 -124.153921) (xy 59.078087 -124.157799) (xy 59.131349 -124.169375)
			(xy 59.18242 -124.188413) (xy 59.230262 -124.214526) (xy 59.2739 -124.247183) (xy 59.312447 -124.285719)
			(xy 59.345116 -124.329348) (xy 59.371243 -124.377182) (xy 59.390295 -124.428249) (xy 59.401886 -124.481507)
			(xy 59.405779 -124.535872) (xy 60.12092 -124.535872) (xy 60.124812 -124.481523) (xy 60.136398 -124.428281)
			(xy 60.155445 -124.377229) (xy 60.181563 -124.329408) (xy 60.214221 -124.285791) (xy 60.252754 -124.247266)
			(xy 60.296378 -124.214618) (xy 60.344205 -124.18851) (xy 60.395261 -124.169475) (xy 60.448505 -124.1579)
			(xy 60.502856 -124.15402) (xy 60.557205 -124.157916) (xy 60.610446 -124.169506) (xy 60.661496 -124.188556)
			(xy 60.709315 -124.214678) (xy 60.7314 -124.230638) (xy 60.750412 -124.244234) (xy 60.792295 -124.264966)
			(xy 60.837263 -124.277692) (xy 60.8838 -124.281982) (xy 60.930337 -124.277692) (xy 60.975305 -124.264966)
			(xy 61.017188 -124.244234) (xy 61.0362 -124.230638) (xy 61.058245 -124.214616) (xy 61.106073 -124.188489)
			(xy 61.157133 -124.169436) (xy 61.210385 -124.157843) (xy 61.264744 -124.153947) (xy 61.319105 -124.157827)
			(xy 61.37236 -124.169404) (xy 61.423425 -124.188443) (xy 61.471261 -124.214556) (xy 61.514894 -124.247211)
			(xy 61.553435 -124.285743) (xy 61.586099 -124.329369) (xy 61.612222 -124.377199) (xy 61.631272 -124.42826)
			(xy 61.642861 -124.481513) (xy 61.646753 -124.535872) (xy 62.02493 -124.535872) (xy 62.028821 -124.481525)
			(xy 62.040407 -124.428285) (xy 62.059452 -124.377236) (xy 62.085569 -124.329416) (xy 62.118226 -124.285801)
			(xy 62.156757 -124.247277) (xy 62.200379 -124.214629) (xy 62.248203 -124.188522) (xy 62.299256 -124.169486)
			(xy 62.352499 -124.15791) (xy 62.406847 -124.15403) (xy 62.461194 -124.157924) (xy 62.514433 -124.169512)
			(xy 62.565482 -124.18856) (xy 62.6133 -124.214679) (xy 62.635384 -124.230638) (xy 62.654396 -124.244234)
			(xy 62.696279 -124.264966) (xy 62.741247 -124.277692) (xy 62.787784 -124.281982) (xy 62.834321 -124.277692)
			(xy 62.879289 -124.264966) (xy 62.921172 -124.244234) (xy 62.940184 -124.230638) (xy 62.962229 -124.214615)
			(xy 63.010059 -124.188485) (xy 63.06112 -124.169429) (xy 63.114374 -124.157835) (xy 63.168735 -124.153937)
			(xy 63.223098 -124.157816) (xy 63.276356 -124.169393) (xy 63.327423 -124.188432) (xy 63.375262 -124.214545)
			(xy 63.418896 -124.2472) (xy 63.457439 -124.285734) (xy 63.490105 -124.329361) (xy 63.51623 -124.377193)
			(xy 63.535281 -124.428256) (xy 63.546871 -124.48151) (xy 63.550763 -124.535872) (xy 63.546879 -124.590235)
			(xy 63.535297 -124.643491) (xy 63.516253 -124.694557) (xy 63.490135 -124.742393) (xy 63.457475 -124.786024)
			(xy 63.418938 -124.824564) (xy 63.375308 -124.857226) (xy 63.327474 -124.883345) (xy 63.276409 -124.902392)
			(xy 63.223153 -124.913976) (xy 63.16879 -124.917863) (xy 63.114428 -124.913973) (xy 63.061173 -124.902386)
			(xy 63.010109 -124.883338) (xy 62.962276 -124.857215) (xy 62.940184 -124.841254) (xy 62.921172 -124.827658)
			(xy 62.879289 -124.806926) (xy 62.834321 -124.7942) (xy 62.787784 -124.78991) (xy 62.741247 -124.7942)
			(xy 62.696279 -124.806926) (xy 62.654396 -124.827658) (xy 62.635384 -124.841254) (xy 62.613253 -124.857151)
			(xy 62.565431 -124.883263) (xy 62.51438 -124.902303) (xy 62.461139 -124.913884) (xy 62.406791 -124.91777)
			(xy 62.352444 -124.913882) (xy 62.299203 -124.902298) (xy 62.248153 -124.883256) (xy 62.200332 -124.857141)
			(xy 62.156715 -124.824487) (xy 62.118189 -124.785957) (xy 62.085539 -124.742337) (xy 62.059429 -124.694514)
			(xy 62.040392 -124.643462) (xy 62.028813 -124.59022) (xy 62.02493 -124.535872) (xy 61.646753 -124.535872)
			(xy 61.642869 -124.590233) (xy 61.631288 -124.643487) (xy 61.612245 -124.694551) (xy 61.586129 -124.742385)
			(xy 61.553471 -124.786015) (xy 61.514936 -124.824553) (xy 61.471308 -124.857214) (xy 61.423476 -124.883334)
			(xy 61.372413 -124.90238) (xy 61.31916 -124.913965) (xy 61.2648 -124.917853) (xy 61.210439 -124.913965)
			(xy 61.157186 -124.90238) (xy 61.106123 -124.883334) (xy 61.058291 -124.857214) (xy 61.0362 -124.841254)
			(xy 61.017188 -124.827658) (xy 60.975305 -124.806926) (xy 60.930337 -124.7942) (xy 60.8838 -124.78991)
			(xy 60.837263 -124.7942) (xy 60.792295 -124.806926) (xy 60.750412 -124.827658) (xy 60.7314 -124.841254)
			(xy 60.709269 -124.857152) (xy 60.661446 -124.883267) (xy 60.610393 -124.902309) (xy 60.55715 -124.913892)
			(xy 60.5028 -124.91778) (xy 60.448451 -124.913892) (xy 60.395208 -124.90231) (xy 60.344155 -124.883267)
			(xy 60.296332 -124.857152) (xy 60.252713 -124.824497) (xy 60.214185 -124.785967) (xy 60.181533 -124.742345)
			(xy 60.155422 -124.69452) (xy 60.136383 -124.643466) (xy 60.124804 -124.590222) (xy 60.12092 -124.535872)
			(xy 59.405779 -124.535872) (xy 59.401894 -124.590239) (xy 59.390311 -124.643498) (xy 59.371265 -124.694567)
			(xy 59.345145 -124.742406) (xy 59.312483 -124.78604) (xy 59.273942 -124.824581) (xy 59.230309 -124.857244)
			(xy 59.18247 -124.883364) (xy 59.131402 -124.90241) (xy 59.078142 -124.913993) (xy 59.023776 -124.917879)
			(xy 58.96941 -124.913986) (xy 58.916152 -124.902396) (xy 58.865085 -124.883344) (xy 58.81725 -124.857217)
			(xy 58.795158 -124.841254) (xy 58.776146 -124.827658) (xy 58.734263 -124.806926) (xy 58.689295 -124.7942)
			(xy 58.642758 -124.78991) (xy 58.596221 -124.7942) (xy 58.551253 -124.806926) (xy 58.50937 -124.827658)
			(xy 58.490358 -124.841254) (xy 58.468228 -124.857148) (xy 58.420408 -124.883256) (xy 58.369359 -124.902293)
			(xy 58.316121 -124.913871) (xy 58.261777 -124.917755) (xy 58.207433 -124.913864) (xy 58.154196 -124.90228)
			(xy 58.10315 -124.883237) (xy 58.055333 -124.857123) (xy 58.011719 -124.82447) (xy 57.973197 -124.785942)
			(xy 57.940549 -124.742324) (xy 57.914442 -124.694504) (xy 57.895406 -124.643455) (xy 57.883828 -124.590217)
			(xy 57.879945 -124.535872) (xy 40.798319 -124.535872) (xy 40.799217 -124.537516) (xy 40.818264 -124.588577)
			(xy 40.829851 -124.641829) (xy 40.833741 -124.696188) (xy 40.829855 -124.750547) (xy 40.818271 -124.8038)
			(xy 40.799227 -124.854862) (xy 40.773109 -124.902694) (xy 40.740449 -124.946321) (xy 40.701912 -124.984857)
			(xy 40.658284 -125.017515) (xy 40.610451 -125.043632) (xy 40.559388 -125.062675) (xy 40.506135 -125.074256)
			(xy 40.451776 -125.078141) (xy 40.397417 -125.074249) (xy 40.344165 -125.062661) (xy 40.293105 -125.043612)
			(xy 40.245276 -125.017489) (xy 40.223186 -125.001528) (xy 40.204174 -124.987932) (xy 40.162291 -124.9672)
			(xy 40.117323 -124.954474) (xy 40.070786 -124.950184) (xy 40.024249 -124.954474) (xy 39.979281 -124.9672)
			(xy 39.937398 -124.987932) (xy 39.918386 -125.001528) (xy 39.896279 -125.01746) (xy 39.848456 -125.043576)
			(xy 39.797403 -125.06262) (xy 39.744159 -125.074204) (xy 39.689808 -125.078092) (xy 39.635457 -125.074206)
			(xy 39.582213 -125.062624) (xy 39.531159 -125.043582) (xy 39.483334 -125.017469) (xy 39.439713 -124.984814)
			(xy 39.401183 -124.946284) (xy 39.368529 -124.902663) (xy 39.342416 -124.854838) (xy 39.323375 -124.803783)
			(xy 39.311794 -124.750539) (xy 39.307908 -124.696188) (xy 29.4005 -124.696188) (xy 29.4005 -125.368558)
			(xy 29.400954 -125.383805) (xy 29.408199 -125.413425) (xy 29.422261 -125.440483) (xy 29.442339 -125.463434)
			(xy 29.467287 -125.480969) (xy 29.495682 -125.492087) (xy 29.510736 -125.494542) (xy 29.531497 -125.496872)
			(xy 29.57325 -125.495527) (xy 29.614221 -125.487375) (xy 29.653308 -125.472635) (xy 29.68946 -125.451704)
			(xy 29.721704 -125.425144) (xy 29.73578 -125.409706) (xy 29.763898 -125.376555) (xy 29.825324 -125.315038)
			(xy 29.892165 -125.259453) (xy 29.963852 -125.210274) (xy 30.039772 -125.167922) (xy 30.119276 -125.132758)
			(xy 30.201687 -125.105082) (xy 30.2863 -125.08513) (xy 30.372394 -125.073073) (xy 30.459233 -125.069014)
			(xy 30.546076 -125.072987) (xy 30.632181 -125.084959) (xy 30.716815 -125.104826) (xy 30.799253 -125.13242)
			(xy 30.878792 -125.167506) (xy 30.954754 -125.209782) (xy 31.026489 -125.25889) (xy 31.093386 -125.314408)
			(xy 31.154873 -125.375864) (xy 31.210425 -125.442733) (xy 31.259569 -125.514444) (xy 31.301883 -125.590384)
			(xy 31.337009 -125.669906) (xy 31.364644 -125.75233) (xy 31.384555 -125.836953) (xy 31.396569 -125.923053)
			(xy 31.400586 -126.009894) (xy 31.398576 -126.053358) (xy 34.599874 -126.053358) (xy 34.599874 -125.966458)
			(xy 34.607892 -125.879929) (xy 34.62386 -125.794509) (xy 34.647641 -125.710927) (xy 34.679033 -125.629895)
			(xy 34.717767 -125.552106) (xy 34.763514 -125.478222) (xy 34.815883 -125.408875) (xy 34.874427 -125.344655)
			(xy 34.938647 -125.286111) (xy 35.007994 -125.233742) (xy 35.081878 -125.187995) (xy 35.159667 -125.149261)
			(xy 35.240699 -125.117869) (xy 35.324281 -125.094088) (xy 35.409701 -125.07812) (xy 35.49623 -125.070102)
			(xy 35.58313 -125.070102) (xy 35.669659 -125.07812) (xy 35.755079 -125.094088) (xy 35.838661 -125.117869)
			(xy 35.919693 -125.149261) (xy 35.997482 -125.187995) (xy 36.071366 -125.233742) (xy 36.140713 -125.286111)
			(xy 36.204933 -125.344655) (xy 36.263477 -125.408875) (xy 36.315846 -125.478222) (xy 36.361593 -125.552106)
			(xy 36.400327 -125.629895) (xy 36.431719 -125.710927) (xy 36.4555 -125.794509) (xy 36.471468 -125.879929)
			(xy 36.479486 -125.966458) (xy 36.479988 -126.009908) (xy 36.479486 -126.053358) (xy 36.471468 -126.139887)
			(xy 36.4555 -126.225307) (xy 36.431719 -126.308889) (xy 36.400327 -126.389921) (xy 36.361593 -126.46771)
			(xy 36.315846 -126.541594) (xy 36.281802 -126.586675) (xy 39.307925 -126.586675) (xy 39.311816 -126.532327)
			(xy 39.323402 -126.479086) (xy 39.342447 -126.428036) (xy 39.368564 -126.380216) (xy 39.401221 -126.336599)
			(xy 39.439753 -126.298075) (xy 39.483375 -126.265426) (xy 39.5312 -126.239318) (xy 39.582253 -126.220282)
			(xy 39.635497 -126.208706) (xy 39.689845 -126.204825) (xy 39.744193 -126.208719) (xy 39.797433 -126.220308)
			(xy 39.848483 -126.239356) (xy 39.896301 -126.265475) (xy 39.918386 -126.281434) (xy 39.937398 -126.29503)
			(xy 39.979281 -126.315762) (xy 40.024249 -126.328488) (xy 40.070786 -126.332778) (xy 40.117323 -126.328488)
			(xy 40.162291 -126.315762) (xy 40.204174 -126.29503) (xy 40.223186 -126.281434) (xy 40.245235 -126.265416)
			(xy 40.293064 -126.239288) (xy 40.344125 -126.220233) (xy 40.397378 -126.208638) (xy 40.451739 -126.204741)
			(xy 40.506101 -126.208621) (xy 40.559358 -126.220198) (xy 40.610425 -126.239237) (xy 40.658262 -126.26535)
			(xy 40.701896 -126.298006) (xy 40.740438 -126.336539) (xy 40.773103 -126.380165) (xy 40.79842 -126.426519)
			(xy 57.879883 -126.426519) (xy 57.883768 -126.372166) (xy 57.895348 -126.318919) (xy 57.914389 -126.267862)
			(xy 57.940501 -126.220035) (xy 57.973155 -126.176411) (xy 58.011685 -126.137878) (xy 58.055306 -126.10522)
			(xy 58.103131 -126.079103) (xy 58.154186 -126.060058) (xy 58.207432 -126.048473) (xy 58.261785 -126.044583)
			(xy 58.316138 -126.048468) (xy 58.369385 -126.060049) (xy 58.420441 -126.07909) (xy 58.468269 -126.105204)
			(xy 58.490358 -126.12116) (xy 58.50937 -126.134756) (xy 58.551253 -126.155488) (xy 58.596221 -126.168214)
			(xy 58.642758 -126.172504) (xy 58.689295 -126.168214) (xy 58.734263 -126.155488) (xy 58.776146 -126.134756)
			(xy 58.795158 -126.12116) (xy 58.817277 -126.10524) (xy 58.865104 -126.079116) (xy 58.916161 -126.060066)
			(xy 58.969411 -126.048477) (xy 59.023767 -126.044584) (xy 59.078125 -126.048467) (xy 59.131376 -126.060048)
			(xy 59.182437 -126.079089) (xy 59.230268 -126.105204) (xy 59.273895 -126.137861) (xy 59.31243 -126.176395)
			(xy 59.345088 -126.220021) (xy 59.371205 -126.267851) (xy 59.390249 -126.318911) (xy 59.401831 -126.372162)
			(xy 59.405716 -126.426519) (xy 60.120858 -126.426519) (xy 60.124743 -126.37216) (xy 60.136325 -126.318908)
			(xy 60.155368 -126.267846) (xy 60.181485 -126.220014) (xy 60.214143 -126.176386) (xy 60.252678 -126.13785)
			(xy 60.296305 -126.105191) (xy 60.344137 -126.079073) (xy 60.395198 -126.060028) (xy 60.44845 -126.048445)
			(xy 60.502809 -126.044558) (xy 60.557167 -126.048447) (xy 60.610419 -126.060033) (xy 60.661479 -126.07908)
			(xy 60.70931 -126.1052) (xy 60.7314 -126.12116) (xy 60.750412 -126.134756) (xy 60.792295 -126.155488)
			(xy 60.837263 -126.168214) (xy 60.8838 -126.172504) (xy 60.930337 -126.168214) (xy 60.975305 -126.155488)
			(xy 61.017188 -126.134756) (xy 61.0362 -126.12116) (xy 61.058318 -126.105243) (xy 61.106142 -126.079127)
			(xy 61.157196 -126.060082) (xy 61.21044 -126.048498) (xy 61.264791 -126.044609) (xy 61.319143 -126.048495)
			(xy 61.372388 -126.060077) (xy 61.423442 -126.079119) (xy 61.471267 -126.105234) (xy 61.514888 -126.137889)
			(xy 61.553418 -126.17642) (xy 61.586072 -126.220042) (xy 61.612185 -126.267867) (xy 61.631226 -126.318922)
			(xy 61.642806 -126.372168) (xy 61.646691 -126.426519) (xy 62.024867 -126.426519) (xy 62.028752 -126.372163)
			(xy 62.040334 -126.318912) (xy 62.059376 -126.267852) (xy 62.085491 -126.220022) (xy 62.118148 -126.176395)
			(xy 62.156681 -126.13786) (xy 62.200306 -126.105202) (xy 62.248135 -126.079084) (xy 62.299194 -126.060039)
			(xy 62.352443 -126.048455) (xy 62.4068 -126.044567) (xy 62.461156 -126.048455) (xy 62.514406 -126.060039)
			(xy 62.565465 -126.079084) (xy 62.613294 -126.105201) (xy 62.635384 -126.12116) (xy 62.654396 -126.134756)
			(xy 62.696279 -126.155488) (xy 62.741247 -126.168214) (xy 62.787784 -126.172504) (xy 62.834321 -126.168214)
			(xy 62.879289 -126.155488) (xy 62.921172 -126.134756) (xy 62.940184 -126.12116) (xy 62.962303 -126.105242)
			(xy 63.010127 -126.079123) (xy 63.061183 -126.060076) (xy 63.114429 -126.04849) (xy 63.168782 -126.0446)
			(xy 63.223136 -126.048485) (xy 63.276383 -126.060066) (xy 63.32744 -126.079108) (xy 63.375267 -126.105222)
			(xy 63.418891 -126.137878) (xy 63.457423 -126.17641) (xy 63.490078 -126.220034) (xy 63.516193 -126.267861)
			(xy 63.535234 -126.318918) (xy 63.536473 -126.324614) (xy 66.805046 -126.324614) (xy 66.809117 -126.268992)
			(xy 66.821243 -126.214555) (xy 66.841166 -126.162464) (xy 66.868462 -126.113829) (xy 66.902548 -126.069686)
			(xy 66.942697 -126.030977) (xy 66.988055 -125.998526) (xy 67.037655 -125.973025) (xy 67.090439 -125.955018)
			(xy 67.145282 -125.944888) (xy 67.201016 -125.942851) (xy 67.256453 -125.948951) (xy 67.31041 -125.963057)
			(xy 67.361739 -125.984869) (xy 67.409345 -126.013923) (xy 67.452213 -126.049598) (xy 67.48943 -126.091135)
			(xy 67.520203 -126.137648) (xy 67.543875 -126.188145) (xy 67.559943 -126.241552) (xy 67.568063 -126.296728)
			(xy 67.568572 -126.324614) (xy 67.928234 -126.324614) (xy 67.932305 -126.268992) (xy 67.944431 -126.214555)
			(xy 67.964354 -126.162464) (xy 67.99165 -126.113829) (xy 68.025736 -126.069686) (xy 68.065885 -126.030977)
			(xy 68.111243 -125.998526) (xy 68.160843 -125.973025) (xy 68.213627 -125.955018) (xy 68.26847 -125.944888)
			(xy 68.324204 -125.942851) (xy 68.379641 -125.948951) (xy 68.433598 -125.963057) (xy 68.484927 -125.984869)
			(xy 68.532533 -126.013923) (xy 68.575401 -126.049598) (xy 68.612618 -126.091135) (xy 68.643391 -126.137648)
			(xy 68.667063 -126.188145) (xy 68.683131 -126.241552) (xy 68.691251 -126.296728) (xy 68.69176 -126.324614)
			(xy 69.062852 -126.324614) (xy 69.066923 -126.268992) (xy 69.079049 -126.214555) (xy 69.098972 -126.162464)
			(xy 69.126268 -126.113829) (xy 69.160354 -126.069686) (xy 69.200503 -126.030977) (xy 69.245861 -125.998526)
			(xy 69.295461 -125.973025) (xy 69.348245 -125.955018) (xy 69.403088 -125.944888) (xy 69.458822 -125.942851)
			(xy 69.514259 -125.948951) (xy 69.568216 -125.963057) (xy 69.619545 -125.984869) (xy 69.667151 -126.013923)
			(xy 69.710019 -126.049598) (xy 69.747236 -126.091135) (xy 69.778009 -126.137648) (xy 69.801681 -126.188145)
			(xy 69.817749 -126.241552) (xy 69.825869 -126.296728) (xy 69.826378 -126.324614) (xy 70.173086 -126.324614)
			(xy 70.177157 -126.268992) (xy 70.189283 -126.214555) (xy 70.209206 -126.162464) (xy 70.236502 -126.113829)
			(xy 70.270588 -126.069686) (xy 70.310737 -126.030977) (xy 70.356095 -125.998526) (xy 70.405695 -125.973025)
			(xy 70.458479 -125.955018) (xy 70.513322 -125.944888) (xy 70.569056 -125.942851) (xy 70.624493 -125.948951)
			(xy 70.67845 -125.963057) (xy 70.729779 -125.984869) (xy 70.777385 -126.013923) (xy 70.820253 -126.049598)
			(xy 70.85747 -126.091135) (xy 70.888243 -126.137648) (xy 70.911915 -126.188145) (xy 70.927983 -126.241552)
			(xy 70.936103 -126.296728) (xy 70.936612 -126.324614) (xy 70.936103 -126.3525) (xy 70.927983 -126.407676)
			(xy 70.911915 -126.461083) (xy 70.888243 -126.51158) (xy 70.85747 -126.558093) (xy 70.820253 -126.59963)
			(xy 70.777385 -126.635305) (xy 70.729779 -126.664359) (xy 70.67845 -126.686171) (xy 70.624493 -126.700277)
			(xy 70.569056 -126.706377) (xy 70.513322 -126.70434) (xy 70.458479 -126.69421) (xy 70.405695 -126.676203)
			(xy 70.356095 -126.650702) (xy 70.310737 -126.618251) (xy 70.270588 -126.579542) (xy 70.236502 -126.535399)
			(xy 70.209206 -126.486764) (xy 70.189283 -126.434673) (xy 70.177157 -126.380236) (xy 70.173086 -126.324614)
			(xy 69.826378 -126.324614) (xy 69.825869 -126.3525) (xy 69.817749 -126.407676) (xy 69.801681 -126.461083)
			(xy 69.778009 -126.51158) (xy 69.747236 -126.558093) (xy 69.710019 -126.59963) (xy 69.667151 -126.635305)
			(xy 69.619545 -126.664359) (xy 69.568216 -126.686171) (xy 69.514259 -126.700277) (xy 69.458822 -126.706377)
			(xy 69.403088 -126.70434) (xy 69.348245 -126.69421) (xy 69.295461 -126.676203) (xy 69.245861 -126.650702)
			(xy 69.200503 -126.618251) (xy 69.160354 -126.579542) (xy 69.126268 -126.535399) (xy 69.098972 -126.486764)
			(xy 69.079049 -126.434673) (xy 69.066923 -126.380236) (xy 69.062852 -126.324614) (xy 68.69176 -126.324614)
			(xy 68.691251 -126.3525) (xy 68.683131 -126.407676) (xy 68.667063 -126.461083) (xy 68.643391 -126.51158)
			(xy 68.612618 -126.558093) (xy 68.575401 -126.59963) (xy 68.532533 -126.635305) (xy 68.484927 -126.664359)
			(xy 68.433598 -126.686171) (xy 68.379641 -126.700277) (xy 68.324204 -126.706377) (xy 68.26847 -126.70434)
			(xy 68.213627 -126.69421) (xy 68.160843 -126.676203) (xy 68.111243 -126.650702) (xy 68.065885 -126.618251)
			(xy 68.025736 -126.579542) (xy 67.99165 -126.535399) (xy 67.964354 -126.486764) (xy 67.944431 -126.434673)
			(xy 67.932305 -126.380236) (xy 67.928234 -126.324614) (xy 67.568572 -126.324614) (xy 67.568063 -126.3525)
			(xy 67.559943 -126.407676) (xy 67.543875 -126.461083) (xy 67.520203 -126.51158) (xy 67.48943 -126.558093)
			(xy 67.452213 -126.59963) (xy 67.409345 -126.635305) (xy 67.361739 -126.664359) (xy 67.31041 -126.686171)
			(xy 67.256453 -126.700277) (xy 67.201016 -126.706377) (xy 67.145282 -126.70434) (xy 67.090439 -126.69421)
			(xy 67.037655 -126.676203) (xy 66.988055 -126.650702) (xy 66.942697 -126.618251) (xy 66.902548 -126.579542)
			(xy 66.868462 -126.535399) (xy 66.841166 -126.486764) (xy 66.821243 -126.434673) (xy 66.809117 -126.380236)
			(xy 66.805046 -126.324614) (xy 63.536473 -126.324614) (xy 63.546816 -126.372166) (xy 63.5507 -126.426519)
			(xy 63.54681 -126.480872) (xy 63.535224 -126.534119) (xy 63.516177 -126.585174) (xy 63.490057 -126.632999)
			(xy 63.457398 -126.676619) (xy 63.418862 -126.715147) (xy 63.375235 -126.747798) (xy 63.327405 -126.773908)
			(xy 63.276346 -126.792945) (xy 63.223098 -126.804521) (xy 63.168744 -126.8084) (xy 63.114391 -126.804505)
			(xy 63.061146 -126.792913) (xy 63.010092 -126.773861) (xy 62.96227 -126.747737) (xy 62.940184 -126.731776)
			(xy 62.921172 -126.71818) (xy 62.879289 -126.697448) (xy 62.834321 -126.684722) (xy 62.787784 -126.680432)
			(xy 62.741247 -126.684722) (xy 62.696279 -126.697448) (xy 62.654396 -126.71818) (xy 62.635384 -126.731776)
			(xy 62.613326 -126.747778) (xy 62.5655 -126.7739) (xy 62.514443 -126.79295) (xy 62.461194 -126.804539)
			(xy 62.406838 -126.808433) (xy 62.352481 -126.80455) (xy 62.29923 -126.792971) (xy 62.248169 -126.773932)
			(xy 62.200338 -126.747819) (xy 62.15671 -126.715165) (xy 62.118173 -126.676634) (xy 62.085512 -126.63301)
			(xy 62.059392 -126.585183) (xy 62.040345 -126.534125) (xy 62.028758 -126.480875) (xy 62.024867 -126.426519)
			(xy 61.646691 -126.426519) (xy 61.642801 -126.48087) (xy 61.631215 -126.534114) (xy 61.612169 -126.585168)
			(xy 61.586051 -126.632991) (xy 61.553393 -126.67661) (xy 61.514859 -126.715136) (xy 61.471235 -126.747787)
			(xy 61.423407 -126.773897) (xy 61.372351 -126.792934) (xy 61.319105 -126.80451) (xy 61.264753 -126.808391)
			(xy 61.210402 -126.804497) (xy 61.157159 -126.792907) (xy 61.106107 -126.773857) (xy 61.058286 -126.747736)
			(xy 61.0362 -126.731776) (xy 61.017188 -126.71818) (xy 60.975305 -126.697448) (xy 60.930337 -126.684722)
			(xy 60.8838 -126.680432) (xy 60.837263 -126.684722) (xy 60.792295 -126.697448) (xy 60.750412 -126.71818)
			(xy 60.7314 -126.731776) (xy 60.709342 -126.747779) (xy 60.661514 -126.773904) (xy 60.610456 -126.792956)
			(xy 60.557205 -126.804547) (xy 60.502847 -126.808442) (xy 60.448488 -126.804561) (xy 60.395235 -126.792983)
			(xy 60.344172 -126.773943) (xy 60.296338 -126.74783) (xy 60.252707 -126.715175) (xy 60.214168 -126.676643)
			(xy 60.181506 -126.633018) (xy 60.155384 -126.585189) (xy 60.136336 -126.534129) (xy 60.124749 -126.480878)
			(xy 60.120858 -126.426519) (xy 59.405716 -126.426519) (xy 59.401825 -126.480876) (xy 59.390238 -126.534126)
			(xy 59.371189 -126.585184) (xy 59.345068 -126.633011) (xy 59.312405 -126.676634) (xy 59.273866 -126.715164)
			(xy 59.230235 -126.747817) (xy 59.182402 -126.773927) (xy 59.131339 -126.792963) (xy 59.078087 -126.804538)
			(xy 59.023729 -126.808416) (xy 58.969373 -126.804518) (xy 58.916124 -126.792923) (xy 58.865069 -126.773868)
			(xy 58.817245 -126.74774) (xy 58.795158 -126.731776) (xy 58.776146 -126.71818) (xy 58.734263 -126.697448)
			(xy 58.689295 -126.684722) (xy 58.642758 -126.680432) (xy 58.596221 -126.684722) (xy 58.551253 -126.697448)
			(xy 58.50937 -126.71818) (xy 58.490358 -126.731776) (xy 58.468301 -126.747776) (xy 58.420476 -126.773894)
			(xy 58.369422 -126.79294) (xy 58.316176 -126.804526) (xy 58.261823 -126.808417) (xy 58.20747 -126.804533)
			(xy 58.154223 -126.792953) (xy 58.103166 -126.773913) (xy 58.055338 -126.747801) (xy 58.011714 -126.715148)
			(xy 57.97318 -126.676618) (xy 57.940522 -126.632997) (xy 57.914405 -126.585173) (xy 57.895359 -126.534118)
			(xy 57.883773 -126.480872) (xy 57.879883 -126.426519) (xy 40.79842 -126.426519) (xy 40.799227 -126.427997)
			(xy 40.818278 -126.479059) (xy 40.829867 -126.532313) (xy 40.833759 -126.586675) (xy 40.829874 -126.641037)
			(xy 40.818292 -126.694292) (xy 40.799248 -126.745357) (xy 40.773131 -126.793192) (xy 40.740471 -126.836823)
			(xy 40.701934 -126.875361) (xy 40.658304 -126.908023) (xy 40.61047 -126.934142) (xy 40.559406 -126.953188)
			(xy 40.506151 -126.964772) (xy 40.451789 -126.968659) (xy 40.397428 -126.964769) (xy 40.344173 -126.953182)
			(xy 40.29311 -126.934133) (xy 40.245278 -126.908011) (xy 40.223186 -126.89205) (xy 40.204174 -126.878454)
			(xy 40.162291 -126.857722) (xy 40.117323 -126.844996) (xy 40.070786 -126.840706) (xy 40.024249 -126.844996)
			(xy 39.979281 -126.857722) (xy 39.937398 -126.878454) (xy 39.918386 -126.89205) (xy 39.896259 -126.907952)
			(xy 39.848437 -126.934065) (xy 39.797385 -126.953106) (xy 39.744143 -126.964688) (xy 39.689795 -126.968575)
			(xy 39.635447 -126.964687) (xy 39.582205 -126.953103) (xy 39.531154 -126.934061) (xy 39.483333 -126.907947)
			(xy 39.439715 -126.875292) (xy 39.401188 -126.836762) (xy 39.368537 -126.793142) (xy 39.342427 -126.745318)
			(xy 39.323388 -126.694266) (xy 39.311809 -126.641023) (xy 39.307925 -126.586675) (xy 36.281802 -126.586675)
			(xy 36.263477 -126.610941) (xy 36.204933 -126.675161) (xy 36.140713 -126.733705) (xy 36.071366 -126.786074)
			(xy 35.997482 -126.831821) (xy 35.919693 -126.870555) (xy 35.838661 -126.901947) (xy 35.755079 -126.925728)
			(xy 35.669659 -126.941696) (xy 35.58313 -126.949714) (xy 35.49623 -126.949714) (xy 35.409701 -126.941696)
			(xy 35.324281 -126.925728) (xy 35.240699 -126.901947) (xy 35.159667 -126.870555) (xy 35.081878 -126.831821)
			(xy 35.007994 -126.786074) (xy 34.938647 -126.733705) (xy 34.874427 -126.675161) (xy 34.815883 -126.610941)
			(xy 34.763514 -126.541594) (xy 34.717767 -126.46771) (xy 34.679033 -126.389921) (xy 34.647641 -126.308889)
			(xy 34.62386 -126.225307) (xy 34.607892 -126.139887) (xy 34.599874 -126.053358) (xy 31.398576 -126.053358)
			(xy 31.39657 -126.096735) (xy 31.384557 -126.182835) (xy 31.364648 -126.267458) (xy 31.337013 -126.349883)
			(xy 31.301889 -126.429405) (xy 31.259575 -126.505346) (xy 31.210433 -126.577057) (xy 31.154881 -126.643927)
			(xy 31.093395 -126.705383) (xy 31.026499 -126.760903) (xy 30.954764 -126.810011) (xy 30.878803 -126.852289)
			(xy 30.799264 -126.887375) (xy 30.716826 -126.91497) (xy 30.632194 -126.934839) (xy 30.546088 -126.946812)
			(xy 30.459245 -126.950786) (xy 30.372406 -126.946728) (xy 30.286312 -126.934672) (xy 30.201699 -126.914721)
			(xy 30.119288 -126.887046) (xy 30.039783 -126.851883) (xy 29.963862 -126.809532) (xy 29.892175 -126.760355)
			(xy 29.825333 -126.70477) (xy 29.763906 -126.643254) (xy 29.73578 -126.61011) (xy 29.721738 -126.594635)
			(xy 29.689504 -126.56805) (xy 29.653349 -126.547107) (xy 29.61425 -126.532373) (xy 29.573265 -126.524245)
			(xy 29.531502 -126.522944) (xy 29.510736 -126.525274) (xy 29.495673 -126.527723) (xy 29.467249 -126.538805)
			(xy 29.442274 -126.556327) (xy 29.422182 -126.579285) (xy 29.408124 -126.606361) (xy 29.400907 -126.636003)
			(xy 29.4005 -126.651258) (xy 29.4005 -127.908558) (xy 29.400954 -127.923805) (xy 29.408199 -127.953425)
			(xy 29.422261 -127.980483) (xy 29.442339 -128.003434) (xy 29.467287 -128.020969) (xy 29.495682 -128.032087)
			(xy 29.510736 -128.034542) (xy 29.531497 -128.036872) (xy 29.57325 -128.035527) (xy 29.614221 -128.027375)
			(xy 29.653308 -128.012635) (xy 29.68946 -127.991704) (xy 29.721704 -127.965144) (xy 29.73578 -127.949706)
			(xy 29.763898 -127.916555) (xy 29.825324 -127.855038) (xy 29.892165 -127.799453) (xy 29.963852 -127.750274)
			(xy 30.039772 -127.707922) (xy 30.119276 -127.672758) (xy 30.201687 -127.645082) (xy 30.2863 -127.62513)
			(xy 30.372394 -127.613073) (xy 30.459233 -127.609014) (xy 30.546076 -127.612987) (xy 30.632181 -127.624959)
			(xy 30.716815 -127.644826) (xy 30.799253 -127.67242) (xy 30.878792 -127.707506) (xy 30.954754 -127.749782)
			(xy 31.026489 -127.79889) (xy 31.093386 -127.854408) (xy 31.154873 -127.915864) (xy 31.210425 -127.982733)
			(xy 31.259569 -128.054444) (xy 31.301883 -128.130384) (xy 31.337009 -128.209906) (xy 31.364644 -128.29233)
			(xy 31.384555 -128.376953) (xy 31.396569 -128.463053) (xy 31.400586 -128.549894) (xy 31.398576 -128.593358)
			(xy 34.599874 -128.593358) (xy 34.599874 -128.506458) (xy 34.607892 -128.419929) (xy 34.62386 -128.334509)
			(xy 34.647641 -128.250927) (xy 34.679033 -128.169895) (xy 34.717767 -128.092106) (xy 34.763514 -128.018222)
			(xy 34.815883 -127.948875) (xy 34.874427 -127.884655) (xy 34.938647 -127.826111) (xy 35.007994 -127.773742)
			(xy 35.081878 -127.727995) (xy 35.159667 -127.689261) (xy 35.240699 -127.657869) (xy 35.324281 -127.634088)
			(xy 35.409701 -127.61812) (xy 35.49623 -127.610102) (xy 35.58313 -127.610102) (xy 35.669659 -127.61812)
			(xy 35.755079 -127.634088) (xy 35.838661 -127.657869) (xy 35.919693 -127.689261) (xy 35.997482 -127.727995)
			(xy 36.071366 -127.773742) (xy 36.140713 -127.826111) (xy 36.204933 -127.884655) (xy 36.263477 -127.948875)
			(xy 36.315846 -128.018222) (xy 36.361593 -128.092106) (xy 36.400327 -128.169895) (xy 36.431719 -128.250927)
			(xy 36.4555 -128.334509) (xy 36.471468 -128.419929) (xy 36.479486 -128.506458) (xy 36.479988 -128.549908)
			(xy 36.479486 -128.593358) (xy 36.476285 -128.627908) (xy 39.307881 -128.627908) (xy 39.311767 -128.573554)
			(xy 39.32335 -128.520305) (xy 39.342393 -128.469248) (xy 39.368508 -128.42142) (xy 39.401165 -128.377795)
			(xy 39.439698 -128.339263) (xy 39.483322 -128.306607) (xy 39.531151 -128.280491) (xy 39.582209 -128.261449)
			(xy 39.635457 -128.249867) (xy 39.689812 -128.245981) (xy 39.744166 -128.24987) (xy 39.797414 -128.261455)
			(xy 39.848471 -128.280501) (xy 39.896297 -128.306619) (xy 39.918386 -128.322578) (xy 39.937398 -128.336174)
			(xy 39.979281 -128.356906) (xy 40.024249 -128.369632) (xy 40.070786 -128.373922) (xy 40.117323 -128.369632)
			(xy 40.162291 -128.356906) (xy 40.204174 -128.336174) (xy 40.223186 -128.322578) (xy 40.245288 -128.306636)
			(xy 40.293113 -128.280515) (xy 40.34417 -128.261466) (xy 40.397417 -128.249878) (xy 40.451772 -128.245986)
			(xy 40.506128 -128.24987) (xy 40.559377 -128.261451) (xy 40.610437 -128.280492) (xy 40.658266 -128.306606)
			(xy 40.701892 -128.339262) (xy 40.740426 -128.377794) (xy 40.773084 -128.421418) (xy 40.7992 -128.469246)
			(xy 40.818244 -128.520304) (xy 40.829827 -128.573553) (xy 40.833714 -128.627908) (xy 40.829825 -128.682264)
			(xy 40.826864 -128.695873) (xy 47.574952 -128.695873) (xy 47.574952 -128.614763) (xy 47.582902 -128.534044)
			(xy 47.598725 -128.454493) (xy 47.62227 -128.376877) (xy 47.653309 -128.301941) (xy 47.691544 -128.230409)
			(xy 47.736606 -128.162969) (xy 47.788061 -128.10027) (xy 47.845414 -128.042917) (xy 47.908113 -127.991462)
			(xy 47.975553 -127.9464) (xy 48.047085 -127.908165) (xy 48.122021 -127.877126) (xy 48.199637 -127.853581)
			(xy 48.279188 -127.837758) (xy 48.359907 -127.829808) (xy 48.441017 -127.829808) (xy 48.521736 -127.837758)
			(xy 48.601287 -127.853581) (xy 48.678903 -127.877126) (xy 48.753839 -127.908165) (xy 48.825371 -127.9464)
			(xy 48.892811 -127.991462) (xy 48.95551 -128.042917) (xy 49.012863 -128.10027) (xy 49.064318 -128.162969)
			(xy 49.10938 -128.230409) (xy 49.147615 -128.301941) (xy 49.178654 -128.376877) (xy 49.202199 -128.454493)
			(xy 49.218022 -128.534044) (xy 49.225972 -128.614763) (xy 49.22647 -128.655318) (xy 49.225972 -128.695873)
			(xy 51.075072 -128.695873) (xy 51.075072 -128.614763) (xy 51.083022 -128.534044) (xy 51.098845 -128.454493)
			(xy 51.12239 -128.376877) (xy 51.153429 -128.301941) (xy 51.191664 -128.230409) (xy 51.236726 -128.162969)
			(xy 51.288181 -128.10027) (xy 51.345534 -128.042917) (xy 51.408233 -127.991462) (xy 51.475673 -127.9464)
			(xy 51.547205 -127.908165) (xy 51.622141 -127.877126) (xy 51.699757 -127.853581) (xy 51.779308 -127.837758)
			(xy 51.860027 -127.829808) (xy 51.941137 -127.829808) (xy 52.021856 -127.837758) (xy 52.101407 -127.853581)
			(xy 52.179023 -127.877126) (xy 52.253959 -127.908165) (xy 52.325491 -127.9464) (xy 52.392931 -127.991462)
			(xy 52.45563 -128.042917) (xy 52.512983 -128.10027) (xy 52.564438 -128.162969) (xy 52.6095 -128.230409)
			(xy 52.647735 -128.301941) (xy 52.678774 -128.376877) (xy 52.702319 -128.454493) (xy 52.704925 -128.467593)
			(xy 57.879918 -128.467593) (xy 57.883806 -128.413245) (xy 57.895389 -128.360004) (xy 57.914432 -128.308953)
			(xy 57.940545 -128.261132) (xy 57.973199 -128.217514) (xy 58.011728 -128.178987) (xy 58.055347 -128.146335)
			(xy 58.10317 -128.120224) (xy 58.154222 -128.101184) (xy 58.207463 -128.089604) (xy 58.261811 -128.085718)
			(xy 58.316159 -128.089607) (xy 58.3694 -128.101191) (xy 58.420451 -128.120233) (xy 58.468272 -128.146348)
			(xy 58.490358 -128.162304) (xy 58.50937 -128.1759) (xy 58.551253 -128.196632) (xy 58.596221 -128.209358)
			(xy 58.642758 -128.213648) (xy 58.689295 -128.209358) (xy 58.734263 -128.196632) (xy 58.776146 -128.1759)
			(xy 58.795158 -128.162304) (xy 58.817236 -128.146324) (xy 58.865065 -128.120195) (xy 58.916126 -128.10114)
			(xy 58.969379 -128.089546) (xy 59.023741 -128.085649) (xy 59.078103 -128.089529) (xy 59.13136 -128.101106)
			(xy 59.182427 -128.120146) (xy 59.230265 -128.14626) (xy 59.273898 -128.178917) (xy 59.312439 -128.217452)
			(xy 59.345104 -128.26108) (xy 59.371226 -128.308912) (xy 59.390275 -128.359976) (xy 59.401862 -128.413231)
			(xy 59.405751 -128.467593) (xy 60.120893 -128.467593) (xy 60.124782 -128.413239) (xy 60.136366 -128.359993)
			(xy 60.155411 -128.308937) (xy 60.181529 -128.261111) (xy 60.214187 -128.217489) (xy 60.252721 -128.178959)
			(xy 60.296347 -128.146306) (xy 60.344175 -128.120194) (xy 60.395233 -128.101155) (xy 60.448481 -128.089576)
			(xy 60.502835 -128.085693) (xy 60.557188 -128.089586) (xy 60.610434 -128.101174) (xy 60.661489 -128.120223)
			(xy 60.709313 -128.146344) (xy 60.7314 -128.162304) (xy 60.750412 -128.1759) (xy 60.792295 -128.196632)
			(xy 60.837263 -128.209358) (xy 60.8838 -128.213648) (xy 60.930337 -128.209358) (xy 60.975305 -128.196632)
			(xy 61.017188 -128.1759) (xy 61.0362 -128.162304) (xy 61.058277 -128.146328) (xy 61.106103 -128.120206)
			(xy 61.15716 -128.101156) (xy 61.210409 -128.089567) (xy 61.264765 -128.085674) (xy 61.319121 -128.089557)
			(xy 61.372372 -128.101136) (xy 61.423433 -128.120176) (xy 61.471264 -128.14629) (xy 61.514891 -128.178945)
			(xy 61.553427 -128.217476) (xy 61.586087 -128.261101) (xy 61.612206 -128.308929) (xy 61.631252 -128.359987)
			(xy 61.642837 -128.413237) (xy 61.646726 -128.467593) (xy 62.024903 -128.467593) (xy 62.028791 -128.413242)
			(xy 62.040375 -128.359997) (xy 62.059419 -128.308943) (xy 62.085535 -128.261119) (xy 62.118192 -128.217498)
			(xy 62.156724 -128.17897) (xy 62.200347 -128.146317) (xy 62.248173 -128.120205) (xy 62.299229 -128.101166)
			(xy 62.352475 -128.089586) (xy 62.406826 -128.085703) (xy 62.461177 -128.089594) (xy 62.514421 -128.101181)
			(xy 62.565474 -128.120227) (xy 62.613297 -128.146345) (xy 62.635384 -128.162304) (xy 62.654396 -128.1759)
			(xy 62.696279 -128.196632) (xy 62.741247 -128.209358) (xy 62.787784 -128.213648) (xy 62.834321 -128.209358)
			(xy 62.879289 -128.196632) (xy 62.921172 -128.1759) (xy 62.940184 -128.162304) (xy 62.962261 -128.146327)
			(xy 63.010089 -128.120202) (xy 63.061147 -128.10115) (xy 63.114398 -128.089559) (xy 63.168756 -128.085664)
			(xy 63.223115 -128.089546) (xy 63.276368 -128.101125) (xy 63.327431 -128.120165) (xy 63.375264 -128.146279)
			(xy 63.418894 -128.178934) (xy 63.457432 -128.217467) (xy 63.490094 -128.261093) (xy 63.516214 -128.308922)
			(xy 63.535261 -128.359983) (xy 63.546847 -128.413234) (xy 63.550736 -128.467593) (xy 63.546849 -128.521951)
			(xy 63.535265 -128.575203) (xy 63.51622 -128.626264) (xy 63.490101 -128.674095) (xy 63.457441 -128.717722)
			(xy 63.418905 -128.756256) (xy 63.375276 -128.788914) (xy 63.327444 -128.815029) (xy 63.276381 -128.834071)
			(xy 63.223129 -128.845652) (xy 63.16877 -128.849536) (xy 63.114412 -128.845643) (xy 63.061161 -128.834054)
			(xy 63.010102 -128.815004) (xy 62.962273 -128.788881) (xy 62.940184 -128.77292) (xy 62.921172 -128.759324)
			(xy 62.879289 -128.738592) (xy 62.834321 -128.725866) (xy 62.787784 -128.721576) (xy 62.741247 -128.725866)
			(xy 62.696279 -128.738592) (xy 62.654396 -128.759324) (xy 62.635384 -128.77292) (xy 62.613285 -128.788862)
			(xy 62.565461 -128.814979) (xy 62.514407 -128.834024) (xy 62.461163 -128.845608) (xy 62.406812 -128.849497)
			(xy 62.35246 -128.845612) (xy 62.299215 -128.83403) (xy 62.24816 -128.814989) (xy 62.200335 -128.788875)
			(xy 62.156713 -128.756221) (xy 62.118182 -128.717691) (xy 62.085527 -128.674069) (xy 62.059413 -128.626244)
			(xy 62.040371 -128.575189) (xy 62.028789 -128.521944) (xy 62.024903 -128.467593) (xy 61.646726 -128.467593)
			(xy 61.642839 -128.521949) (xy 61.631256 -128.575199) (xy 61.612212 -128.626258) (xy 61.586095 -128.674087)
			(xy 61.553437 -128.717713) (xy 61.514902 -128.756246) (xy 61.471276 -128.788902) (xy 61.423446 -128.815018)
			(xy 61.372386 -128.83406) (xy 61.319136 -128.845641) (xy 61.264779 -128.849526) (xy 61.210423 -128.845635)
			(xy 61.157174 -128.834048) (xy 61.106116 -128.815) (xy 61.058289 -128.78888) (xy 61.0362 -128.77292)
			(xy 61.017188 -128.759324) (xy 60.975305 -128.738592) (xy 60.930337 -128.725866) (xy 60.8838 -128.721576)
			(xy 60.837263 -128.725866) (xy 60.792295 -128.738592) (xy 60.750412 -128.759324) (xy 60.7314 -128.77292)
			(xy 60.709301 -128.788864) (xy 60.661476 -128.814983) (xy 60.61042 -128.83403) (xy 60.557174 -128.845616)
			(xy 60.502821 -128.849507) (xy 60.448467 -128.845622) (xy 60.395219 -128.834041) (xy 60.344162 -128.815)
			(xy 60.296334 -128.788886) (xy 60.25271 -128.756231) (xy 60.214178 -128.7177) (xy 60.181521 -128.674077)
			(xy 60.155405 -128.62625) (xy 60.136362 -128.575194) (xy 60.12478 -128.521946) (xy 60.120893 -128.467593)
			(xy 59.405751 -128.467593) (xy 59.401864 -128.521955) (xy 59.390279 -128.57521) (xy 59.371232 -128.626275)
			(xy 59.345112 -128.674108) (xy 59.312449 -128.717737) (xy 59.273909 -128.756273) (xy 59.230277 -128.788932)
			(xy 59.18244 -128.815048) (xy 59.131374 -128.83409) (xy 59.078118 -128.845669) (xy 59.023755 -128.849551)
			(xy 58.969394 -128.845657) (xy 58.91614 -128.834064) (xy 58.865078 -128.815011) (xy 58.817248 -128.788883)
			(xy 58.795158 -128.77292) (xy 58.776146 -128.759324) (xy 58.734263 -128.738592) (xy 58.689295 -128.725866)
			(xy 58.642758 -128.721576) (xy 58.596221 -128.725866) (xy 58.551253 -128.738592) (xy 58.50937 -128.759324)
			(xy 58.490358 -128.77292) (xy 58.46826 -128.78886) (xy 58.420438 -128.814973) (xy 58.369386 -128.834013)
			(xy 58.316145 -128.845595) (xy 58.261797 -128.849482) (xy 58.207449 -128.845594) (xy 58.154208 -128.834012)
			(xy 58.103157 -128.81497) (xy 58.055335 -128.788857) (xy 58.011717 -128.756204) (xy 57.97319 -128.717675)
			(xy 57.940538 -128.674056) (xy 57.914426 -128.626234) (xy 57.895385 -128.575182) (xy 57.883804 -128.521941)
			(xy 57.879918 -128.467593) (xy 52.704925 -128.467593) (xy 52.718142 -128.534044) (xy 52.726092 -128.614763)
			(xy 52.72659 -128.655318) (xy 52.726092 -128.695873) (xy 52.718142 -128.776592) (xy 52.702319 -128.856143)
			(xy 52.678774 -128.933759) (xy 52.647735 -129.008695) (xy 52.6095 -129.080227) (xy 52.564438 -129.147667)
			(xy 52.512983 -129.210366) (xy 52.45563 -129.267719) (xy 52.392931 -129.319174) (xy 52.325491 -129.364236)
			(xy 52.253959 -129.402471) (xy 52.179023 -129.43351) (xy 52.101407 -129.457055) (xy 52.021856 -129.472878)
			(xy 51.941137 -129.480828) (xy 51.860027 -129.480828) (xy 51.779308 -129.472878) (xy 51.699757 -129.457055)
			(xy 51.622141 -129.43351) (xy 51.547205 -129.402471) (xy 51.475673 -129.364236) (xy 51.408233 -129.319174)
			(xy 51.345534 -129.267719) (xy 51.288181 -129.210366) (xy 51.236726 -129.147667) (xy 51.191664 -129.080227)
			(xy 51.153429 -129.008695) (xy 51.12239 -128.933759) (xy 51.098845 -128.856143) (xy 51.083022 -128.776592)
			(xy 51.075072 -128.695873) (xy 49.225972 -128.695873) (xy 49.218022 -128.776592) (xy 49.202199 -128.856143)
			(xy 49.178654 -128.933759) (xy 49.147615 -129.008695) (xy 49.10938 -129.080227) (xy 49.064318 -129.147667)
			(xy 49.012863 -129.210366) (xy 48.95551 -129.267719) (xy 48.892811 -129.319174) (xy 48.825371 -129.364236)
			(xy 48.753839 -129.402471) (xy 48.678903 -129.43351) (xy 48.601287 -129.457055) (xy 48.521736 -129.472878)
			(xy 48.441017 -129.480828) (xy 48.359907 -129.480828) (xy 48.279188 -129.472878) (xy 48.199637 -129.457055)
			(xy 48.122021 -129.43351) (xy 48.047085 -129.402471) (xy 47.975553 -129.364236) (xy 47.908113 -129.319174)
			(xy 47.845414 -129.267719) (xy 47.788061 -129.210366) (xy 47.736606 -129.147667) (xy 47.691544 -129.080227)
			(xy 47.653309 -129.008695) (xy 47.62227 -128.933759) (xy 47.598725 -128.856143) (xy 47.582902 -128.776592)
			(xy 47.574952 -128.695873) (xy 40.826864 -128.695873) (xy 40.818239 -128.735512) (xy 40.799193 -128.786569)
			(xy 40.773075 -128.834396) (xy 40.740415 -128.878019) (xy 40.701879 -128.916549) (xy 40.658252 -128.949203)
			(xy 40.610421 -128.975315) (xy 40.559361 -128.994354) (xy 40.506111 -129.005932) (xy 40.451756 -129.009814)
			(xy 40.397401 -129.00592) (xy 40.344154 -128.994329) (xy 40.293098 -128.975278) (xy 40.245273 -128.949155)
			(xy 40.223186 -128.933194) (xy 40.204174 -128.919598) (xy 40.162291 -128.898866) (xy 40.117323 -128.88614)
			(xy 40.070786 -128.88185) (xy 40.024249 -128.88614) (xy 39.979281 -128.898866) (xy 39.937398 -128.919598)
			(xy 39.918386 -128.933194) (xy 39.896311 -128.949172) (xy 39.848486 -128.975292) (xy 39.79743 -128.99434)
			(xy 39.744183 -129.005928) (xy 39.689828 -129.009819) (xy 39.635474 -129.005936) (xy 39.582225 -128.994356)
			(xy 39.531166 -128.975316) (xy 39.483337 -128.949202) (xy 39.439711 -128.916548) (xy 39.401176 -128.878017)
			(xy 39.368517 -128.834394) (xy 39.3424 -128.786568) (xy 39.323354 -128.735511) (xy 39.31177 -128.682263)
			(xy 39.307881 -128.627908) (xy 36.476285 -128.627908) (xy 36.471468 -128.679887) (xy 36.4555 -128.765307)
			(xy 36.431719 -128.848889) (xy 36.400327 -128.929921) (xy 36.361593 -129.00771) (xy 36.315846 -129.081594)
			(xy 36.263477 -129.150941) (xy 36.204933 -129.215161) (xy 36.140713 -129.273705) (xy 36.071366 -129.326074)
			(xy 35.997482 -129.371821) (xy 35.919693 -129.410555) (xy 35.838661 -129.441947) (xy 35.755079 -129.465728)
			(xy 35.669659 -129.481696) (xy 35.58313 -129.489714) (xy 35.49623 -129.489714) (xy 35.409701 -129.481696)
			(xy 35.324281 -129.465728) (xy 35.240699 -129.441947) (xy 35.159667 -129.410555) (xy 35.081878 -129.371821)
			(xy 35.007994 -129.326074) (xy 34.938647 -129.273705) (xy 34.874427 -129.215161) (xy 34.815883 -129.150941)
			(xy 34.763514 -129.081594) (xy 34.717767 -129.00771) (xy 34.679033 -128.929921) (xy 34.647641 -128.848889)
			(xy 34.62386 -128.765307) (xy 34.607892 -128.679887) (xy 34.599874 -128.593358) (xy 31.398576 -128.593358)
			(xy 31.39657 -128.636735) (xy 31.384557 -128.722835) (xy 31.364648 -128.807458) (xy 31.337013 -128.889883)
			(xy 31.301889 -128.969405) (xy 31.259575 -129.045346) (xy 31.210433 -129.117057) (xy 31.154881 -129.183927)
			(xy 31.093395 -129.245383) (xy 31.026499 -129.300903) (xy 30.954764 -129.350011) (xy 30.878803 -129.392289)
			(xy 30.799264 -129.427375) (xy 30.716826 -129.45497) (xy 30.632194 -129.474839) (xy 30.546088 -129.486812)
			(xy 30.459245 -129.490786) (xy 30.372406 -129.486728) (xy 30.286312 -129.474672) (xy 30.201699 -129.454721)
			(xy 30.119288 -129.427046) (xy 30.039783 -129.391883) (xy 29.963862 -129.349532) (xy 29.892175 -129.300355)
			(xy 29.825333 -129.24477) (xy 29.763906 -129.183254) (xy 29.73578 -129.15011) (xy 29.721738 -129.134635)
			(xy 29.689504 -129.10805) (xy 29.653349 -129.087107) (xy 29.61425 -129.072373) (xy 29.573265 -129.064245)
			(xy 29.531502 -129.062944) (xy 29.510736 -129.065274) (xy 29.495673 -129.067723) (xy 29.467249 -129.078805)
			(xy 29.442274 -129.096327) (xy 29.422182 -129.119285) (xy 29.408124 -129.146361) (xy 29.400907 -129.176003)
			(xy 29.4005 -129.191258) (xy 29.4005 -130.448558) (xy 29.400954 -130.463805) (xy 29.408199 -130.493425)
			(xy 29.422261 -130.520483) (xy 29.442339 -130.543434) (xy 29.467287 -130.560969) (xy 29.495682 -130.572087)
			(xy 29.510736 -130.574542) (xy 29.531497 -130.576872) (xy 29.57325 -130.575527) (xy 29.614221 -130.567375)
			(xy 29.653308 -130.552635) (xy 29.68946 -130.531704) (xy 29.721704 -130.505144) (xy 29.73578 -130.489706)
			(xy 29.763898 -130.456555) (xy 29.825324 -130.395038) (xy 29.892165 -130.339453) (xy 29.963852 -130.290274)
			(xy 30.039772 -130.247922) (xy 30.119276 -130.212758) (xy 30.201687 -130.185082) (xy 30.2863 -130.16513)
			(xy 30.372394 -130.153073) (xy 30.459233 -130.149014) (xy 30.546076 -130.152987) (xy 30.632181 -130.164959)
			(xy 30.716815 -130.184826) (xy 30.799253 -130.21242) (xy 30.878792 -130.247506) (xy 30.954754 -130.289782)
			(xy 31.026489 -130.33889) (xy 31.093386 -130.394408) (xy 31.154873 -130.455864) (xy 31.210425 -130.522733)
			(xy 31.259569 -130.594444) (xy 31.301883 -130.670384) (xy 31.337009 -130.749906) (xy 31.364644 -130.83233)
			(xy 31.384555 -130.916953) (xy 31.396569 -131.003053) (xy 31.400586 -131.089894) (xy 31.398576 -131.133358)
			(xy 34.599874 -131.133358) (xy 34.599874 -131.046458) (xy 34.607892 -130.959929) (xy 34.62386 -130.874509)
			(xy 34.647641 -130.790927) (xy 34.679033 -130.709895) (xy 34.717767 -130.632106) (xy 34.763514 -130.558222)
			(xy 34.815883 -130.488875) (xy 34.874427 -130.424655) (xy 34.938647 -130.366111) (xy 35.007994 -130.313742)
			(xy 35.081878 -130.267995) (xy 35.159667 -130.229261) (xy 35.240699 -130.197869) (xy 35.324281 -130.174088)
			(xy 35.409701 -130.15812) (xy 35.49623 -130.150102) (xy 35.58313 -130.150102) (xy 35.669659 -130.15812)
			(xy 35.755079 -130.174088) (xy 35.838661 -130.197869) (xy 35.919693 -130.229261) (xy 35.997482 -130.267995)
			(xy 36.071366 -130.313742) (xy 36.140713 -130.366111) (xy 36.204933 -130.424655) (xy 36.263477 -130.488875)
			(xy 36.300343 -130.537693) (xy 39.307901 -130.537693) (xy 39.31179 -130.483341) (xy 39.323374 -130.430096)
			(xy 39.342418 -130.379042) (xy 39.368534 -130.331218) (xy 39.401191 -130.287597) (xy 39.439723 -130.249068)
			(xy 39.483347 -130.216416) (xy 39.531173 -130.190304) (xy 39.582229 -130.171264) (xy 39.635475 -130.159685)
			(xy 39.689827 -130.155801) (xy 39.744179 -130.159693) (xy 39.797423 -130.17128) (xy 39.848476 -130.190326)
			(xy 39.896299 -130.216445) (xy 39.918386 -130.232404) (xy 39.937398 -130.246) (xy 39.979281 -130.266732)
			(xy 40.024249 -130.279458) (xy 40.070786 -130.283748) (xy 40.117323 -130.279458) (xy 40.162291 -130.266732)
			(xy 40.204174 -130.246) (xy 40.223186 -130.232404) (xy 40.245263 -130.216427) (xy 40.29309 -130.190302)
			(xy 40.344149 -130.171251) (xy 40.397399 -130.15966) (xy 40.451757 -130.155765) (xy 40.506115 -130.159647)
			(xy 40.559368 -130.171226) (xy 40.610431 -130.190266) (xy 40.658264 -130.21638) (xy 40.701894 -130.249036)
			(xy 40.740431 -130.287568) (xy 40.773093 -130.331194) (xy 40.798314 -130.377377) (xy 57.879939 -130.377377)
			(xy 57.883829 -130.323033) (xy 57.895414 -130.269795) (xy 57.914457 -130.218747) (xy 57.940571 -130.17093)
			(xy 57.973225 -130.127316) (xy 58.011753 -130.088792) (xy 58.055372 -130.056144) (xy 58.103193 -130.030036)
			(xy 58.154242 -130.011) (xy 58.207482 -129.999422) (xy 58.261827 -129.995539) (xy 58.316172 -129.99943)
			(xy 58.369409 -130.011015) (xy 58.420456 -130.030059) (xy 58.468274 -130.056174) (xy 58.490358 -130.07213)
			(xy 58.50937 -130.085726) (xy 58.551253 -130.106458) (xy 58.596221 -130.119184) (xy 58.642758 -130.123474)
			(xy 58.689295 -130.119184) (xy 58.734263 -130.106458) (xy 58.776146 -130.085726) (xy 58.795158 -130.07213)
			(xy 58.817212 -130.056115) (xy 58.865042 -130.029983) (xy 58.916105 -130.010924) (xy 58.969361 -129.999327)
			(xy 59.023725 -129.995428) (xy 59.078091 -129.999306) (xy 59.131351 -130.010882) (xy 59.182422 -130.029921)
			(xy 59.230263 -130.056034) (xy 59.2739 -130.088691) (xy 59.312445 -130.127226) (xy 59.345113 -130.170855)
			(xy 59.371239 -130.218689) (xy 59.39029 -130.269755) (xy 59.40188 -130.323012) (xy 59.405772 -130.377377)
			(xy 60.120914 -130.377377) (xy 60.124805 -130.323027) (xy 60.136391 -130.269783) (xy 60.155437 -130.218731)
			(xy 60.181555 -130.170909) (xy 60.214213 -130.127291) (xy 60.252747 -130.088765) (xy 60.296371 -130.056115)
			(xy 60.344198 -130.030006) (xy 60.395254 -130.01097) (xy 60.4485 -129.999394) (xy 60.502851 -129.995514)
			(xy 60.557201 -129.999409) (xy 60.610443 -130.010999) (xy 60.661494 -130.030048) (xy 60.709315 -130.05617)
			(xy 60.7314 -130.07213) (xy 60.750412 -130.085726) (xy 60.792295 -130.106458) (xy 60.837263 -130.119184)
			(xy 60.8838 -130.123474) (xy 60.930337 -130.119184) (xy 60.975305 -130.106458) (xy 61.017188 -130.085726)
			(xy 61.0362 -130.07213) (xy 61.058253 -130.056119) (xy 61.10608 -130.029993) (xy 61.157139 -130.01094)
			(xy 61.21039 -129.999348) (xy 61.264749 -129.995453) (xy 61.319109 -129.999334) (xy 61.372363 -130.010912)
			(xy 61.423427 -130.029951) (xy 61.471262 -130.056064) (xy 61.514893 -130.088719) (xy 61.553433 -130.127251)
			(xy 61.586096 -130.170876) (xy 61.612219 -130.218706) (xy 61.631268 -130.269766) (xy 61.642856 -130.323018)
			(xy 61.646747 -130.377377) (xy 62.024923 -130.377377) (xy 62.028814 -130.323029) (xy 62.0404 -130.269788)
			(xy 62.059445 -130.218737) (xy 62.085561 -130.170917) (xy 62.118218 -130.1273) (xy 62.156749 -130.088775)
			(xy 62.200371 -130.056126) (xy 62.248196 -130.030018) (xy 62.29925 -130.010981) (xy 62.352493 -129.999405)
			(xy 62.406842 -129.995523) (xy 62.46119 -129.999417) (xy 62.51443 -130.011005) (xy 62.56548 -130.030052)
			(xy 62.613299 -130.056171) (xy 62.635384 -130.07213) (xy 62.654396 -130.085726) (xy 62.696279 -130.106458)
			(xy 62.741247 -130.119184) (xy 62.787784 -130.123474) (xy 62.834321 -130.119184) (xy 62.879289 -130.106458)
			(xy 62.921172 -130.085726) (xy 62.940184 -130.07213) (xy 62.962237 -130.056117) (xy 63.010066 -130.029989)
			(xy 63.061126 -130.010934) (xy 63.114379 -129.99934) (xy 63.16874 -129.995443) (xy 63.223102 -129.999323)
			(xy 63.276359 -130.0109) (xy 63.327425 -130.029939) (xy 63.375262 -130.056053) (xy 63.418896 -130.088708)
			(xy 63.457437 -130.127242) (xy 63.490103 -130.170868) (xy 63.516226 -130.2187) (xy 63.535276 -130.269762)
			(xy 63.546865 -130.323016) (xy 63.550757 -130.377377) (xy 63.546872 -130.431739) (xy 63.535289 -130.484994)
			(xy 63.516245 -130.536059) (xy 63.490127 -130.583893) (xy 63.457467 -130.627524) (xy 63.41893 -130.666062)
			(xy 63.375301 -130.698723) (xy 63.327467 -130.724842) (xy 63.276402 -130.743887) (xy 63.223147 -130.75547)
			(xy 63.168786 -130.759357) (xy 63.114424 -130.755466) (xy 63.06117 -130.743879) (xy 63.010107 -130.72483)
			(xy 62.962275 -130.698707) (xy 62.940184 -130.682746) (xy 62.921172 -130.66915) (xy 62.879289 -130.648418)
			(xy 62.834321 -130.635692) (xy 62.787784 -130.631402) (xy 62.741247 -130.635692) (xy 62.696279 -130.648418)
			(xy 62.654396 -130.66915) (xy 62.635384 -130.682746) (xy 62.613261 -130.698653) (xy 62.565438 -130.724767)
			(xy 62.514387 -130.743808) (xy 62.461145 -130.75539) (xy 62.406796 -130.759277) (xy 62.352448 -130.755389)
			(xy 62.299206 -130.743806) (xy 62.248155 -130.724763) (xy 62.200333 -130.698649) (xy 62.156715 -130.665995)
			(xy 62.118188 -130.627465) (xy 62.085536 -130.583845) (xy 62.059426 -130.536021) (xy 62.040387 -130.484968)
			(xy 62.028807 -130.431726) (xy 62.024923 -130.377377) (xy 61.646747 -130.377377) (xy 61.642862 -130.431737)
			(xy 61.63128 -130.48499) (xy 61.612237 -130.536053) (xy 61.586121 -130.583885) (xy 61.553463 -130.627514)
			(xy 61.514928 -130.666051) (xy 61.4713 -130.698712) (xy 61.423469 -130.72483) (xy 61.372407 -130.743875)
			(xy 61.319154 -130.75546) (xy 61.264795 -130.759347) (xy 61.210436 -130.755458) (xy 61.157183 -130.743872)
			(xy 61.106122 -130.724826) (xy 61.058291 -130.698706) (xy 61.0362 -130.682746) (xy 61.017188 -130.66915)
			(xy 60.975305 -130.648418) (xy 60.930337 -130.635692) (xy 60.8838 -130.631402) (xy 60.837263 -130.635692)
			(xy 60.792295 -130.648418) (xy 60.750412 -130.66915) (xy 60.7314 -130.682746) (xy 60.709276 -130.698655)
			(xy 60.661453 -130.72477) (xy 60.6104 -130.743814) (xy 60.557156 -130.755398) (xy 60.502805 -130.759286)
			(xy 60.448455 -130.755399) (xy 60.39521 -130.743817) (xy 60.344157 -130.724775) (xy 60.296333 -130.69866)
			(xy 60.252712 -130.666005) (xy 60.214183 -130.627475) (xy 60.18153 -130.583853) (xy 60.155418 -130.536027)
			(xy 60.136378 -130.484973) (xy 60.124798 -130.431728) (xy 60.120914 -130.377377) (xy 59.405772 -130.377377)
			(xy 59.401887 -130.431742) (xy 59.390303 -130.485001) (xy 59.371258 -130.536069) (xy 59.345138 -130.583906)
			(xy 59.312475 -130.627539) (xy 59.273934 -130.666079) (xy 59.230301 -130.698741) (xy 59.182463 -130.72486)
			(xy 59.131395 -130.743905) (xy 59.078136 -130.755488) (xy 59.023771 -130.759372) (xy 58.969406 -130.755479)
			(xy 58.916149 -130.743889) (xy 58.865084 -130.724836) (xy 58.81725 -130.698709) (xy 58.795158 -130.682746)
			(xy 58.776146 -130.66915) (xy 58.734263 -130.648418) (xy 58.689295 -130.635692) (xy 58.642758 -130.631402)
			(xy 58.596221 -130.635692) (xy 58.551253 -130.648418) (xy 58.50937 -130.66915) (xy 58.490358 -130.682746)
			(xy 58.468235 -130.698651) (xy 58.420415 -130.72476) (xy 58.369365 -130.743798) (xy 58.316126 -130.755377)
			(xy 58.261781 -130.759261) (xy 58.207437 -130.755371) (xy 58.154199 -130.743787) (xy 58.103151 -130.724745)
			(xy 58.055333 -130.698631) (xy 58.011719 -130.665978) (xy 57.973195 -130.62745) (xy 57.940547 -130.583832)
			(xy 57.914438 -130.536011) (xy 57.895401 -130.484962) (xy 57.883823 -130.431722) (xy 57.879939 -130.377377)
			(xy 40.798314 -130.377377) (xy 40.799213 -130.379023) (xy 40.81826 -130.430083) (xy 40.829845 -130.483335)
			(xy 40.833735 -130.537693) (xy 40.829848 -130.592051) (xy 40.818264 -130.645303) (xy 40.799219 -130.696364)
			(xy 40.773101 -130.744194) (xy 40.740441 -130.787821) (xy 40.701905 -130.826355) (xy 40.658276 -130.859012)
			(xy 40.610444 -130.885128) (xy 40.559382 -130.90417) (xy 40.50613 -130.915751) (xy 40.451771 -130.919635)
			(xy 40.397413 -130.915742) (xy 40.344163 -130.904154) (xy 40.293104 -130.885104) (xy 40.245275 -130.858981)
			(xy 40.223186 -130.84302) (xy 40.204174 -130.829424) (xy 40.162291 -130.808692) (xy 40.117323 -130.795966)
			(xy 40.070786 -130.791676) (xy 40.024249 -130.795966) (xy 39.979281 -130.808692) (xy 39.937398 -130.829424)
			(xy 39.918386 -130.84302) (xy 39.896287 -130.858963) (xy 39.848463 -130.885079) (xy 39.797409 -130.904124)
			(xy 39.744164 -130.915709) (xy 39.689813 -130.919599) (xy 39.635461 -130.915713) (xy 39.582216 -130.904132)
			(xy 39.53116 -130.88509) (xy 39.483335 -130.858976) (xy 39.439712 -130.826322) (xy 39.401182 -130.787792)
			(xy 39.368527 -130.74417) (xy 39.342412 -130.696345) (xy 39.32337 -130.64529) (xy 39.311788 -130.592045)
			(xy 39.307901 -130.537693) (xy 36.300343 -130.537693) (xy 36.315846 -130.558222) (xy 36.361593 -130.632106)
			(xy 36.400327 -130.709895) (xy 36.431719 -130.790927) (xy 36.4555 -130.874509) (xy 36.471468 -130.959929)
			(xy 36.479486 -131.046458) (xy 36.479988 -131.089908) (xy 36.479486 -131.133358) (xy 36.471468 -131.219887)
			(xy 36.4555 -131.305307) (xy 36.431719 -131.388889) (xy 36.400327 -131.469921) (xy 36.361593 -131.54771)
			(xy 36.315846 -131.621594) (xy 36.263477 -131.690941) (xy 36.204933 -131.755161) (xy 36.140713 -131.813705)
			(xy 36.071366 -131.866074) (xy 35.997482 -131.911821) (xy 35.919693 -131.950555) (xy 35.838661 -131.981947)
			(xy 35.755079 -132.005728) (xy 35.669659 -132.021696) (xy 35.58313 -132.029714) (xy 35.49623 -132.029714)
			(xy 35.409701 -132.021696) (xy 35.324281 -132.005728) (xy 35.240699 -131.981947) (xy 35.159667 -131.950555)
			(xy 35.081878 -131.911821) (xy 35.007994 -131.866074) (xy 34.938647 -131.813705) (xy 34.874427 -131.755161)
			(xy 34.815883 -131.690941) (xy 34.763514 -131.621594) (xy 34.717767 -131.54771) (xy 34.679033 -131.469921)
			(xy 34.647641 -131.388889) (xy 34.62386 -131.305307) (xy 34.607892 -131.219887) (xy 34.599874 -131.133358)
			(xy 31.398576 -131.133358) (xy 31.39657 -131.176735) (xy 31.384557 -131.262835) (xy 31.364648 -131.347458)
			(xy 31.337013 -131.429883) (xy 31.301889 -131.509405) (xy 31.259575 -131.585346) (xy 31.210433 -131.657057)
			(xy 31.154881 -131.723927) (xy 31.093395 -131.785383) (xy 31.026499 -131.840903) (xy 30.954764 -131.890011)
			(xy 30.878803 -131.932289) (xy 30.799264 -131.967375) (xy 30.716826 -131.99497) (xy 30.632194 -132.014839)
			(xy 30.546088 -132.026812) (xy 30.459245 -132.030786) (xy 30.372406 -132.026728) (xy 30.286312 -132.014672)
			(xy 30.201699 -131.994721) (xy 30.119288 -131.967046) (xy 30.039783 -131.931883) (xy 29.963862 -131.889532)
			(xy 29.892175 -131.840355) (xy 29.825333 -131.78477) (xy 29.763906 -131.723254) (xy 29.73578 -131.69011)
			(xy 29.721738 -131.674635) (xy 29.689504 -131.64805) (xy 29.653349 -131.627107) (xy 29.61425 -131.612373)
			(xy 29.573265 -131.604245) (xy 29.531502 -131.602944) (xy 29.510736 -131.605274) (xy 29.495673 -131.607723)
			(xy 29.467249 -131.618805) (xy 29.442274 -131.636327) (xy 29.422182 -131.659285) (xy 29.408124 -131.686361)
			(xy 29.400907 -131.716003) (xy 29.4005 -131.731258) (xy 29.4005 -132.988558) (xy 29.400954 -133.003805)
			(xy 29.408199 -133.033425) (xy 29.422261 -133.060483) (xy 29.442339 -133.083434) (xy 29.467287 -133.100969)
			(xy 29.495682 -133.112087) (xy 29.510736 -133.114542) (xy 29.531497 -133.116872) (xy 29.57325 -133.115527)
			(xy 29.614221 -133.107375) (xy 29.653308 -133.092635) (xy 29.68946 -133.071704) (xy 29.721704 -133.045144)
			(xy 29.73578 -133.029706) (xy 29.763898 -132.996555) (xy 29.825324 -132.935038) (xy 29.892165 -132.879453)
			(xy 29.963852 -132.830274) (xy 30.039772 -132.787922) (xy 30.119276 -132.752758) (xy 30.201687 -132.725082)
			(xy 30.2863 -132.70513) (xy 30.372394 -132.693073) (xy 30.459233 -132.689014) (xy 30.546076 -132.692987)
			(xy 30.632181 -132.704959) (xy 30.716815 -132.724826) (xy 30.799253 -132.75242) (xy 30.878792 -132.787506)
			(xy 30.954754 -132.829782) (xy 31.026489 -132.87889) (xy 31.093386 -132.934408) (xy 31.154873 -132.995864)
			(xy 31.210425 -133.062733) (xy 31.259569 -133.134444) (xy 31.301883 -133.210384) (xy 31.337009 -133.289906)
			(xy 31.364644 -133.37233) (xy 31.384555 -133.456953) (xy 31.396569 -133.543053) (xy 31.400586 -133.629894)
			(xy 31.398576 -133.673358) (xy 34.599874 -133.673358) (xy 34.599874 -133.586458) (xy 34.607892 -133.499929)
			(xy 34.62386 -133.414509) (xy 34.647641 -133.330927) (xy 34.679033 -133.249895) (xy 34.717767 -133.172106)
			(xy 34.763514 -133.098222) (xy 34.815883 -133.028875) (xy 34.874427 -132.964655) (xy 34.938647 -132.906111)
			(xy 35.007994 -132.853742) (xy 35.081878 -132.807995) (xy 35.159667 -132.769261) (xy 35.240699 -132.737869)
			(xy 35.324281 -132.714088) (xy 35.409701 -132.69812) (xy 35.49623 -132.690102) (xy 35.58313 -132.690102)
			(xy 35.669659 -132.69812) (xy 35.755079 -132.714088) (xy 35.838661 -132.737869) (xy 35.919693 -132.769261)
			(xy 35.997482 -132.807995) (xy 36.071366 -132.853742) (xy 36.140713 -132.906111) (xy 36.204933 -132.964655)
			(xy 36.263477 -133.028875) (xy 36.315846 -133.098222) (xy 36.361593 -133.172106) (xy 36.400327 -133.249895)
			(xy 36.431719 -133.330927) (xy 36.4555 -133.414509) (xy 36.471468 -133.499929) (xy 36.479486 -133.586458)
			(xy 36.479988 -133.629908) (xy 36.479486 -133.673358) (xy 36.471468 -133.759887) (xy 36.4555 -133.845307)
			(xy 36.431719 -133.928889) (xy 36.400327 -134.009921) (xy 36.361593 -134.08771) (xy 36.315846 -134.161594)
			(xy 36.263477 -134.230941) (xy 36.204933 -134.295161) (xy 36.140713 -134.353705) (xy 36.071366 -134.406074)
			(xy 35.997482 -134.451821) (xy 35.919693 -134.490555) (xy 35.838661 -134.521947) (xy 35.755079 -134.545728)
			(xy 35.669659 -134.561696) (xy 35.58313 -134.569714) (xy 35.49623 -134.569714) (xy 35.409701 -134.561696)
			(xy 35.324281 -134.545728) (xy 35.240699 -134.521947) (xy 35.159667 -134.490555) (xy 35.081878 -134.451821)
			(xy 35.007994 -134.406074) (xy 34.938647 -134.353705) (xy 34.874427 -134.295161) (xy 34.815883 -134.230941)
			(xy 34.763514 -134.161594) (xy 34.717767 -134.08771) (xy 34.679033 -134.009921) (xy 34.647641 -133.928889)
			(xy 34.62386 -133.845307) (xy 34.607892 -133.759887) (xy 34.599874 -133.673358) (xy 31.398576 -133.673358)
			(xy 31.39657 -133.716735) (xy 31.384557 -133.802835) (xy 31.364648 -133.887458) (xy 31.337013 -133.969883)
			(xy 31.301889 -134.049405) (xy 31.259575 -134.125346) (xy 31.210433 -134.197057) (xy 31.154881 -134.263927)
			(xy 31.093395 -134.325383) (xy 31.026499 -134.380903) (xy 30.954764 -134.430011) (xy 30.878803 -134.472289)
			(xy 30.799264 -134.507375) (xy 30.716826 -134.53497) (xy 30.632194 -134.554839) (xy 30.546088 -134.566812)
			(xy 30.459245 -134.570786) (xy 30.372406 -134.566728) (xy 30.286312 -134.554672) (xy 30.201699 -134.534721)
			(xy 30.119288 -134.507046) (xy 30.039783 -134.471883) (xy 29.963862 -134.429532) (xy 29.892175 -134.380355)
			(xy 29.825333 -134.32477) (xy 29.763906 -134.263254) (xy 29.73578 -134.23011) (xy 29.721738 -134.214635)
			(xy 29.689504 -134.18805) (xy 29.653349 -134.167107) (xy 29.61425 -134.152373) (xy 29.573265 -134.144245)
			(xy 29.531502 -134.142944) (xy 29.510736 -134.145274) (xy 29.495673 -134.147723) (xy 29.467249 -134.158805)
			(xy 29.442274 -134.176327) (xy 29.422182 -134.199285) (xy 29.408124 -134.226361) (xy 29.400907 -134.256003)
			(xy 29.4005 -134.271258) (xy 29.4005 -135.528558) (xy 29.400954 -135.543805) (xy 29.408199 -135.573425)
			(xy 29.422261 -135.600483) (xy 29.442339 -135.623434) (xy 29.467287 -135.640969) (xy 29.495682 -135.652087)
			(xy 29.510736 -135.654542) (xy 29.531497 -135.656872) (xy 29.57325 -135.655527) (xy 29.614221 -135.647375)
			(xy 29.653308 -135.632635) (xy 29.68946 -135.611704) (xy 29.721704 -135.585144) (xy 29.73578 -135.569706)
			(xy 29.763898 -135.536555) (xy 29.825324 -135.475038) (xy 29.892165 -135.419453) (xy 29.963852 -135.370274)
			(xy 30.039772 -135.327922) (xy 30.119276 -135.292758) (xy 30.201687 -135.265082) (xy 30.2863 -135.24513)
			(xy 30.372394 -135.233073) (xy 30.459233 -135.229014) (xy 30.546076 -135.232987) (xy 30.632181 -135.244959)
			(xy 30.716815 -135.264826) (xy 30.799253 -135.29242) (xy 30.878792 -135.327506) (xy 30.954754 -135.369782)
			(xy 31.026489 -135.41889) (xy 31.093386 -135.474408) (xy 31.154873 -135.535864) (xy 31.210425 -135.602733)
			(xy 31.259569 -135.674444) (xy 31.301883 -135.750384) (xy 31.337009 -135.829906) (xy 31.364644 -135.91233)
			(xy 31.384555 -135.996953) (xy 31.396569 -136.083053) (xy 31.400586 -136.169894) (xy 31.398576 -136.213358)
			(xy 34.599874 -136.213358) (xy 34.599874 -136.126458) (xy 34.607892 -136.039929) (xy 34.62386 -135.954509)
			(xy 34.647641 -135.870927) (xy 34.679033 -135.789895) (xy 34.717767 -135.712106) (xy 34.763514 -135.638222)
			(xy 34.815883 -135.568875) (xy 34.874427 -135.504655) (xy 34.938647 -135.446111) (xy 35.007994 -135.393742)
			(xy 35.081878 -135.347995) (xy 35.159667 -135.309261) (xy 35.240699 -135.277869) (xy 35.324281 -135.254088)
			(xy 35.409701 -135.23812) (xy 35.49623 -135.230102) (xy 35.58313 -135.230102) (xy 35.669659 -135.23812)
			(xy 35.755079 -135.254088) (xy 35.838661 -135.277869) (xy 35.919693 -135.309261) (xy 35.997482 -135.347995)
			(xy 36.071366 -135.393742) (xy 36.140713 -135.446111) (xy 36.204933 -135.504655) (xy 36.263477 -135.568875)
			(xy 36.315846 -135.638222) (xy 36.361593 -135.712106) (xy 36.400327 -135.789895) (xy 36.431719 -135.870927)
			(xy 36.4555 -135.954509) (xy 36.471468 -136.039929) (xy 36.479486 -136.126458) (xy 36.479988 -136.169908)
			(xy 36.479486 -136.213358) (xy 36.471468 -136.299887) (xy 36.4555 -136.385307) (xy 36.431719 -136.468889)
			(xy 36.400327 -136.549921) (xy 36.361593 -136.62771) (xy 36.315846 -136.701594) (xy 36.263477 -136.770941)
			(xy 36.204933 -136.835161) (xy 36.140713 -136.893705) (xy 36.071366 -136.946074) (xy 35.997482 -136.991821)
			(xy 35.919693 -137.030555) (xy 35.838661 -137.061947) (xy 35.755079 -137.085728) (xy 35.669659 -137.101696)
			(xy 35.58313 -137.109714) (xy 35.49623 -137.109714) (xy 35.409701 -137.101696) (xy 35.324281 -137.085728)
			(xy 35.240699 -137.061947) (xy 35.159667 -137.030555) (xy 35.081878 -136.991821) (xy 35.007994 -136.946074)
			(xy 34.938647 -136.893705) (xy 34.874427 -136.835161) (xy 34.815883 -136.770941) (xy 34.763514 -136.701594)
			(xy 34.717767 -136.62771) (xy 34.679033 -136.549921) (xy 34.647641 -136.468889) (xy 34.62386 -136.385307)
			(xy 34.607892 -136.299887) (xy 34.599874 -136.213358) (xy 31.398576 -136.213358) (xy 31.39657 -136.256735)
			(xy 31.384557 -136.342835) (xy 31.364648 -136.427458) (xy 31.337013 -136.509883) (xy 31.301889 -136.589405)
			(xy 31.259575 -136.665346) (xy 31.210433 -136.737057) (xy 31.154881 -136.803927) (xy 31.093395 -136.865383)
			(xy 31.026499 -136.920903) (xy 30.954764 -136.970011) (xy 30.878803 -137.012289) (xy 30.799264 -137.047375)
			(xy 30.716826 -137.07497) (xy 30.632194 -137.094839) (xy 30.546088 -137.106812) (xy 30.459245 -137.110786)
			(xy 30.372406 -137.106728) (xy 30.286312 -137.094672) (xy 30.201699 -137.074721) (xy 30.119288 -137.047046)
			(xy 30.039783 -137.011883) (xy 29.963862 -136.969532) (xy 29.892175 -136.920355) (xy 29.825333 -136.86477)
			(xy 29.763906 -136.803254) (xy 29.73578 -136.77011) (xy 29.721738 -136.754635) (xy 29.689504 -136.72805)
			(xy 29.653349 -136.707107) (xy 29.61425 -136.692373) (xy 29.573265 -136.684245) (xy 29.531502 -136.682944)
			(xy 29.510736 -136.685274) (xy 29.495673 -136.687723) (xy 29.467249 -136.698805) (xy 29.442274 -136.716327)
			(xy 29.422182 -136.739285) (xy 29.408124 -136.766361) (xy 29.400907 -136.796003) (xy 29.4005 -136.811258)
			(xy 29.4005 -138.068558) (xy 29.400954 -138.083805) (xy 29.408199 -138.113425) (xy 29.422261 -138.140483)
			(xy 29.442339 -138.163434) (xy 29.467287 -138.180969) (xy 29.495682 -138.192087) (xy 29.510736 -138.194542)
			(xy 29.531497 -138.196872) (xy 29.57325 -138.195527) (xy 29.614221 -138.187375) (xy 29.653308 -138.172635)
			(xy 29.68946 -138.151704) (xy 29.721704 -138.125144) (xy 29.73578 -138.109706) (xy 29.763898 -138.076555)
			(xy 29.825324 -138.015038) (xy 29.892165 -137.959453) (xy 29.963852 -137.910274) (xy 30.039772 -137.867922)
			(xy 30.119276 -137.832758) (xy 30.201687 -137.805082) (xy 30.2863 -137.78513) (xy 30.372394 -137.773073)
			(xy 30.459233 -137.769014) (xy 30.546076 -137.772987) (xy 30.632181 -137.784959) (xy 30.716815 -137.804826)
			(xy 30.799253 -137.83242) (xy 30.878792 -137.867506) (xy 30.954754 -137.909782) (xy 31.026489 -137.95889)
			(xy 31.093386 -138.014408) (xy 31.154873 -138.075864) (xy 31.210425 -138.142733) (xy 31.259569 -138.214444)
			(xy 31.301883 -138.290384) (xy 31.337009 -138.369906) (xy 31.364644 -138.45233) (xy 31.384555 -138.536953)
			(xy 31.396569 -138.623053) (xy 31.400586 -138.709894) (xy 31.398576 -138.753358) (xy 34.599874 -138.753358)
			(xy 34.599874 -138.666458) (xy 34.607892 -138.579929) (xy 34.62386 -138.494509) (xy 34.647641 -138.410927)
			(xy 34.679033 -138.329895) (xy 34.717767 -138.252106) (xy 34.763514 -138.178222) (xy 34.815883 -138.108875)
			(xy 34.874427 -138.044655) (xy 34.938647 -137.986111) (xy 35.007994 -137.933742) (xy 35.081878 -137.887995)
			(xy 35.159667 -137.849261) (xy 35.240699 -137.817869) (xy 35.324281 -137.794088) (xy 35.409701 -137.77812)
			(xy 35.49623 -137.770102) (xy 35.58313 -137.770102) (xy 35.669659 -137.77812) (xy 35.755079 -137.794088)
			(xy 35.838661 -137.817869) (xy 35.919693 -137.849261) (xy 35.997482 -137.887995) (xy 36.071366 -137.933742)
			(xy 36.140713 -137.986111) (xy 36.204933 -138.044655) (xy 36.263477 -138.108875) (xy 36.315846 -138.178222)
			(xy 36.361593 -138.252106) (xy 36.400327 -138.329895) (xy 36.431719 -138.410927) (xy 36.4555 -138.494509)
			(xy 36.471468 -138.579929) (xy 36.479486 -138.666458) (xy 36.479988 -138.709908) (xy 36.479486 -138.753358)
			(xy 36.471468 -138.839887) (xy 36.4555 -138.925307) (xy 36.431719 -139.008889) (xy 36.400327 -139.089921)
			(xy 36.361593 -139.16771) (xy 36.315846 -139.241594) (xy 36.263477 -139.310941) (xy 36.204933 -139.375161)
			(xy 36.140713 -139.433705) (xy 36.071366 -139.486074) (xy 35.997482 -139.531821) (xy 35.919693 -139.570555)
			(xy 35.838661 -139.601947) (xy 35.755079 -139.625728) (xy 35.669659 -139.641696) (xy 35.58313 -139.649714)
			(xy 35.49623 -139.649714) (xy 35.409701 -139.641696) (xy 35.324281 -139.625728) (xy 35.240699 -139.601947)
			(xy 35.159667 -139.570555) (xy 35.081878 -139.531821) (xy 35.007994 -139.486074) (xy 34.938647 -139.433705)
			(xy 34.874427 -139.375161) (xy 34.815883 -139.310941) (xy 34.763514 -139.241594) (xy 34.717767 -139.16771)
			(xy 34.679033 -139.089921) (xy 34.647641 -139.008889) (xy 34.62386 -138.925307) (xy 34.607892 -138.839887)
			(xy 34.599874 -138.753358) (xy 31.398576 -138.753358) (xy 31.39657 -138.796735) (xy 31.384557 -138.882835)
			(xy 31.364648 -138.967458) (xy 31.337013 -139.049883) (xy 31.301889 -139.129405) (xy 31.259575 -139.205346)
			(xy 31.210433 -139.277057) (xy 31.154881 -139.343927) (xy 31.093395 -139.405383) (xy 31.026499 -139.460903)
			(xy 30.954764 -139.510011) (xy 30.878803 -139.552289) (xy 30.799264 -139.587375) (xy 30.716826 -139.61497)
			(xy 30.632194 -139.634839) (xy 30.546088 -139.646812) (xy 30.459245 -139.650786) (xy 30.372406 -139.646728)
			(xy 30.286312 -139.634672) (xy 30.201699 -139.614721) (xy 30.119288 -139.587046) (xy 30.039783 -139.551883)
			(xy 29.963862 -139.509532) (xy 29.892175 -139.460355) (xy 29.825333 -139.40477) (xy 29.763906 -139.343254)
			(xy 29.73578 -139.31011) (xy 29.721738 -139.294635) (xy 29.689504 -139.26805) (xy 29.653349 -139.247107)
			(xy 29.61425 -139.232373) (xy 29.573265 -139.224245) (xy 29.531502 -139.222944) (xy 29.510736 -139.225274)
			(xy 29.495673 -139.227723) (xy 29.467249 -139.238805) (xy 29.442274 -139.256327) (xy 29.422182 -139.279285)
			(xy 29.408124 -139.306361) (xy 29.400907 -139.336003) (xy 29.4005 -139.351258) (xy 29.4005 -140.254228)
			(xy 39.818818 -140.254228) (xy 39.819523 -140.195605) (xy 39.828091 -140.078667) (xy 39.844787 -139.962611)
			(xy 39.86953 -139.848001) (xy 39.902199 -139.735393) (xy 39.942635 -139.625335) (xy 39.990642 -139.518363)
			(xy 40.045986 -139.414996) (xy 40.108399 -139.315737) (xy 40.177577 -139.221068) (xy 40.253183 -139.13145)
			(xy 40.334851 -139.047318) (xy 40.422182 -138.969081) (xy 40.514753 -138.89712) (xy 40.612113 -138.831784)
			(xy 40.713789 -138.773392) (xy 40.819288 -138.722226) (xy 40.928095 -138.678537) (xy 41.039682 -138.642535)
			(xy 41.153506 -138.614397) (xy 41.269014 -138.594259) (xy 41.385645 -138.582218) (xy 41.502832 -138.578334)
			(xy 41.620004 -138.582625) (xy 41.736593 -138.595071) (xy 41.85203 -138.615611) (xy 41.965756 -138.644144)
			(xy 42.077217 -138.680533) (xy 42.185872 -138.724601) (xy 42.291192 -138.776133) (xy 42.392665 -138.834878)
			(xy 42.489797 -138.900552) (xy 42.501941 -138.91006) (xy 43.327831 -138.91006) (xy 43.331866 -138.834356)
			(xy 43.343925 -138.759511) (xy 43.363871 -138.68637) (xy 43.391478 -138.615765) (xy 43.426434 -138.548494)
			(xy 43.468342 -138.485319) (xy 43.516728 -138.426957) (xy 43.571044 -138.374069) (xy 43.630673 -138.327254)
			(xy 43.694941 -138.287042) (xy 43.763118 -138.25389) (xy 43.834434 -138.228172) (xy 43.908079 -138.21018)
			(xy 43.983219 -138.200118) (xy 44.059003 -138.198099) (xy 44.134573 -138.204148) (xy 44.209071 -138.218195)
			(xy 44.281654 -138.240081) (xy 44.3515 -138.269558) (xy 44.417817 -138.306293) (xy 44.479853 -138.349868)
			(xy 44.536906 -138.39979) (xy 44.58833 -138.455494) (xy 44.633541 -138.516349) (xy 44.672028 -138.581664)
			(xy 44.703354 -138.6507) (xy 44.727164 -138.722675) (xy 44.743189 -138.796773) (xy 44.751248 -138.872154)
			(xy 44.751752 -138.91006) (xy 45.867831 -138.91006) (xy 45.871866 -138.834356) (xy 45.883925 -138.759511)
			(xy 45.903871 -138.68637) (xy 45.931478 -138.615765) (xy 45.966434 -138.548494) (xy 46.008342 -138.485319)
			(xy 46.056728 -138.426957) (xy 46.111044 -138.374069) (xy 46.170673 -138.327254) (xy 46.234941 -138.287042)
			(xy 46.303118 -138.25389) (xy 46.374434 -138.228172) (xy 46.448079 -138.21018) (xy 46.523219 -138.200118)
			(xy 46.599003 -138.198099) (xy 46.674573 -138.204148) (xy 46.749071 -138.218195) (xy 46.821654 -138.240081)
			(xy 46.8915 -138.269558) (xy 46.957817 -138.306293) (xy 47.019853 -138.349868) (xy 47.076906 -138.39979)
			(xy 47.12833 -138.455494) (xy 47.173541 -138.516349) (xy 47.212028 -138.581664) (xy 47.243354 -138.6507)
			(xy 47.267164 -138.722675) (xy 47.283189 -138.796773) (xy 47.291248 -138.872154) (xy 47.291752 -138.91006)
			(xy 48.407831 -138.91006) (xy 48.411866 -138.834356) (xy 48.423925 -138.759511) (xy 48.443871 -138.68637)
			(xy 48.471478 -138.615765) (xy 48.506434 -138.548494) (xy 48.548342 -138.485319) (xy 48.596728 -138.426957)
			(xy 48.651044 -138.374069) (xy 48.710673 -138.327254) (xy 48.774941 -138.287042) (xy 48.843118 -138.25389)
			(xy 48.914434 -138.228172) (xy 48.988079 -138.21018) (xy 49.063219 -138.200118) (xy 49.139003 -138.198099)
			(xy 49.214573 -138.204148) (xy 49.289071 -138.218195) (xy 49.361654 -138.240081) (xy 49.4315 -138.269558)
			(xy 49.497817 -138.306293) (xy 49.559853 -138.349868) (xy 49.616906 -138.39979) (xy 49.66833 -138.455494)
			(xy 49.713541 -138.516349) (xy 49.752028 -138.581664) (xy 49.783354 -138.6507) (xy 49.807164 -138.722675)
			(xy 49.823189 -138.796773) (xy 49.831248 -138.872154) (xy 49.831752 -138.91006) (xy 50.947831 -138.91006)
			(xy 50.951866 -138.834356) (xy 50.963925 -138.759511) (xy 50.983871 -138.68637) (xy 51.011478 -138.615765)
			(xy 51.046434 -138.548494) (xy 51.088342 -138.485319) (xy 51.136728 -138.426957) (xy 51.191044 -138.374069)
			(xy 51.250673 -138.327254) (xy 51.314941 -138.287042) (xy 51.383118 -138.25389) (xy 51.454434 -138.228172)
			(xy 51.528079 -138.21018) (xy 51.603219 -138.200118) (xy 51.679003 -138.198099) (xy 51.754573 -138.204148)
			(xy 51.829071 -138.218195) (xy 51.901654 -138.240081) (xy 51.9715 -138.269558) (xy 52.037817 -138.306293)
			(xy 52.099853 -138.349868) (xy 52.156906 -138.39979) (xy 52.20833 -138.455494) (xy 52.253541 -138.516349)
			(xy 52.292028 -138.581664) (xy 52.323354 -138.6507) (xy 52.347164 -138.722675) (xy 52.363189 -138.796773)
			(xy 52.371248 -138.872154) (xy 52.371752 -138.91006) (xy 53.487831 -138.91006) (xy 53.491866 -138.834356)
			(xy 53.503925 -138.759511) (xy 53.523871 -138.68637) (xy 53.551478 -138.615765) (xy 53.586434 -138.548494)
			(xy 53.628342 -138.485319) (xy 53.676728 -138.426957) (xy 53.731044 -138.374069) (xy 53.790673 -138.327254)
			(xy 53.854941 -138.287042) (xy 53.923118 -138.25389) (xy 53.994434 -138.228172) (xy 54.068079 -138.21018)
			(xy 54.143219 -138.200118) (xy 54.219003 -138.198099) (xy 54.294573 -138.204148) (xy 54.369071 -138.218195)
			(xy 54.441654 -138.240081) (xy 54.5115 -138.269558) (xy 54.577817 -138.306293) (xy 54.639853 -138.349868)
			(xy 54.696906 -138.39979) (xy 54.74833 -138.455494) (xy 54.793541 -138.516349) (xy 54.832028 -138.581664)
			(xy 54.863354 -138.6507) (xy 54.887164 -138.722675) (xy 54.903189 -138.796773) (xy 54.911248 -138.872154)
			(xy 54.911752 -138.91006) (xy 56.027831 -138.91006) (xy 56.031866 -138.834356) (xy 56.043925 -138.759511)
			(xy 56.063871 -138.68637) (xy 56.091478 -138.615765) (xy 56.126434 -138.548494) (xy 56.168342 -138.485319)
			(xy 56.216728 -138.426957) (xy 56.271044 -138.374069) (xy 56.330673 -138.327254) (xy 56.394941 -138.287042)
			(xy 56.463118 -138.25389) (xy 56.534434 -138.228172) (xy 56.608079 -138.21018) (xy 56.683219 -138.200118)
			(xy 56.759003 -138.198099) (xy 56.834573 -138.204148) (xy 56.909071 -138.218195) (xy 56.981654 -138.240081)
			(xy 57.0515 -138.269558) (xy 57.117817 -138.306293) (xy 57.179853 -138.349868) (xy 57.236906 -138.39979)
			(xy 57.28833 -138.455494) (xy 57.333541 -138.516349) (xy 57.372028 -138.581664) (xy 57.403354 -138.6507)
			(xy 57.427164 -138.722675) (xy 57.443189 -138.796773) (xy 57.451248 -138.872154) (xy 57.451752 -138.91006)
			(xy 58.567831 -138.91006) (xy 58.571866 -138.834356) (xy 58.583925 -138.759511) (xy 58.603871 -138.68637)
			(xy 58.631478 -138.615765) (xy 58.666434 -138.548494) (xy 58.708342 -138.485319) (xy 58.756728 -138.426957)
			(xy 58.811044 -138.374069) (xy 58.870673 -138.327254) (xy 58.934941 -138.287042) (xy 59.003118 -138.25389)
			(xy 59.074434 -138.228172) (xy 59.148079 -138.21018) (xy 59.223219 -138.200118) (xy 59.299003 -138.198099)
			(xy 59.374573 -138.204148) (xy 59.449071 -138.218195) (xy 59.521654 -138.240081) (xy 59.5915 -138.269558)
			(xy 59.657817 -138.306293) (xy 59.719853 -138.349868) (xy 59.776906 -138.39979) (xy 59.82833 -138.455494)
			(xy 59.873541 -138.516349) (xy 59.912028 -138.581664) (xy 59.943354 -138.6507) (xy 59.967164 -138.722675)
			(xy 59.983189 -138.796773) (xy 59.991248 -138.872154) (xy 59.991752 -138.91006) (xy 61.107831 -138.91006)
			(xy 61.111866 -138.834356) (xy 61.123925 -138.759511) (xy 61.143871 -138.68637) (xy 61.171478 -138.615765)
			(xy 61.206434 -138.548494) (xy 61.248342 -138.485319) (xy 61.296728 -138.426957) (xy 61.351044 -138.374069)
			(xy 61.410673 -138.327254) (xy 61.474941 -138.287042) (xy 61.543118 -138.25389) (xy 61.614434 -138.228172)
			(xy 61.688079 -138.21018) (xy 61.763219 -138.200118) (xy 61.839003 -138.198099) (xy 61.914573 -138.204148)
			(xy 61.989071 -138.218195) (xy 62.061654 -138.240081) (xy 62.1315 -138.269558) (xy 62.197817 -138.306293)
			(xy 62.259853 -138.349868) (xy 62.316906 -138.39979) (xy 62.36833 -138.455494) (xy 62.413541 -138.516349)
			(xy 62.452028 -138.581664) (xy 62.483354 -138.6507) (xy 62.507164 -138.722675) (xy 62.523189 -138.796773)
			(xy 62.531248 -138.872154) (xy 62.531752 -138.91006) (xy 62.531248 -138.947966) (xy 62.523189 -139.023347)
			(xy 62.507164 -139.097445) (xy 62.483354 -139.16942) (xy 62.452028 -139.238456) (xy 62.413541 -139.303771)
			(xy 62.36833 -139.364626) (xy 62.316906 -139.42033) (xy 62.259853 -139.470252) (xy 62.197817 -139.513827)
			(xy 62.1315 -139.550562) (xy 62.061654 -139.580039) (xy 61.989071 -139.601925) (xy 61.914573 -139.615972)
			(xy 61.839003 -139.622021) (xy 61.763219 -139.620002) (xy 61.688079 -139.60994) (xy 61.614434 -139.591948)
			(xy 61.543118 -139.56623) (xy 61.474941 -139.533078) (xy 61.410673 -139.492866) (xy 61.351044 -139.446051)
			(xy 61.296728 -139.393163) (xy 61.248342 -139.334801) (xy 61.206434 -139.271626) (xy 61.171478 -139.204355)
			(xy 61.143871 -139.13375) (xy 61.123925 -139.060609) (xy 61.111866 -138.985764) (xy 61.107831 -138.91006)
			(xy 59.991752 -138.91006) (xy 59.991248 -138.947966) (xy 59.983189 -139.023347) (xy 59.967164 -139.097445)
			(xy 59.943354 -139.16942) (xy 59.912028 -139.238456) (xy 59.873541 -139.303771) (xy 59.82833 -139.364626)
			(xy 59.776906 -139.42033) (xy 59.719853 -139.470252) (xy 59.657817 -139.513827) (xy 59.5915 -139.550562)
			(xy 59.521654 -139.580039) (xy 59.449071 -139.601925) (xy 59.374573 -139.615972) (xy 59.299003 -139.622021)
			(xy 59.223219 -139.620002) (xy 59.148079 -139.60994) (xy 59.074434 -139.591948) (xy 59.003118 -139.56623)
			(xy 58.934941 -139.533078) (xy 58.870673 -139.492866) (xy 58.811044 -139.446051) (xy 58.756728 -139.393163)
			(xy 58.708342 -139.334801) (xy 58.666434 -139.271626) (xy 58.631478 -139.204355) (xy 58.603871 -139.13375)
			(xy 58.583925 -139.060609) (xy 58.571866 -138.985764) (xy 58.567831 -138.91006) (xy 57.451752 -138.91006)
			(xy 57.451248 -138.947966) (xy 57.443189 -139.023347) (xy 57.427164 -139.097445) (xy 57.403354 -139.16942)
			(xy 57.372028 -139.238456) (xy 57.333541 -139.303771) (xy 57.28833 -139.364626) (xy 57.236906 -139.42033)
			(xy 57.179853 -139.470252) (xy 57.117817 -139.513827) (xy 57.0515 -139.550562) (xy 56.981654 -139.580039)
			(xy 56.909071 -139.601925) (xy 56.834573 -139.615972) (xy 56.759003 -139.622021) (xy 56.683219 -139.620002)
			(xy 56.608079 -139.60994) (xy 56.534434 -139.591948) (xy 56.463118 -139.56623) (xy 56.394941 -139.533078)
			(xy 56.330673 -139.492866) (xy 56.271044 -139.446051) (xy 56.216728 -139.393163) (xy 56.168342 -139.334801)
			(xy 56.126434 -139.271626) (xy 56.091478 -139.204355) (xy 56.063871 -139.13375) (xy 56.043925 -139.060609)
			(xy 56.031866 -138.985764) (xy 56.027831 -138.91006) (xy 54.911752 -138.91006) (xy 54.911248 -138.947966)
			(xy 54.903189 -139.023347) (xy 54.887164 -139.097445) (xy 54.863354 -139.16942) (xy 54.832028 -139.238456)
			(xy 54.793541 -139.303771) (xy 54.74833 -139.364626) (xy 54.696906 -139.42033) (xy 54.639853 -139.470252)
			(xy 54.577817 -139.513827) (xy 54.5115 -139.550562) (xy 54.441654 -139.580039) (xy 54.369071 -139.601925)
			(xy 54.294573 -139.615972) (xy 54.219003 -139.622021) (xy 54.143219 -139.620002) (xy 54.068079 -139.60994)
			(xy 53.994434 -139.591948) (xy 53.923118 -139.56623) (xy 53.854941 -139.533078) (xy 53.790673 -139.492866)
			(xy 53.731044 -139.446051) (xy 53.676728 -139.393163) (xy 53.628342 -139.334801) (xy 53.586434 -139.271626)
			(xy 53.551478 -139.204355) (xy 53.523871 -139.13375) (xy 53.503925 -139.060609) (xy 53.491866 -138.985764)
			(xy 53.487831 -138.91006) (xy 52.371752 -138.91006) (xy 52.371248 -138.947966) (xy 52.363189 -139.023347)
			(xy 52.347164 -139.097445) (xy 52.323354 -139.16942) (xy 52.292028 -139.238456) (xy 52.253541 -139.303771)
			(xy 52.20833 -139.364626) (xy 52.156906 -139.42033) (xy 52.099853 -139.470252) (xy 52.037817 -139.513827)
			(xy 51.9715 -139.550562) (xy 51.901654 -139.580039) (xy 51.829071 -139.601925) (xy 51.754573 -139.615972)
			(xy 51.679003 -139.622021) (xy 51.603219 -139.620002) (xy 51.528079 -139.60994) (xy 51.454434 -139.591948)
			(xy 51.383118 -139.56623) (xy 51.314941 -139.533078) (xy 51.250673 -139.492866) (xy 51.191044 -139.446051)
			(xy 51.136728 -139.393163) (xy 51.088342 -139.334801) (xy 51.046434 -139.271626) (xy 51.011478 -139.204355)
			(xy 50.983871 -139.13375) (xy 50.963925 -139.060609) (xy 50.951866 -138.985764) (xy 50.947831 -138.91006)
			(xy 49.831752 -138.91006) (xy 49.831248 -138.947966) (xy 49.823189 -139.023347) (xy 49.807164 -139.097445)
			(xy 49.783354 -139.16942) (xy 49.752028 -139.238456) (xy 49.713541 -139.303771) (xy 49.66833 -139.364626)
			(xy 49.616906 -139.42033) (xy 49.559853 -139.470252) (xy 49.497817 -139.513827) (xy 49.4315 -139.550562)
			(xy 49.361654 -139.580039) (xy 49.289071 -139.601925) (xy 49.214573 -139.615972) (xy 49.139003 -139.622021)
			(xy 49.063219 -139.620002) (xy 48.988079 -139.60994) (xy 48.914434 -139.591948) (xy 48.843118 -139.56623)
			(xy 48.774941 -139.533078) (xy 48.710673 -139.492866) (xy 48.651044 -139.446051) (xy 48.596728 -139.393163)
			(xy 48.548342 -139.334801) (xy 48.506434 -139.271626) (xy 48.471478 -139.204355) (xy 48.443871 -139.13375)
			(xy 48.423925 -139.060609) (xy 48.411866 -138.985764) (xy 48.407831 -138.91006) (xy 47.291752 -138.91006)
			(xy 47.291248 -138.947966) (xy 47.283189 -139.023347) (xy 47.267164 -139.097445) (xy 47.243354 -139.16942)
			(xy 47.212028 -139.238456) (xy 47.173541 -139.303771) (xy 47.12833 -139.364626) (xy 47.076906 -139.42033)
			(xy 47.019853 -139.470252) (xy 46.957817 -139.513827) (xy 46.8915 -139.550562) (xy 46.821654 -139.580039)
			(xy 46.749071 -139.601925) (xy 46.674573 -139.615972) (xy 46.599003 -139.622021) (xy 46.523219 -139.620002)
			(xy 46.448079 -139.60994) (xy 46.374434 -139.591948) (xy 46.303118 -139.56623) (xy 46.234941 -139.533078)
			(xy 46.170673 -139.492866) (xy 46.111044 -139.446051) (xy 46.056728 -139.393163) (xy 46.008342 -139.334801)
			(xy 45.966434 -139.271626) (xy 45.931478 -139.204355) (xy 45.903871 -139.13375) (xy 45.883925 -139.060609)
			(xy 45.871866 -138.985764) (xy 45.867831 -138.91006) (xy 44.751752 -138.91006) (xy 44.751248 -138.947966)
			(xy 44.743189 -139.023347) (xy 44.727164 -139.097445) (xy 44.703354 -139.16942) (xy 44.672028 -139.238456)
			(xy 44.633541 -139.303771) (xy 44.58833 -139.364626) (xy 44.536906 -139.42033) (xy 44.479853 -139.470252)
			(xy 44.417817 -139.513827) (xy 44.3515 -139.550562) (xy 44.281654 -139.580039) (xy 44.209071 -139.601925)
			(xy 44.134573 -139.615972) (xy 44.059003 -139.622021) (xy 43.983219 -139.620002) (xy 43.908079 -139.60994)
			(xy 43.834434 -139.591948) (xy 43.763118 -139.56623) (xy 43.694941 -139.533078) (xy 43.630673 -139.492866)
			(xy 43.571044 -139.446051) (xy 43.516728 -139.393163) (xy 43.468342 -139.334801) (xy 43.426434 -139.271626)
			(xy 43.391478 -139.204355) (xy 43.363871 -139.13375) (xy 43.343925 -139.060609) (xy 43.331866 -138.985764)
			(xy 43.327831 -138.91006) (xy 42.501941 -138.91006) (xy 42.582117 -138.972834) (xy 42.669176 -139.051374)
			(xy 42.750551 -139.135789) (xy 42.825845 -139.225669) (xy 42.894694 -139.320578) (xy 42.956761 -139.420054)
			(xy 43.011746 -139.523612) (xy 43.059381 -139.630751) (xy 43.099434 -139.740948) (xy 43.131712 -139.853669)
			(xy 43.156056 -139.968365) (xy 43.172348 -140.084478) (xy 43.18051 -140.201445) (xy 43.181016 -140.26007)
			(xy 43.180861 -140.290833) (xy 43.178574 -140.352316) (xy 43.176444 -140.383006) (xy 43.175682 -140.392404)
			(xy 43.170622 -140.450806) (xy 43.153396 -140.566771) (xy 43.12813 -140.681253) (xy 43.094949 -140.793697)
			(xy 43.054014 -140.903555) (xy 43.005523 -141.010294) (xy 42.949712 -141.113395) (xy 42.886853 -141.212356)
			(xy 42.817252 -141.306696) (xy 42.741246 -141.395958) (xy 42.659204 -141.479706) (xy 42.571527 -141.557535)
			(xy 42.503292 -141.61008) (xy 43.327831 -141.61008) (xy 43.331866 -141.534376) (xy 43.343925 -141.459531)
			(xy 43.363871 -141.38639) (xy 43.391478 -141.315785) (xy 43.426434 -141.248514) (xy 43.468342 -141.185339)
			(xy 43.516728 -141.126977) (xy 43.571044 -141.074089) (xy 43.630673 -141.027274) (xy 43.694941 -140.987062)
			(xy 43.763118 -140.95391) (xy 43.834434 -140.928192) (xy 43.908079 -140.9102) (xy 43.983219 -140.900138)
			(xy 44.059003 -140.898119) (xy 44.134573 -140.904168) (xy 44.209071 -140.918215) (xy 44.281654 -140.940101)
			(xy 44.3515 -140.969578) (xy 44.417817 -141.006313) (xy 44.479853 -141.049888) (xy 44.536906 -141.09981)
			(xy 44.58833 -141.155514) (xy 44.633541 -141.216369) (xy 44.672028 -141.281684) (xy 44.703354 -141.35072)
			(xy 44.727164 -141.422695) (xy 44.743189 -141.496793) (xy 44.751248 -141.572174) (xy 44.751752 -141.61008)
			(xy 45.867831 -141.61008) (xy 45.871866 -141.534376) (xy 45.883925 -141.459531) (xy 45.903871 -141.38639)
			(xy 45.931478 -141.315785) (xy 45.966434 -141.248514) (xy 46.008342 -141.185339) (xy 46.056728 -141.126977)
			(xy 46.111044 -141.074089) (xy 46.170673 -141.027274) (xy 46.234941 -140.987062) (xy 46.303118 -140.95391)
			(xy 46.374434 -140.928192) (xy 46.448079 -140.9102) (xy 46.523219 -140.900138) (xy 46.599003 -140.898119)
			(xy 46.674573 -140.904168) (xy 46.749071 -140.918215) (xy 46.821654 -140.940101) (xy 46.8915 -140.969578)
			(xy 46.957817 -141.006313) (xy 47.019853 -141.049888) (xy 47.076906 -141.09981) (xy 47.12833 -141.155514)
			(xy 47.173541 -141.216369) (xy 47.212028 -141.281684) (xy 47.243354 -141.35072) (xy 47.267164 -141.422695)
			(xy 47.283189 -141.496793) (xy 47.291248 -141.572174) (xy 47.291752 -141.61008) (xy 48.407831 -141.61008)
			(xy 48.411866 -141.534376) (xy 48.423925 -141.459531) (xy 48.443871 -141.38639) (xy 48.471478 -141.315785)
			(xy 48.506434 -141.248514) (xy 48.548342 -141.185339) (xy 48.596728 -141.126977) (xy 48.651044 -141.074089)
			(xy 48.710673 -141.027274) (xy 48.774941 -140.987062) (xy 48.843118 -140.95391) (xy 48.914434 -140.928192)
			(xy 48.988079 -140.9102) (xy 49.063219 -140.900138) (xy 49.139003 -140.898119) (xy 49.214573 -140.904168)
			(xy 49.289071 -140.918215) (xy 49.361654 -140.940101) (xy 49.4315 -140.969578) (xy 49.497817 -141.006313)
			(xy 49.559853 -141.049888) (xy 49.616906 -141.09981) (xy 49.66833 -141.155514) (xy 49.713541 -141.216369)
			(xy 49.752028 -141.281684) (xy 49.783354 -141.35072) (xy 49.807164 -141.422695) (xy 49.823189 -141.496793)
			(xy 49.831248 -141.572174) (xy 49.831752 -141.61008) (xy 50.947831 -141.61008) (xy 50.951866 -141.534376)
			(xy 50.963925 -141.459531) (xy 50.983871 -141.38639) (xy 51.011478 -141.315785) (xy 51.046434 -141.248514)
			(xy 51.088342 -141.185339) (xy 51.136728 -141.126977) (xy 51.191044 -141.074089) (xy 51.250673 -141.027274)
			(xy 51.314941 -140.987062) (xy 51.383118 -140.95391) (xy 51.454434 -140.928192) (xy 51.528079 -140.9102)
			(xy 51.603219 -140.900138) (xy 51.679003 -140.898119) (xy 51.754573 -140.904168) (xy 51.829071 -140.918215)
			(xy 51.901654 -140.940101) (xy 51.9715 -140.969578) (xy 52.037817 -141.006313) (xy 52.099853 -141.049888)
			(xy 52.156906 -141.09981) (xy 52.20833 -141.155514) (xy 52.253541 -141.216369) (xy 52.292028 -141.281684)
			(xy 52.323354 -141.35072) (xy 52.347164 -141.422695) (xy 52.363189 -141.496793) (xy 52.371248 -141.572174)
			(xy 52.371752 -141.61008) (xy 53.487831 -141.61008) (xy 53.491866 -141.534376) (xy 53.503925 -141.459531)
			(xy 53.523871 -141.38639) (xy 53.551478 -141.315785) (xy 53.586434 -141.248514) (xy 53.628342 -141.185339)
			(xy 53.676728 -141.126977) (xy 53.731044 -141.074089) (xy 53.790673 -141.027274) (xy 53.854941 -140.987062)
			(xy 53.923118 -140.95391) (xy 53.994434 -140.928192) (xy 54.068079 -140.9102) (xy 54.143219 -140.900138)
			(xy 54.219003 -140.898119) (xy 54.294573 -140.904168) (xy 54.369071 -140.918215) (xy 54.441654 -140.940101)
			(xy 54.5115 -140.969578) (xy 54.577817 -141.006313) (xy 54.639853 -141.049888) (xy 54.696906 -141.09981)
			(xy 54.74833 -141.155514) (xy 54.793541 -141.216369) (xy 54.832028 -141.281684) (xy 54.863354 -141.35072)
			(xy 54.887164 -141.422695) (xy 54.903189 -141.496793) (xy 54.911248 -141.572174) (xy 54.911752 -141.61008)
			(xy 56.027831 -141.61008) (xy 56.031866 -141.534376) (xy 56.043925 -141.459531) (xy 56.063871 -141.38639)
			(xy 56.091478 -141.315785) (xy 56.126434 -141.248514) (xy 56.168342 -141.185339) (xy 56.216728 -141.126977)
			(xy 56.271044 -141.074089) (xy 56.330673 -141.027274) (xy 56.394941 -140.987062) (xy 56.463118 -140.95391)
			(xy 56.534434 -140.928192) (xy 56.608079 -140.9102) (xy 56.683219 -140.900138) (xy 56.759003 -140.898119)
			(xy 56.834573 -140.904168) (xy 56.909071 -140.918215) (xy 56.981654 -140.940101) (xy 57.0515 -140.969578)
			(xy 57.117817 -141.006313) (xy 57.179853 -141.049888) (xy 57.236906 -141.09981) (xy 57.28833 -141.155514)
			(xy 57.333541 -141.216369) (xy 57.372028 -141.281684) (xy 57.403354 -141.35072) (xy 57.427164 -141.422695)
			(xy 57.443189 -141.496793) (xy 57.451248 -141.572174) (xy 57.451752 -141.61008) (xy 58.567831 -141.61008)
			(xy 58.571866 -141.534376) (xy 58.583925 -141.459531) (xy 58.603871 -141.38639) (xy 58.631478 -141.315785)
			(xy 58.666434 -141.248514) (xy 58.708342 -141.185339) (xy 58.756728 -141.126977) (xy 58.811044 -141.074089)
			(xy 58.870673 -141.027274) (xy 58.934941 -140.987062) (xy 59.003118 -140.95391) (xy 59.074434 -140.928192)
			(xy 59.148079 -140.9102) (xy 59.223219 -140.900138) (xy 59.299003 -140.898119) (xy 59.374573 -140.904168)
			(xy 59.449071 -140.918215) (xy 59.521654 -140.940101) (xy 59.5915 -140.969578) (xy 59.657817 -141.006313)
			(xy 59.719853 -141.049888) (xy 59.776906 -141.09981) (xy 59.82833 -141.155514) (xy 59.873541 -141.216369)
			(xy 59.912028 -141.281684) (xy 59.943354 -141.35072) (xy 59.967164 -141.422695) (xy 59.983189 -141.496793)
			(xy 59.991248 -141.572174) (xy 59.991752 -141.61008) (xy 61.107831 -141.61008) (xy 61.111866 -141.534376)
			(xy 61.123925 -141.459531) (xy 61.143871 -141.38639) (xy 61.171478 -141.315785) (xy 61.206434 -141.248514)
			(xy 61.248342 -141.185339) (xy 61.296728 -141.126977) (xy 61.351044 -141.074089) (xy 61.410673 -141.027274)
			(xy 61.474941 -140.987062) (xy 61.543118 -140.95391) (xy 61.614434 -140.928192) (xy 61.688079 -140.9102)
			(xy 61.763219 -140.900138) (xy 61.839003 -140.898119) (xy 61.914573 -140.904168) (xy 61.989071 -140.918215)
			(xy 62.061654 -140.940101) (xy 62.1315 -140.969578) (xy 62.197817 -141.006313) (xy 62.259853 -141.049888)
			(xy 62.316906 -141.09981) (xy 62.36833 -141.155514) (xy 62.413541 -141.216369) (xy 62.452028 -141.281684)
			(xy 62.483354 -141.35072) (xy 62.507164 -141.422695) (xy 62.523189 -141.496793) (xy 62.531248 -141.572174)
			(xy 62.531752 -141.61008) (xy 62.531248 -141.647986) (xy 62.523189 -141.723367) (xy 62.507164 -141.797465)
			(xy 62.483354 -141.86944) (xy 62.452028 -141.938476) (xy 62.413541 -142.003791) (xy 62.36833 -142.064646)
			(xy 62.316906 -142.12035) (xy 62.259853 -142.170272) (xy 62.197817 -142.213847) (xy 62.1315 -142.250582)
			(xy 62.061654 -142.280059) (xy 61.989071 -142.301945) (xy 61.914573 -142.315992) (xy 61.839003 -142.322041)
			(xy 61.763219 -142.320022) (xy 61.688079 -142.30996) (xy 61.614434 -142.291968) (xy 61.543118 -142.26625)
			(xy 61.474941 -142.233098) (xy 61.410673 -142.192886) (xy 61.351044 -142.146071) (xy 61.296728 -142.093183)
			(xy 61.248342 -142.034821) (xy 61.206434 -141.971646) (xy 61.171478 -141.904375) (xy 61.143871 -141.83377)
			(xy 61.123925 -141.760629) (xy 61.111866 -141.685784) (xy 61.107831 -141.61008) (xy 59.991752 -141.61008)
			(xy 59.991248 -141.647986) (xy 59.983189 -141.723367) (xy 59.967164 -141.797465) (xy 59.943354 -141.86944)
			(xy 59.912028 -141.938476) (xy 59.873541 -142.003791) (xy 59.82833 -142.064646) (xy 59.776906 -142.12035)
			(xy 59.719853 -142.170272) (xy 59.657817 -142.213847) (xy 59.5915 -142.250582) (xy 59.521654 -142.280059)
			(xy 59.449071 -142.301945) (xy 59.374573 -142.315992) (xy 59.299003 -142.322041) (xy 59.223219 -142.320022)
			(xy 59.148079 -142.30996) (xy 59.074434 -142.291968) (xy 59.003118 -142.26625) (xy 58.934941 -142.233098)
			(xy 58.870673 -142.192886) (xy 58.811044 -142.146071) (xy 58.756728 -142.093183) (xy 58.708342 -142.034821)
			(xy 58.666434 -141.971646) (xy 58.631478 -141.904375) (xy 58.603871 -141.83377) (xy 58.583925 -141.760629)
			(xy 58.571866 -141.685784) (xy 58.567831 -141.61008) (xy 57.451752 -141.61008) (xy 57.451248 -141.647986)
			(xy 57.443189 -141.723367) (xy 57.427164 -141.797465) (xy 57.403354 -141.86944) (xy 57.372028 -141.938476)
			(xy 57.333541 -142.003791) (xy 57.28833 -142.064646) (xy 57.236906 -142.12035) (xy 57.179853 -142.170272)
			(xy 57.117817 -142.213847) (xy 57.0515 -142.250582) (xy 56.981654 -142.280059) (xy 56.909071 -142.301945)
			(xy 56.834573 -142.315992) (xy 56.759003 -142.322041) (xy 56.683219 -142.320022) (xy 56.608079 -142.30996)
			(xy 56.534434 -142.291968) (xy 56.463118 -142.26625) (xy 56.394941 -142.233098) (xy 56.330673 -142.192886)
			(xy 56.271044 -142.146071) (xy 56.216728 -142.093183) (xy 56.168342 -142.034821) (xy 56.126434 -141.971646)
			(xy 56.091478 -141.904375) (xy 56.063871 -141.83377) (xy 56.043925 -141.760629) (xy 56.031866 -141.685784)
			(xy 56.027831 -141.61008) (xy 54.911752 -141.61008) (xy 54.911248 -141.647986) (xy 54.903189 -141.723367)
			(xy 54.887164 -141.797465) (xy 54.863354 -141.86944) (xy 54.832028 -141.938476) (xy 54.793541 -142.003791)
			(xy 54.74833 -142.064646) (xy 54.696906 -142.12035) (xy 54.639853 -142.170272) (xy 54.577817 -142.213847)
			(xy 54.5115 -142.250582) (xy 54.441654 -142.280059) (xy 54.369071 -142.301945) (xy 54.294573 -142.315992)
			(xy 54.219003 -142.322041) (xy 54.143219 -142.320022) (xy 54.068079 -142.30996) (xy 53.994434 -142.291968)
			(xy 53.923118 -142.26625) (xy 53.854941 -142.233098) (xy 53.790673 -142.192886) (xy 53.731044 -142.146071)
			(xy 53.676728 -142.093183) (xy 53.628342 -142.034821) (xy 53.586434 -141.971646) (xy 53.551478 -141.904375)
			(xy 53.523871 -141.83377) (xy 53.503925 -141.760629) (xy 53.491866 -141.685784) (xy 53.487831 -141.61008)
			(xy 52.371752 -141.61008) (xy 52.371248 -141.647986) (xy 52.363189 -141.723367) (xy 52.347164 -141.797465)
			(xy 52.323354 -141.86944) (xy 52.292028 -141.938476) (xy 52.253541 -142.003791) (xy 52.20833 -142.064646)
			(xy 52.156906 -142.12035) (xy 52.099853 -142.170272) (xy 52.037817 -142.213847) (xy 51.9715 -142.250582)
			(xy 51.901654 -142.280059) (xy 51.829071 -142.301945) (xy 51.754573 -142.315992) (xy 51.679003 -142.322041)
			(xy 51.603219 -142.320022) (xy 51.528079 -142.30996) (xy 51.454434 -142.291968) (xy 51.383118 -142.26625)
			(xy 51.314941 -142.233098) (xy 51.250673 -142.192886) (xy 51.191044 -142.146071) (xy 51.136728 -142.093183)
			(xy 51.088342 -142.034821) (xy 51.046434 -141.971646) (xy 51.011478 -141.904375) (xy 50.983871 -141.83377)
			(xy 50.963925 -141.760629) (xy 50.951866 -141.685784) (xy 50.947831 -141.61008) (xy 49.831752 -141.61008)
			(xy 49.831248 -141.647986) (xy 49.823189 -141.723367) (xy 49.807164 -141.797465) (xy 49.783354 -141.86944)
			(xy 49.752028 -141.938476) (xy 49.713541 -142.003791) (xy 49.66833 -142.064646) (xy 49.616906 -142.12035)
			(xy 49.559853 -142.170272) (xy 49.497817 -142.213847) (xy 49.4315 -142.250582) (xy 49.361654 -142.280059)
			(xy 49.289071 -142.301945) (xy 49.214573 -142.315992) (xy 49.139003 -142.322041) (xy 49.063219 -142.320022)
			(xy 48.988079 -142.30996) (xy 48.914434 -142.291968) (xy 48.843118 -142.26625) (xy 48.774941 -142.233098)
			(xy 48.710673 -142.192886) (xy 48.651044 -142.146071) (xy 48.596728 -142.093183) (xy 48.548342 -142.034821)
			(xy 48.506434 -141.971646) (xy 48.471478 -141.904375) (xy 48.443871 -141.83377) (xy 48.423925 -141.760629)
			(xy 48.411866 -141.685784) (xy 48.407831 -141.61008) (xy 47.291752 -141.61008) (xy 47.291248 -141.647986)
			(xy 47.283189 -141.723367) (xy 47.267164 -141.797465) (xy 47.243354 -141.86944) (xy 47.212028 -141.938476)
			(xy 47.173541 -142.003791) (xy 47.12833 -142.064646) (xy 47.076906 -142.12035) (xy 47.019853 -142.170272)
			(xy 46.957817 -142.213847) (xy 46.8915 -142.250582) (xy 46.821654 -142.280059) (xy 46.749071 -142.301945)
			(xy 46.674573 -142.315992) (xy 46.599003 -142.322041) (xy 46.523219 -142.320022) (xy 46.448079 -142.30996)
			(xy 46.374434 -142.291968) (xy 46.303118 -142.26625) (xy 46.234941 -142.233098) (xy 46.170673 -142.192886)
			(xy 46.111044 -142.146071) (xy 46.056728 -142.093183) (xy 46.008342 -142.034821) (xy 45.966434 -141.971646)
			(xy 45.931478 -141.904375) (xy 45.903871 -141.83377) (xy 45.883925 -141.760629) (xy 45.871866 -141.685784)
			(xy 45.867831 -141.61008) (xy 44.751752 -141.61008) (xy 44.751248 -141.647986) (xy 44.743189 -141.723367)
			(xy 44.727164 -141.797465) (xy 44.703354 -141.86944) (xy 44.672028 -141.938476) (xy 44.633541 -142.003791)
			(xy 44.58833 -142.064646) (xy 44.536906 -142.12035) (xy 44.479853 -142.170272) (xy 44.417817 -142.213847)
			(xy 44.3515 -142.250582) (xy 44.281654 -142.280059) (xy 44.209071 -142.301945) (xy 44.134573 -142.315992)
			(xy 44.059003 -142.322041) (xy 43.983219 -142.320022) (xy 43.908079 -142.30996) (xy 43.834434 -142.291968)
			(xy 43.763118 -142.26625) (xy 43.694941 -142.233098) (xy 43.630673 -142.192886) (xy 43.571044 -142.146071)
			(xy 43.516728 -142.093183) (xy 43.468342 -142.034821) (xy 43.426434 -141.971646) (xy 43.391478 -141.904375)
			(xy 43.363871 -141.83377) (xy 43.343925 -141.760629) (xy 43.331866 -141.685784) (xy 43.327831 -141.61008)
			(xy 42.503292 -141.61008) (xy 42.47864 -141.629064) (xy 42.380994 -141.693948) (xy 42.279065 -141.75187)
			(xy 42.173347 -141.802549) (xy 42.064355 -141.845738) (xy 41.952619 -141.881228) (xy 41.838681 -141.908845)
			(xy 41.723096 -141.928457) (xy 41.606425 -141.939967) (xy 41.489236 -141.943319) (xy 41.372098 -141.938497)
			(xy 41.25558 -141.925525) (xy 41.14025 -141.904466) (xy 41.026668 -141.875421) (xy 40.915385 -141.838533)
			(xy 40.806943 -141.79398) (xy 40.70187 -141.74198) (xy 40.600675 -141.682784) (xy 40.50385 -141.616681)
			(xy 40.411868 -141.543992) (xy 40.325173 -141.46507) (xy 40.244189 -141.380299) (xy 40.169308 -141.290091)
			(xy 40.100895 -141.194885) (xy 40.039282 -141.095143) (xy 39.984769 -140.991351) (xy 39.937621 -140.884012)
			(xy 39.898066 -140.773649) (xy 39.866298 -140.660798) (xy 39.842471 -140.546008) (xy 39.826699 -140.429836)
			(xy 39.819061 -140.312848) (xy 39.818818 -140.254228) (xy 29.4005 -140.254228) (xy 29.4005 -140.608558)
			(xy 29.400954 -140.623805) (xy 29.408199 -140.653425) (xy 29.422261 -140.680483) (xy 29.442339 -140.703434)
			(xy 29.467287 -140.720969) (xy 29.495682 -140.732087) (xy 29.510736 -140.734542) (xy 29.531497 -140.736872)
			(xy 29.57325 -140.735527) (xy 29.614221 -140.727375) (xy 29.653308 -140.712635) (xy 29.68946 -140.691704)
			(xy 29.721704 -140.665144) (xy 29.73578 -140.649706) (xy 29.763898 -140.616555) (xy 29.825324 -140.555038)
			(xy 29.892165 -140.499453) (xy 29.963852 -140.450274) (xy 30.039772 -140.407922) (xy 30.119276 -140.372758)
			(xy 30.201687 -140.345082) (xy 30.2863 -140.32513) (xy 30.372394 -140.313073) (xy 30.459233 -140.309014)
			(xy 30.546076 -140.312987) (xy 30.632181 -140.324959) (xy 30.716815 -140.344826) (xy 30.799253 -140.37242)
			(xy 30.878792 -140.407506) (xy 30.954754 -140.449782) (xy 31.026489 -140.49889) (xy 31.093386 -140.554408)
			(xy 31.154873 -140.615864) (xy 31.210425 -140.682733) (xy 31.259569 -140.754444) (xy 31.301883 -140.830384)
			(xy 31.337009 -140.909906) (xy 31.364644 -140.99233) (xy 31.384555 -141.076953) (xy 31.396569 -141.163053)
			(xy 31.400586 -141.249894) (xy 31.398576 -141.293358) (xy 34.599874 -141.293358) (xy 34.599874 -141.206458)
			(xy 34.607892 -141.119929) (xy 34.62386 -141.034509) (xy 34.647641 -140.950927) (xy 34.679033 -140.869895)
			(xy 34.717767 -140.792106) (xy 34.763514 -140.718222) (xy 34.815883 -140.648875) (xy 34.874427 -140.584655)
			(xy 34.938647 -140.526111) (xy 35.007994 -140.473742) (xy 35.081878 -140.427995) (xy 35.159667 -140.389261)
			(xy 35.240699 -140.357869) (xy 35.324281 -140.334088) (xy 35.409701 -140.31812) (xy 35.49623 -140.310102)
			(xy 35.58313 -140.310102) (xy 35.669659 -140.31812) (xy 35.755079 -140.334088) (xy 35.838661 -140.357869)
			(xy 35.919693 -140.389261) (xy 35.997482 -140.427995) (xy 36.071366 -140.473742) (xy 36.140713 -140.526111)
			(xy 36.204933 -140.584655) (xy 36.263477 -140.648875) (xy 36.315846 -140.718222) (xy 36.361593 -140.792106)
			(xy 36.400327 -140.869895) (xy 36.431719 -140.950927) (xy 36.4555 -141.034509) (xy 36.471468 -141.119929)
			(xy 36.479486 -141.206458) (xy 36.479988 -141.249908) (xy 36.479486 -141.293358) (xy 36.471468 -141.379887)
			(xy 36.4555 -141.465307) (xy 36.431719 -141.548889) (xy 36.400327 -141.629921) (xy 36.361593 -141.70771)
			(xy 36.315846 -141.781594) (xy 36.263477 -141.850941) (xy 36.204933 -141.915161) (xy 36.140713 -141.973705)
			(xy 36.071366 -142.026074) (xy 35.997482 -142.071821) (xy 35.919693 -142.110555) (xy 35.838661 -142.141947)
			(xy 35.755079 -142.165728) (xy 35.669659 -142.181696) (xy 35.58313 -142.189714) (xy 35.49623 -142.189714)
			(xy 35.409701 -142.181696) (xy 35.324281 -142.165728) (xy 35.240699 -142.141947) (xy 35.159667 -142.110555)
			(xy 35.081878 -142.071821) (xy 35.007994 -142.026074) (xy 34.938647 -141.973705) (xy 34.874427 -141.915161)
			(xy 34.815883 -141.850941) (xy 34.763514 -141.781594) (xy 34.717767 -141.70771) (xy 34.679033 -141.629921)
			(xy 34.647641 -141.548889) (xy 34.62386 -141.465307) (xy 34.607892 -141.379887) (xy 34.599874 -141.293358)
			(xy 31.398576 -141.293358) (xy 31.39657 -141.336735) (xy 31.384557 -141.422835) (xy 31.364648 -141.507458)
			(xy 31.337013 -141.589883) (xy 31.301889 -141.669405) (xy 31.259575 -141.745346) (xy 31.210433 -141.817057)
			(xy 31.154881 -141.883927) (xy 31.093395 -141.945383) (xy 31.026499 -142.000903) (xy 30.954764 -142.050011)
			(xy 30.878803 -142.092289) (xy 30.799264 -142.127375) (xy 30.716826 -142.15497) (xy 30.632194 -142.174839)
			(xy 30.546088 -142.186812) (xy 30.459245 -142.190786) (xy 30.372406 -142.186728) (xy 30.286312 -142.174672)
			(xy 30.201699 -142.154721) (xy 30.119288 -142.127046) (xy 30.039783 -142.091883) (xy 29.963862 -142.049532)
			(xy 29.892175 -142.000355) (xy 29.825333 -141.94477) (xy 29.763906 -141.883254) (xy 29.73578 -141.85011)
			(xy 29.721738 -141.834635) (xy 29.689504 -141.80805) (xy 29.653349 -141.787107) (xy 29.61425 -141.772373)
			(xy 29.573265 -141.764245) (xy 29.531502 -141.762944) (xy 29.510736 -141.765274) (xy 29.495673 -141.767723)
			(xy 29.467249 -141.778805) (xy 29.442274 -141.796327) (xy 29.422182 -141.819285) (xy 29.408124 -141.846361)
			(xy 29.400907 -141.876003) (xy 29.4005 -141.891258) (xy 29.4005 -150.88342) (xy 57.520655 -150.88342)
			(xy 57.52454 -150.829061) (xy 57.536122 -150.775808) (xy 57.555165 -150.724746) (xy 57.581282 -150.676913)
			(xy 57.613941 -150.633285) (xy 57.652476 -150.594748) (xy 57.696103 -150.562088) (xy 57.743935 -150.53597)
			(xy 57.794997 -150.516926) (xy 57.84825 -150.505342) (xy 57.902609 -150.501455) (xy 57.956968 -150.505344)
			(xy 58.01022 -150.51693) (xy 58.061281 -150.535978) (xy 58.109111 -150.562098) (xy 58.131202 -150.578058)
			(xy 58.150214 -150.591654) (xy 58.192097 -150.612386) (xy 58.237065 -150.625112) (xy 58.283602 -150.629402)
			(xy 58.330139 -150.625112) (xy 58.375107 -150.612386) (xy 58.41699 -150.591654) (xy 58.436002 -150.578058)
			(xy 58.458122 -150.562144) (xy 58.505945 -150.536028) (xy 58.556999 -150.516984) (xy 58.610243 -150.5054)
			(xy 58.664593 -150.501512) (xy 58.718944 -150.505398) (xy 58.772189 -150.516981) (xy 58.823243 -150.536023)
			(xy 58.871067 -150.562137) (xy 58.914688 -150.594792) (xy 58.953217 -150.633323) (xy 58.98587 -150.676945)
			(xy 59.011983 -150.72477) (xy 59.031023 -150.775825) (xy 59.042604 -150.829069) (xy 59.046488 -150.88342)
			(xy 59.407348 -150.88342) (xy 59.411233 -150.82906) (xy 59.422816 -150.775805) (xy 59.44186 -150.724741)
			(xy 59.467977 -150.676907) (xy 59.500637 -150.633278) (xy 59.539174 -150.59474) (xy 59.582803 -150.56208)
			(xy 59.630637 -150.535962) (xy 59.6817 -150.516917) (xy 59.734955 -150.505334) (xy 59.789316 -150.501448)
			(xy 59.843676 -150.505338) (xy 59.89693 -150.516926) (xy 59.947992 -150.535975) (xy 59.995823 -150.562097)
			(xy 60.017914 -150.578058) (xy 60.036926 -150.591654) (xy 60.078809 -150.612386) (xy 60.123777 -150.625112)
			(xy 60.170314 -150.629402) (xy 60.216851 -150.625112) (xy 60.261819 -150.612386) (xy 60.303702 -150.591654)
			(xy 60.322714 -150.578058) (xy 60.344834 -150.562145) (xy 60.392656 -150.536031) (xy 60.443709 -150.516989)
			(xy 60.496951 -150.505406) (xy 60.5513 -150.501519) (xy 60.605649 -150.505406) (xy 60.658892 -150.516989)
			(xy 60.709944 -150.536031) (xy 60.757767 -150.562145) (xy 60.801386 -150.5948) (xy 60.839914 -150.63333)
			(xy 60.872566 -150.676951) (xy 60.898677 -150.724775) (xy 60.917717 -150.775828) (xy 60.929297 -150.829071)
			(xy 60.933181 -150.88342) (xy 61.648483 -150.88342) (xy 61.652367 -150.829067) (xy 61.663947 -150.77582)
			(xy 61.682988 -150.724764) (xy 61.7091 -150.676936) (xy 61.741754 -150.633312) (xy 61.780283 -150.594778)
			(xy 61.823904 -150.562121) (xy 61.871729 -150.536003) (xy 61.922784 -150.516958) (xy 61.97603 -150.505373)
			(xy 62.030383 -150.501483) (xy 62.084736 -150.505368) (xy 62.137982 -150.516948) (xy 62.189039 -150.535989)
			(xy 62.236866 -150.562102) (xy 62.258956 -150.578058) (xy 62.277968 -150.591654) (xy 62.319851 -150.612386)
			(xy 62.364819 -150.625112) (xy 62.411356 -150.629402) (xy 62.457893 -150.625112) (xy 62.502861 -150.612386)
			(xy 62.544744 -150.591654) (xy 62.563756 -150.578058) (xy 62.585877 -150.56214) (xy 62.633704 -150.536017)
			(xy 62.684761 -150.516967) (xy 62.738011 -150.505377) (xy 62.792367 -150.501484) (xy 62.846725 -150.505368)
			(xy 62.899976 -150.516948) (xy 62.951037 -150.53599) (xy 62.998868 -150.562105) (xy 63.042495 -150.594762)
			(xy 63.08103 -150.633296) (xy 63.113689 -150.676922) (xy 63.139805 -150.724752) (xy 63.158848 -150.775812)
			(xy 63.170431 -150.829063) (xy 63.174316 -150.88342) (xy 63.552332 -150.88342) (xy 63.556218 -150.829056)
			(xy 63.567802 -150.775798) (xy 63.586847 -150.724731) (xy 63.612967 -150.676894) (xy 63.64563 -150.633262)
			(xy 63.68417 -150.594723) (xy 63.727803 -150.562062) (xy 63.77564 -150.535943) (xy 63.826708 -150.516899)
			(xy 63.879966 -150.505317) (xy 63.93433 -150.501432) (xy 63.988694 -150.505325) (xy 64.041951 -150.516916)
			(xy 64.093015 -150.535968) (xy 64.140848 -150.562095) (xy 64.16294 -150.578058) (xy 64.181952 -150.591654)
			(xy 64.223835 -150.612386) (xy 64.268803 -150.625112) (xy 64.31534 -150.629402) (xy 64.361877 -150.625112)
			(xy 64.406845 -150.612386) (xy 64.448728 -150.591654) (xy 64.46774 -150.578058) (xy 64.489859 -150.562147)
			(xy 64.53768 -150.536037) (xy 64.58873 -150.516999) (xy 64.641969 -150.505419) (xy 64.696315 -150.501535)
			(xy 64.750661 -150.505424) (xy 64.803899 -150.517007) (xy 64.854948 -150.53605) (xy 64.902766 -150.562164)
			(xy 64.946382 -150.594817) (xy 64.984906 -150.633345) (xy 65.017556 -150.676964) (xy 65.043665 -150.724785)
			(xy 65.062703 -150.775835) (xy 65.074281 -150.829075) (xy 65.078165 -150.88342) (xy 65.074276 -150.937766)
			(xy 65.062691 -150.991004) (xy 65.043648 -151.042052) (xy 65.017533 -151.089871) (xy 64.98488 -151.133486)
			(xy 64.946351 -151.17201) (xy 64.902732 -151.204658) (xy 64.854911 -151.230767) (xy 64.80386 -151.249804)
			(xy 64.75062 -151.261382) (xy 64.696274 -151.265265) (xy 64.641929 -151.261375) (xy 64.588691 -151.24979)
			(xy 64.537643 -151.230746) (xy 64.489825 -151.204631) (xy 64.46774 -151.188674) (xy 64.448728 -151.175078)
			(xy 64.406845 -151.154346) (xy 64.361877 -151.14162) (xy 64.31534 -151.13733) (xy 64.268803 -151.14162)
			(xy 64.223835 -151.154346) (xy 64.181952 -151.175078) (xy 64.16294 -151.188674) (xy 64.140883 -151.204683)
			(xy 64.093052 -151.230815) (xy 64.04199 -151.249873) (xy 63.988735 -151.261469) (xy 63.934371 -151.265368)
			(xy 63.880006 -151.261489) (xy 63.826747 -151.249913) (xy 63.775677 -151.230874) (xy 63.727837 -151.20476)
			(xy 63.684201 -151.172103) (xy 63.645657 -151.133569) (xy 63.612989 -151.08994) (xy 63.586864 -151.042106)
			(xy 63.567813 -150.991041) (xy 63.556224 -150.937784) (xy 63.552332 -150.88342) (xy 63.174316 -150.88342)
			(xy 63.170425 -150.937777) (xy 63.158837 -150.991027) (xy 63.139788 -151.042085) (xy 63.113666 -151.089913)
			(xy 63.081003 -151.133535) (xy 63.042464 -151.172065) (xy 62.998834 -151.204717) (xy 62.951 -151.230827)
			(xy 62.899937 -151.249863) (xy 62.846684 -151.261438) (xy 62.792327 -151.265316) (xy 62.73797 -151.261417)
			(xy 62.684722 -151.249822) (xy 62.633666 -151.230766) (xy 62.585843 -151.204638) (xy 62.563756 -151.188674)
			(xy 62.544744 -151.175078) (xy 62.502861 -151.154346) (xy 62.457893 -151.14162) (xy 62.411356 -151.13733)
			(xy 62.364819 -151.14162) (xy 62.319851 -151.154346) (xy 62.277968 -151.175078) (xy 62.258956 -151.188674)
			(xy 62.236901 -151.204676) (xy 62.189076 -151.230794) (xy 62.138022 -151.24984) (xy 62.084776 -151.261427)
			(xy 62.030423 -151.265317) (xy 61.97607 -151.261433) (xy 61.922823 -151.249853) (xy 61.871766 -151.230814)
			(xy 61.823939 -151.204701) (xy 61.780314 -151.172048) (xy 61.74178 -151.133519) (xy 61.709122 -151.089898)
			(xy 61.683005 -151.042074) (xy 61.663959 -150.991019) (xy 61.652373 -150.937773) (xy 61.648483 -150.88342)
			(xy 60.933181 -150.88342) (xy 60.929291 -150.937769) (xy 60.917705 -150.991011) (xy 60.89866 -151.042063)
			(xy 60.872544 -151.089884) (xy 60.839887 -151.133501) (xy 60.801355 -151.172027) (xy 60.757732 -151.204677)
			(xy 60.709907 -151.230786) (xy 60.658853 -151.249822) (xy 60.605609 -151.261399) (xy 60.55126 -151.265281)
			(xy 60.496911 -151.261388) (xy 60.443669 -151.2498) (xy 60.392619 -151.230752) (xy 60.344799 -151.204633)
			(xy 60.322714 -151.188674) (xy 60.303702 -151.175078) (xy 60.261819 -151.154346) (xy 60.216851 -151.14162)
			(xy 60.170314 -151.13733) (xy 60.123777 -151.14162) (xy 60.078809 -151.154346) (xy 60.036926 -151.175078)
			(xy 60.017914 -151.188674) (xy 59.995857 -151.204681) (xy 59.948029 -151.230808) (xy 59.896969 -151.249863)
			(xy 59.843717 -151.261456) (xy 59.789356 -151.265352) (xy 59.734995 -151.261472) (xy 59.68174 -151.249894)
			(xy 59.630674 -151.230855) (xy 59.582838 -151.204742) (xy 59.539205 -151.172086) (xy 59.500664 -151.133553)
			(xy 59.468 -151.089927) (xy 59.441877 -151.042096) (xy 59.422827 -150.991034) (xy 59.411239 -150.937781)
			(xy 59.407348 -150.88342) (xy 59.046488 -150.88342) (xy 59.042598 -150.937771) (xy 59.031012 -150.991015)
			(xy 59.011966 -151.042067) (xy 58.985848 -151.08989) (xy 58.95319 -151.133508) (xy 58.914657 -151.172035)
			(xy 58.871033 -151.204685) (xy 58.823206 -151.230794) (xy 58.77215 -151.249831) (xy 58.718904 -151.261407)
			(xy 58.664553 -151.265288) (xy 58.610202 -151.261394) (xy 58.55696 -151.249804) (xy 58.505908 -151.230755)
			(xy 58.458088 -151.204634) (xy 58.436002 -151.188674) (xy 58.41699 -151.175078) (xy 58.375107 -151.154346)
			(xy 58.330139 -151.14162) (xy 58.283602 -151.13733) (xy 58.237065 -151.14162) (xy 58.192097 -151.154346)
			(xy 58.150214 -151.175078) (xy 58.131202 -151.188674) (xy 58.109146 -151.20468) (xy 58.061318 -151.230805)
			(xy 58.010259 -151.249858) (xy 57.957008 -151.26145) (xy 57.90265 -151.265345) (xy 57.84829 -151.261464)
			(xy 57.795036 -151.249886) (xy 57.743972 -151.230847) (xy 57.696138 -151.204734) (xy 57.652507 -151.172079)
			(xy 57.613967 -151.133546) (xy 57.581304 -151.089921) (xy 57.555182 -151.042091) (xy 57.536134 -150.991031)
			(xy 57.524546 -150.937779) (xy 57.520655 -150.88342) (xy 29.4005 -150.88342) (xy 29.4005 -151.965575)
			(xy 48.168042 -151.965575) (xy 48.168042 -151.884465) (xy 48.175992 -151.803746) (xy 48.191815 -151.724195)
			(xy 48.21536 -151.646579) (xy 48.246399 -151.571643) (xy 48.284634 -151.500111) (xy 48.329696 -151.432671)
			(xy 48.381151 -151.369972) (xy 48.438504 -151.312619) (xy 48.501203 -151.261164) (xy 48.568643 -151.216102)
			(xy 48.640175 -151.177867) (xy 48.715111 -151.146828) (xy 48.792727 -151.123283) (xy 48.872278 -151.10746)
			(xy 48.952997 -151.09951) (xy 49.034107 -151.09951) (xy 49.114826 -151.10746) (xy 49.194377 -151.123283)
			(xy 49.271993 -151.146828) (xy 49.346929 -151.177867) (xy 49.418461 -151.216102) (xy 49.485901 -151.261164)
			(xy 49.5486 -151.312619) (xy 49.605953 -151.369972) (xy 49.657408 -151.432671) (xy 49.70247 -151.500111)
			(xy 49.740705 -151.571643) (xy 49.771744 -151.646579) (xy 49.795289 -151.724195) (xy 49.811112 -151.803746)
			(xy 49.819062 -151.884465) (xy 49.81956 -151.92502) (xy 49.819062 -151.965575) (xy 51.668162 -151.965575)
			(xy 51.668162 -151.884465) (xy 51.676112 -151.803746) (xy 51.691935 -151.724195) (xy 51.71548 -151.646579)
			(xy 51.746519 -151.571643) (xy 51.784754 -151.500111) (xy 51.829816 -151.432671) (xy 51.881271 -151.369972)
			(xy 51.938624 -151.312619) (xy 52.001323 -151.261164) (xy 52.068763 -151.216102) (xy 52.140295 -151.177867)
			(xy 52.215231 -151.146828) (xy 52.292847 -151.123283) (xy 52.372398 -151.10746) (xy 52.453117 -151.09951)
			(xy 52.534227 -151.09951) (xy 52.614946 -151.10746) (xy 52.694497 -151.123283) (xy 52.772113 -151.146828)
			(xy 52.847049 -151.177867) (xy 52.918581 -151.216102) (xy 52.986021 -151.261164) (xy 53.04872 -151.312619)
			(xy 53.106073 -151.369972) (xy 53.157528 -151.432671) (xy 53.20259 -151.500111) (xy 53.240825 -151.571643)
			(xy 53.271864 -151.646579) (xy 53.295409 -151.724195) (xy 53.311232 -151.803746) (xy 53.319182 -151.884465)
			(xy 53.31968 -151.92502) (xy 53.319182 -151.965575) (xy 53.311232 -152.046294) (xy 53.295409 -152.125845)
			(xy 53.271864 -152.203461) (xy 53.240825 -152.278397) (xy 53.20259 -152.349929) (xy 53.157528 -152.417369)
			(xy 53.106073 -152.480068) (xy 53.04872 -152.537421) (xy 52.986021 -152.588876) (xy 52.918581 -152.633938)
			(xy 52.847049 -152.672173) (xy 52.772113 -152.703212) (xy 52.694497 -152.726757) (xy 52.614946 -152.74258)
			(xy 52.534227 -152.75053) (xy 52.453117 -152.75053) (xy 52.372398 -152.74258) (xy 52.292847 -152.726757)
			(xy 52.215231 -152.703212) (xy 52.140295 -152.672173) (xy 52.068763 -152.633938) (xy 52.001323 -152.588876)
			(xy 51.938624 -152.537421) (xy 51.881271 -152.480068) (xy 51.829816 -152.417369) (xy 51.784754 -152.349929)
			(xy 51.746519 -152.278397) (xy 51.71548 -152.203461) (xy 51.691935 -152.125845) (xy 51.676112 -152.046294)
			(xy 51.668162 -151.965575) (xy 49.819062 -151.965575) (xy 49.811112 -152.046294) (xy 49.795289 -152.125845)
			(xy 49.771744 -152.203461) (xy 49.740705 -152.278397) (xy 49.70247 -152.349929) (xy 49.657408 -152.417369)
			(xy 49.605953 -152.480068) (xy 49.5486 -152.537421) (xy 49.485901 -152.588876) (xy 49.418461 -152.633938)
			(xy 49.346929 -152.672173) (xy 49.271993 -152.703212) (xy 49.194377 -152.726757) (xy 49.114826 -152.74258)
			(xy 49.034107 -152.75053) (xy 48.952997 -152.75053) (xy 48.872278 -152.74258) (xy 48.792727 -152.726757)
			(xy 48.715111 -152.703212) (xy 48.640175 -152.672173) (xy 48.568643 -152.633938) (xy 48.501203 -152.588876)
			(xy 48.438504 -152.537421) (xy 48.381151 -152.480068) (xy 48.329696 -152.417369) (xy 48.284634 -152.349929)
			(xy 48.246399 -152.278397) (xy 48.21536 -152.203461) (xy 48.191815 -152.125845) (xy 48.175992 -152.046294)
			(xy 48.168042 -151.965575) (xy 29.4005 -151.965575) (xy 29.4005 -152.784299) (xy 57.520684 -152.784299)
			(xy 57.524572 -152.729944) (xy 57.536156 -152.676696) (xy 57.555201 -152.625638) (xy 57.581318 -152.577811)
			(xy 57.613977 -152.534187) (xy 57.652511 -152.495656) (xy 57.696137 -152.463001) (xy 57.743967 -152.436888)
			(xy 57.795026 -152.417847) (xy 57.848275 -152.406267) (xy 57.90263 -152.402384) (xy 57.956985 -152.406276)
			(xy 58.010232 -152.417864) (xy 58.061289 -152.436913) (xy 58.109114 -152.463034) (xy 58.131202 -152.478994)
			(xy 58.150214 -152.49259) (xy 58.192097 -152.513322) (xy 58.237065 -152.526048) (xy 58.283602 -152.530338)
			(xy 58.330139 -152.526048) (xy 58.375107 -152.513322) (xy 58.41699 -152.49259) (xy 58.436002 -152.478994)
			(xy 58.458088 -152.463032) (xy 58.505914 -152.436911) (xy 58.55697 -152.417863) (xy 58.610217 -152.406275)
			(xy 58.664572 -152.402383) (xy 58.718927 -152.406267) (xy 58.772176 -152.417847) (xy 58.823235 -152.436888)
			(xy 58.871064 -152.463001) (xy 58.91469 -152.495656) (xy 58.953225 -152.534187) (xy 58.985883 -152.577811)
			(xy 59.012 -152.625638) (xy 59.031045 -152.676696) (xy 59.042629 -152.729944) (xy 59.046517 -152.784299)
			(xy 59.407377 -152.784299) (xy 59.411265 -152.729942) (xy 59.422849 -152.676692) (xy 59.441895 -152.625633)
			(xy 59.468013 -152.577805) (xy 59.500673 -152.53418) (xy 59.539209 -152.495648) (xy 59.582837 -152.462993)
			(xy 59.630668 -152.436879) (xy 59.681729 -152.417839) (xy 59.73498 -152.406259) (xy 59.789337 -152.402377)
			(xy 59.843693 -152.40627) (xy 59.896942 -152.41786) (xy 59.947999 -152.43691) (xy 59.995826 -152.463033)
			(xy 60.017914 -152.478994) (xy 60.036926 -152.49259) (xy 60.078809 -152.513322) (xy 60.123777 -152.526048)
			(xy 60.170314 -152.530338) (xy 60.216851 -152.526048) (xy 60.261819 -152.513322) (xy 60.303702 -152.49259)
			(xy 60.322714 -152.478994) (xy 60.3448 -152.463033) (xy 60.392625 -152.436914) (xy 60.44368 -152.417867)
			(xy 60.496926 -152.406281) (xy 60.551279 -152.40239) (xy 60.605632 -152.406275) (xy 60.658879 -152.417855)
			(xy 60.709937 -152.436896) (xy 60.757764 -152.46301) (xy 60.801389 -152.495664) (xy 60.839921 -152.534195)
			(xy 60.872578 -152.577817) (xy 60.898695 -152.625643) (xy 60.917738 -152.676699) (xy 60.929322 -152.729946)
			(xy 60.93321 -152.784299) (xy 61.648511 -152.784299) (xy 61.652399 -152.72995) (xy 61.663981 -152.676708)
			(xy 61.683023 -152.625656) (xy 61.709136 -152.577834) (xy 61.74179 -152.534214) (xy 61.780318 -152.495686)
			(xy 61.823938 -152.463033) (xy 61.871761 -152.436921) (xy 61.922813 -152.41788) (xy 61.976055 -152.406298)
			(xy 62.030404 -152.402411) (xy 62.084753 -152.406299) (xy 62.137995 -152.417882) (xy 62.189047 -152.436924)
			(xy 62.236869 -152.463038) (xy 62.258956 -152.478994) (xy 62.277968 -152.49259) (xy 62.319851 -152.513322)
			(xy 62.364819 -152.526048) (xy 62.411356 -152.530338) (xy 62.457893 -152.526048) (xy 62.502861 -152.513322)
			(xy 62.544744 -152.49259) (xy 62.563756 -152.478994) (xy 62.585843 -152.463028) (xy 62.633672 -152.4369)
			(xy 62.684732 -152.417845) (xy 62.737985 -152.406252) (xy 62.792346 -152.402356) (xy 62.846707 -152.406236)
			(xy 62.899963 -152.417814) (xy 62.951029 -152.436855) (xy 62.998865 -152.462969) (xy 63.042498 -152.495626)
			(xy 63.081038 -152.53416) (xy 63.113701 -152.577788) (xy 63.139822 -152.62562) (xy 63.15887 -152.676683)
			(xy 63.170456 -152.729938) (xy 63.174344 -152.784299) (xy 63.552361 -152.784299) (xy 63.55625 -152.729939)
			(xy 63.567835 -152.676685) (xy 63.586882 -152.625623) (xy 63.613003 -152.577792) (xy 63.645666 -152.534165)
			(xy 63.684205 -152.495631) (xy 63.727836 -152.462974) (xy 63.775672 -152.43686) (xy 63.826736 -152.41782)
			(xy 63.879991 -152.406242) (xy 63.934352 -152.402361) (xy 63.988712 -152.406257) (xy 64.041963 -152.41785)
			(xy 64.093023 -152.436904) (xy 64.140851 -152.463031) (xy 64.16294 -152.478994) (xy 64.181952 -152.49259)
			(xy 64.223835 -152.513322) (xy 64.268803 -152.526048) (xy 64.31534 -152.530338) (xy 64.361877 -152.526048)
			(xy 64.406845 -152.513322) (xy 64.448728 -152.49259) (xy 64.46774 -152.478994) (xy 64.489825 -152.463035)
			(xy 64.537648 -152.43692) (xy 64.588701 -152.417877) (xy 64.641944 -152.406294) (xy 64.696294 -152.402406)
			(xy 64.750643 -152.406292) (xy 64.803887 -152.417874) (xy 64.85494 -152.436915) (xy 64.902764 -152.463028)
			(xy 64.946384 -152.495681) (xy 64.984914 -152.53421) (xy 65.017568 -152.57783) (xy 65.043682 -152.625653)
			(xy 65.062724 -152.676706) (xy 65.074307 -152.729949) (xy 65.078194 -152.784299) (xy 65.074307 -152.838648)
			(xy 65.062725 -152.891892) (xy 65.043683 -152.942945) (xy 65.017569 -152.990768) (xy 64.984916 -153.034388)
			(xy 64.946386 -153.072917) (xy 64.902766 -153.105571) (xy 64.854942 -153.131684) (xy 64.803889 -153.150726)
			(xy 64.750646 -153.162308) (xy 64.696296 -153.166194) (xy 64.641946 -153.162306) (xy 64.588703 -153.150723)
			(xy 64.53765 -153.131681) (xy 64.489827 -153.105567) (xy 64.46774 -153.08961) (xy 64.448728 -153.076014)
			(xy 64.406845 -153.055282) (xy 64.361877 -153.042556) (xy 64.31534 -153.038266) (xy 64.268803 -153.042556)
			(xy 64.223835 -153.055282) (xy 64.181952 -153.076014) (xy 64.16294 -153.08961) (xy 64.140849 -153.105571)
			(xy 64.093021 -153.131697) (xy 64.041961 -153.150751) (xy 63.988709 -153.162344) (xy 63.93435 -153.166239)
			(xy 63.879989 -153.162358) (xy 63.826734 -153.150779) (xy 63.775669 -153.131739) (xy 63.727834 -153.105624)
			(xy 63.684203 -153.072968) (xy 63.645664 -153.034433) (xy 63.613002 -152.990806) (xy 63.586881 -152.942975)
			(xy 63.567835 -152.891912) (xy 63.556249 -152.838659) (xy 63.552361 -152.784299) (xy 63.174344 -152.784299)
			(xy 63.170456 -152.83866) (xy 63.158871 -152.891914) (xy 63.139823 -152.942978) (xy 63.113702 -152.99081)
			(xy 63.081039 -153.034438) (xy 63.042499 -153.072973) (xy 62.998867 -153.10563) (xy 62.951031 -153.131744)
			(xy 62.899966 -153.150785) (xy 62.84671 -153.162364) (xy 62.792348 -153.166244) (xy 62.737988 -153.162349)
			(xy 62.684735 -153.150756) (xy 62.633674 -153.131701) (xy 62.585845 -153.105574) (xy 62.563756 -153.08961)
			(xy 62.544744 -153.076014) (xy 62.502861 -153.055282) (xy 62.457893 -153.042556) (xy 62.411356 -153.038266)
			(xy 62.364819 -153.042556) (xy 62.319851 -153.055282) (xy 62.277968 -153.076014) (xy 62.258956 -153.08961)
			(xy 62.236867 -153.105564) (xy 62.189045 -153.131677) (xy 62.137993 -153.150719) (xy 62.08475 -153.162301)
			(xy 62.030402 -153.166189) (xy 61.976053 -153.162302) (xy 61.922811 -153.15072) (xy 61.871759 -153.131678)
			(xy 61.823936 -153.105565) (xy 61.780317 -153.072912) (xy 61.741788 -153.034384) (xy 61.709135 -152.990764)
			(xy 61.683022 -152.942942) (xy 61.66398 -152.89189) (xy 61.652398 -152.838647) (xy 61.648511 -152.784299)
			(xy 60.93321 -152.784299) (xy 60.929322 -152.838652) (xy 60.917739 -152.891899) (xy 60.898696 -152.942955)
			(xy 60.87258 -152.990781) (xy 60.839923 -153.034404) (xy 60.80139 -153.072935) (xy 60.757766 -153.105589)
			(xy 60.709939 -153.131703) (xy 60.658882 -153.150744) (xy 60.605635 -153.162325) (xy 60.551281 -153.16621)
			(xy 60.496928 -153.162319) (xy 60.443682 -153.150733) (xy 60.392627 -153.131687) (xy 60.344802 -153.105569)
			(xy 60.322714 -153.08961) (xy 60.303702 -153.076014) (xy 60.261819 -153.055282) (xy 60.216851 -153.042556)
			(xy 60.170314 -153.038266) (xy 60.123777 -153.042556) (xy 60.078809 -153.055282) (xy 60.036926 -153.076014)
			(xy 60.017914 -153.08961) (xy 59.995824 -153.105568) (xy 59.947997 -153.131691) (xy 59.89694 -153.150741)
			(xy 59.843691 -153.16233) (xy 59.789335 -153.166223) (xy 59.734978 -153.16234) (xy 59.681727 -153.150761)
			(xy 59.630666 -153.13172) (xy 59.582835 -153.105606) (xy 59.539207 -153.07295) (xy 59.500672 -153.034418)
			(xy 59.468012 -152.990793) (xy 59.441894 -152.942965) (xy 59.422849 -152.891905) (xy 59.411264 -152.838655)
			(xy 59.407377 -152.784299) (xy 59.046517 -152.784299) (xy 59.042629 -152.838654) (xy 59.031046 -152.891902)
			(xy 59.012001 -152.94296) (xy 58.985884 -152.990787) (xy 58.953226 -153.034411) (xy 58.914692 -153.072942)
			(xy 58.871066 -153.105598) (xy 58.823237 -153.131711) (xy 58.772178 -153.150752) (xy 58.718929 -153.162333)
			(xy 58.664574 -153.166217) (xy 58.61022 -153.162326) (xy 58.556972 -153.150738) (xy 58.505916 -153.13169)
			(xy 58.45809 -153.10557) (xy 58.436002 -153.08961) (xy 58.41699 -153.076014) (xy 58.375107 -153.055282)
			(xy 58.330139 -153.042556) (xy 58.283602 -153.038266) (xy 58.237065 -153.042556) (xy 58.192097 -153.055282)
			(xy 58.150214 -153.076014) (xy 58.131202 -153.08961) (xy 58.109112 -153.105567) (xy 58.061286 -153.131688)
			(xy 58.01023 -153.150736) (xy 57.956983 -153.162324) (xy 57.902628 -153.166216) (xy 57.848273 -153.162332)
			(xy 57.795024 -153.150752) (xy 57.743965 -153.131711) (xy 57.696135 -153.105598) (xy 57.652509 -153.072943)
			(xy 57.613975 -153.034411) (xy 57.581317 -152.990787) (xy 57.5552 -152.94296) (xy 57.536155 -152.891902)
			(xy 57.524571 -152.838654) (xy 57.520684 -152.784299) (xy 29.4005 -152.784299) (xy 29.4005 -154.459381)
			(xy 57.520708 -154.459381) (xy 57.524598 -154.405029) (xy 57.536184 -154.351785) (xy 57.55523 -154.300732)
			(xy 57.581348 -154.252908) (xy 57.614006 -154.209289) (xy 57.65254 -154.170762) (xy 57.696165 -154.138111)
			(xy 57.743993 -154.112002) (xy 57.79505 -154.092965) (xy 57.848296 -154.081388) (xy 57.902648 -154.077508)
			(xy 57.956999 -154.081402) (xy 58.010243 -154.092992) (xy 58.061295 -154.112042) (xy 58.109116 -154.138164)
			(xy 58.131202 -154.154124) (xy 58.150214 -154.16772) (xy 58.192097 -154.188452) (xy 58.237065 -154.201178)
			(xy 58.283602 -154.205468) (xy 58.330139 -154.201178) (xy 58.375107 -154.188452) (xy 58.41699 -154.16772)
			(xy 58.436002 -154.154124) (xy 58.45806 -154.138121) (xy 58.505887 -154.111997) (xy 58.556946 -154.092945)
			(xy 58.610196 -154.081354) (xy 58.664554 -154.077459) (xy 58.718913 -154.08134) (xy 58.772166 -154.092919)
			(xy 58.823229 -154.111958) (xy 58.871062 -154.138071) (xy 58.914693 -154.170726) (xy 58.953231 -154.209258)
			(xy 58.985893 -154.252883) (xy 59.012015 -154.300712) (xy 59.031063 -154.351772) (xy 59.04265 -154.405023)
			(xy 59.046541 -154.459381) (xy 59.407401 -154.459381) (xy 59.411291 -154.405028) (xy 59.422878 -154.351782)
			(xy 59.441924 -154.300727) (xy 59.468043 -154.252902) (xy 59.500703 -154.209282) (xy 59.539239 -154.170754)
			(xy 59.582865 -154.138103) (xy 59.630695 -154.111993) (xy 59.681753 -154.092957) (xy 59.735001 -154.08138)
			(xy 59.789355 -154.077501) (xy 59.843708 -154.081396) (xy 59.896953 -154.092988) (xy 59.948006 -154.112039)
			(xy 59.995828 -154.138163) (xy 60.017914 -154.154124) (xy 60.036926 -154.16772) (xy 60.078809 -154.188452)
			(xy 60.123777 -154.201178) (xy 60.170314 -154.205468) (xy 60.216851 -154.201178) (xy 60.261819 -154.188452)
			(xy 60.303702 -154.16772) (xy 60.322714 -154.154124) (xy 60.344772 -154.138122) (xy 60.392598 -154.111999)
			(xy 60.443656 -154.092949) (xy 60.496904 -154.08136) (xy 60.551261 -154.077466) (xy 60.605618 -154.081348)
			(xy 60.658869 -154.092927) (xy 60.70993 -154.111967) (xy 60.757762 -154.13808) (xy 60.801391 -154.170734)
			(xy 60.839928 -154.209265) (xy 60.872589 -154.252889) (xy 60.898709 -154.300717) (xy 60.917756 -154.351775)
			(xy 60.929343 -154.405024) (xy 60.933234 -154.459381) (xy 61.648535 -154.459381) (xy 61.652425 -154.405036)
			(xy 61.664009 -154.351797) (xy 61.683052 -154.30075) (xy 61.709166 -154.252931) (xy 61.74182 -154.209316)
			(xy 61.780348 -154.170792) (xy 61.823966 -154.138144) (xy 61.871787 -154.112035) (xy 61.922837 -154.092998)
			(xy 61.976077 -154.081419) (xy 62.030422 -154.077535) (xy 62.084767 -154.081425) (xy 62.138006 -154.09301)
			(xy 62.189053 -154.112053) (xy 62.236871 -154.138168) (xy 62.258956 -154.154124) (xy 62.277968 -154.16772)
			(xy 62.319851 -154.188452) (xy 62.364819 -154.201178) (xy 62.411356 -154.205468) (xy 62.457893 -154.201178)
			(xy 62.502861 -154.188452) (xy 62.544744 -154.16772) (xy 62.563756 -154.154124) (xy 62.585815 -154.138117)
			(xy 62.633646 -154.111985) (xy 62.684708 -154.092927) (xy 62.737964 -154.08133) (xy 62.792328 -154.077431)
			(xy 62.846693 -154.08131) (xy 62.899953 -154.092886) (xy 62.951023 -154.111925) (xy 62.998863 -154.138039)
			(xy 63.0425 -154.170696) (xy 63.081044 -154.209231) (xy 63.113712 -154.25286) (xy 63.139837 -154.300694)
			(xy 63.158888 -154.351759) (xy 63.170477 -154.405016) (xy 63.174369 -154.459381) (xy 63.552385 -154.459381)
			(xy 63.556276 -154.405024) (xy 63.567863 -154.351775) (xy 63.586912 -154.300717) (xy 63.613033 -154.25289)
			(xy 63.645696 -154.209267) (xy 63.684234 -154.170737) (xy 63.727865 -154.138085) (xy 63.775698 -154.111975)
			(xy 63.82676 -154.092938) (xy 63.880013 -154.081363) (xy 63.93437 -154.077485) (xy 63.988726 -154.081383)
			(xy 64.041974 -154.092978) (xy 64.093029 -154.112033) (xy 64.140853 -154.138161) (xy 64.16294 -154.154124)
			(xy 64.181952 -154.16772) (xy 64.223835 -154.188452) (xy 64.268803 -154.201178) (xy 64.31534 -154.205468)
			(xy 64.361877 -154.201178) (xy 64.406845 -154.188452) (xy 64.448728 -154.16772) (xy 64.46774 -154.154124)
			(xy 64.489797 -154.138124) (xy 64.537622 -154.112006) (xy 64.588677 -154.092959) (xy 64.641923 -154.081373)
			(xy 64.696276 -154.077482) (xy 64.750629 -154.081366) (xy 64.803876 -154.092946) (xy 64.854934 -154.111985)
			(xy 64.902762 -154.138098) (xy 64.946387 -154.170751) (xy 64.98492 -154.20928) (xy 65.002387 -154.23261)
			(xy 73.527918 -154.23261) (xy 73.531989 -154.176988) (xy 73.544115 -154.122551) (xy 73.564038 -154.07046)
			(xy 73.591334 -154.021825) (xy 73.62542 -153.977682) (xy 73.665569 -153.938973) (xy 73.710927 -153.906522)
			(xy 73.760527 -153.881021) (xy 73.813311 -153.863014) (xy 73.868154 -153.852884) (xy 73.923888 -153.850847)
			(xy 73.979325 -153.856947) (xy 74.033282 -153.871053) (xy 74.084611 -153.892865) (xy 74.132217 -153.921919)
			(xy 74.175085 -153.957594) (xy 74.212302 -153.999131) (xy 74.243075 -154.045644) (xy 74.266747 -154.096141)
			(xy 74.282815 -154.149548) (xy 74.290935 -154.204724) (xy 74.291444 -154.23261) (xy 74.677268 -154.23261)
			(xy 74.681339 -154.176988) (xy 74.693465 -154.122551) (xy 74.713388 -154.07046) (xy 74.740684 -154.021825)
			(xy 74.77477 -153.977682) (xy 74.814919 -153.938973) (xy 74.860277 -153.906522) (xy 74.909877 -153.881021)
			(xy 74.962661 -153.863014) (xy 75.017504 -153.852884) (xy 75.073238 -153.850847) (xy 75.128675 -153.856947)
			(xy 75.182632 -153.871053) (xy 75.233961 -153.892865) (xy 75.281567 -153.921919) (xy 75.324435 -153.957594)
			(xy 75.361652 -153.999131) (xy 75.392425 -154.045644) (xy 75.416097 -154.096141) (xy 75.432165 -154.149548)
			(xy 75.440285 -154.204724) (xy 75.440794 -154.23261) (xy 75.440285 -154.260496) (xy 75.432165 -154.315672)
			(xy 75.416097 -154.369079) (xy 75.392425 -154.419576) (xy 75.361652 -154.466089) (xy 75.324435 -154.507626)
			(xy 75.281567 -154.543301) (xy 75.233961 -154.572355) (xy 75.182632 -154.594167) (xy 75.128675 -154.608273)
			(xy 75.073238 -154.614373) (xy 75.017504 -154.612336) (xy 74.962661 -154.602206) (xy 74.909877 -154.584199)
			(xy 74.860277 -154.558698) (xy 74.814919 -154.526247) (xy 74.77477 -154.487538) (xy 74.740684 -154.443395)
			(xy 74.713388 -154.39476) (xy 74.693465 -154.342669) (xy 74.681339 -154.288232) (xy 74.677268 -154.23261)
			(xy 74.291444 -154.23261) (xy 74.290935 -154.260496) (xy 74.282815 -154.315672) (xy 74.266747 -154.369079)
			(xy 74.243075 -154.419576) (xy 74.212302 -154.466089) (xy 74.175085 -154.507626) (xy 74.132217 -154.543301)
			(xy 74.084611 -154.572355) (xy 74.033282 -154.594167) (xy 73.979325 -154.608273) (xy 73.923888 -154.614373)
			(xy 73.868154 -154.612336) (xy 73.813311 -154.602206) (xy 73.760527 -154.584199) (xy 73.710927 -154.558698)
			(xy 73.665569 -154.526247) (xy 73.62542 -154.487538) (xy 73.591334 -154.443395) (xy 73.564038 -154.39476)
			(xy 73.544115 -154.342669) (xy 73.531989 -154.288232) (xy 73.527918 -154.23261) (xy 65.002387 -154.23261)
			(xy 65.017579 -154.252902) (xy 65.043696 -154.300727) (xy 65.062742 -154.351782) (xy 65.074328 -154.405028)
			(xy 65.078218 -154.459381) (xy 65.074333 -154.513734) (xy 65.062753 -154.566981) (xy 65.043712 -154.618038)
			(xy 65.017599 -154.665866) (xy 64.984945 -154.709491) (xy 64.946416 -154.748024) (xy 64.902794 -154.780681)
			(xy 64.854969 -154.806799) (xy 64.803913 -154.825844) (xy 64.750667 -154.837429) (xy 64.696314 -154.841318)
			(xy 64.641961 -154.837433) (xy 64.588714 -154.825851) (xy 64.537657 -154.80681) (xy 64.48983 -154.780696)
			(xy 64.46774 -154.76474) (xy 64.448728 -154.751144) (xy 64.406845 -154.730412) (xy 64.361877 -154.717686)
			(xy 64.31534 -154.713396) (xy 64.268803 -154.717686) (xy 64.223835 -154.730412) (xy 64.181952 -154.751144)
			(xy 64.16294 -154.76474) (xy 64.140821 -154.78066) (xy 64.092995 -154.806783) (xy 64.041937 -154.825833)
			(xy 63.988688 -154.837422) (xy 63.934332 -154.841315) (xy 63.879975 -154.837431) (xy 63.826724 -154.825851)
			(xy 63.775663 -154.806809) (xy 63.727832 -154.780694) (xy 63.684205 -154.748038) (xy 63.645671 -154.709504)
			(xy 63.613012 -154.665878) (xy 63.586896 -154.618048) (xy 63.567853 -154.566988) (xy 63.55627 -154.513738)
			(xy 63.552385 -154.459381) (xy 63.174369 -154.459381) (xy 63.170483 -154.513746) (xy 63.158899 -154.567004)
			(xy 63.139853 -154.618071) (xy 63.113732 -154.665908) (xy 63.081069 -154.70954) (xy 63.042529 -154.748079)
			(xy 62.998896 -154.78074) (xy 62.951058 -154.806859) (xy 62.89999 -154.825903) (xy 62.846731 -154.837485)
			(xy 62.792366 -154.841369) (xy 62.738002 -154.837475) (xy 62.684745 -154.825884) (xy 62.633681 -154.806831)
			(xy 62.585848 -154.780704) (xy 62.563756 -154.76474) (xy 62.544744 -154.751144) (xy 62.502861 -154.730412)
			(xy 62.457893 -154.717686) (xy 62.411356 -154.713396) (xy 62.364819 -154.717686) (xy 62.319851 -154.730412)
			(xy 62.277968 -154.751144) (xy 62.258956 -154.76474) (xy 62.236839 -154.780653) (xy 62.189018 -154.806763)
			(xy 62.137969 -154.825801) (xy 62.084729 -154.83738) (xy 62.030384 -154.841265) (xy 61.976039 -154.837375)
			(xy 61.9228 -154.825792) (xy 61.871752 -154.806749) (xy 61.823934 -154.780636) (xy 61.780319 -154.747982)
			(xy 61.741794 -154.709455) (xy 61.709145 -154.665836) (xy 61.683036 -154.618016) (xy 61.663998 -154.566966)
			(xy 61.65242 -154.513726) (xy 61.648535 -154.459381) (xy 60.933234 -154.459381) (xy 60.929349 -154.513738)
			(xy 60.917767 -154.566988) (xy 60.898725 -154.618049) (xy 60.87261 -154.665879) (xy 60.839953 -154.709506)
			(xy 60.80142 -154.748041) (xy 60.757794 -154.7807) (xy 60.709965 -154.806817) (xy 60.658906 -154.825862)
			(xy 60.605656 -154.837446) (xy 60.551299 -154.841334) (xy 60.496942 -154.837446) (xy 60.443692 -154.825861)
			(xy 60.392633 -154.806817) (xy 60.344804 -154.780699) (xy 60.322714 -154.76474) (xy 60.303702 -154.751144)
			(xy 60.261819 -154.730412) (xy 60.216851 -154.717686) (xy 60.170314 -154.713396) (xy 60.123777 -154.717686)
			(xy 60.078809 -154.730412) (xy 60.036926 -154.751144) (xy 60.017914 -154.76474) (xy 59.995795 -154.780658)
			(xy 59.947971 -154.806777) (xy 59.896916 -154.825823) (xy 59.84367 -154.837409) (xy 59.789317 -154.841299)
			(xy 59.734963 -154.837414) (xy 59.681716 -154.825833) (xy 59.63066 -154.806791) (xy 59.582833 -154.780676)
			(xy 59.539209 -154.748021) (xy 59.500678 -154.709489) (xy 59.468023 -154.665865) (xy 59.441908 -154.618038)
			(xy 59.422867 -154.566981) (xy 59.411286 -154.513734) (xy 59.407401 -154.459381) (xy 59.046541 -154.459381)
			(xy 59.042656 -154.513739) (xy 59.031074 -154.566991) (xy 59.012031 -154.618053) (xy 58.985914 -154.665885)
			(xy 58.953256 -154.709513) (xy 58.914722 -154.748049) (xy 58.871095 -154.780708) (xy 58.823264 -154.806826)
			(xy 58.772203 -154.82587) (xy 58.718951 -154.837454) (xy 58.664592 -154.841341) (xy 58.610234 -154.837452)
			(xy 58.556983 -154.825866) (xy 58.505922 -154.806819) (xy 58.458092 -154.7807) (xy 58.436002 -154.76474)
			(xy 58.41699 -154.751144) (xy 58.375107 -154.730412) (xy 58.330139 -154.717686) (xy 58.283602 -154.713396)
			(xy 58.237065 -154.717686) (xy 58.192097 -154.730412) (xy 58.150214 -154.751144) (xy 58.131202 -154.76474)
			(xy 58.109084 -154.780657) (xy 58.06126 -154.806774) (xy 58.010206 -154.825818) (xy 57.956961 -154.837403)
			(xy 57.90261 -154.841292) (xy 57.848258 -154.837406) (xy 57.795013 -154.825824) (xy 57.743958 -154.806782)
			(xy 57.696133 -154.780668) (xy 57.652511 -154.748013) (xy 57.613981 -154.709482) (xy 57.581327 -154.665859)
			(xy 57.555214 -154.618033) (xy 57.536173 -154.566978) (xy 57.524593 -154.513733) (xy 57.520708 -154.459381)
			(xy 29.4005 -154.459381) (xy 29.4005 -155.07716) (xy 72.096374 -155.07716) (xy 72.100445 -155.021538)
			(xy 72.112571 -154.967101) (xy 72.132494 -154.91501) (xy 72.15979 -154.866375) (xy 72.193876 -154.822232)
			(xy 72.234025 -154.783523) (xy 72.279383 -154.751072) (xy 72.328983 -154.725571) (xy 72.381767 -154.707564)
			(xy 72.43661 -154.697434) (xy 72.492344 -154.695397) (xy 72.547781 -154.701497) (xy 72.601738 -154.715603)
			(xy 72.653067 -154.737415) (xy 72.700673 -154.766469) (xy 72.743541 -154.802144) (xy 72.780758 -154.843681)
			(xy 72.811531 -154.890194) (xy 72.835203 -154.940691) (xy 72.851271 -154.994098) (xy 72.859391 -155.049274)
			(xy 72.8599 -155.07716) (xy 72.859391 -155.105046) (xy 72.851271 -155.160222) (xy 72.835203 -155.213629)
			(xy 72.811531 -155.264126) (xy 72.780758 -155.310639) (xy 72.743541 -155.352176) (xy 72.700673 -155.387851)
			(xy 72.653067 -155.416905) (xy 72.601738 -155.438717) (xy 72.547781 -155.452823) (xy 72.492344 -155.458923)
			(xy 72.43661 -155.456886) (xy 72.381767 -155.446756) (xy 72.328983 -155.428749) (xy 72.279383 -155.403248)
			(xy 72.234025 -155.370797) (xy 72.193876 -155.332088) (xy 72.15979 -155.287945) (xy 72.132494 -155.23931)
			(xy 72.112571 -155.187219) (xy 72.100445 -155.132782) (xy 72.096374 -155.07716) (xy 29.4005 -155.07716)
			(xy 29.4005 -156.470598) (xy 57.477306 -156.470598) (xy 57.481193 -156.416248) (xy 57.492776 -156.363004)
			(xy 57.511819 -156.311951) (xy 57.537933 -156.264127) (xy 57.570588 -156.220507) (xy 57.609118 -156.181979)
			(xy 57.65274 -156.149326) (xy 57.700564 -156.123213) (xy 57.751618 -156.104172) (xy 57.804862 -156.092591)
			(xy 57.859212 -156.088706) (xy 57.913562 -156.092595) (xy 57.966805 -156.104179) (xy 58.017858 -156.123223)
			(xy 58.065681 -156.149339) (xy 58.087768 -156.165296) (xy 58.10678 -156.178892) (xy 58.148663 -156.199624)
			(xy 58.193631 -156.21235) (xy 58.240168 -156.21664) (xy 58.286705 -156.21235) (xy 58.331673 -156.199624)
			(xy 58.373556 -156.178892) (xy 58.392568 -156.165296) (xy 58.414653 -156.149328) (xy 58.462481 -156.123202)
			(xy 58.513541 -156.104148) (xy 58.566792 -156.092556) (xy 58.621151 -156.088661) (xy 58.675512 -156.092542)
			(xy 58.728766 -156.104121) (xy 58.77983 -156.123161) (xy 58.827665 -156.149275) (xy 58.871296 -156.181932)
			(xy 58.909835 -156.220466) (xy 58.942497 -156.264092) (xy 58.968618 -156.311923) (xy 58.987665 -156.362985)
			(xy 58.99925 -156.416238) (xy 59.003139 -156.470598) (xy 59.363999 -156.470598) (xy 59.367886 -156.416246)
			(xy 59.37947 -156.363001) (xy 59.398513 -156.311946) (xy 59.424629 -156.264121) (xy 59.457285 -156.2205)
			(xy 59.495816 -156.181971) (xy 59.539439 -156.149317) (xy 59.587266 -156.123204) (xy 59.638321 -156.104164)
			(xy 59.691567 -156.092583) (xy 59.745919 -156.088699) (xy 59.800271 -156.092589) (xy 59.853515 -156.104175)
			(xy 59.904569 -156.12322) (xy 59.952393 -156.149338) (xy 59.97448 -156.165296) (xy 59.993492 -156.178892)
			(xy 60.035375 -156.199624) (xy 60.080343 -156.21235) (xy 60.12688 -156.21664) (xy 60.173417 -156.21235)
			(xy 60.218385 -156.199624) (xy 60.260268 -156.178892) (xy 60.27928 -156.165296) (xy 60.301365 -156.149329)
			(xy 60.349192 -156.123205) (xy 60.40025 -156.104153) (xy 60.453501 -156.092562) (xy 60.507858 -156.088668)
			(xy 60.562217 -156.09255) (xy 60.615469 -156.104129) (xy 60.666532 -156.12317) (xy 60.714365 -156.149284)
			(xy 60.757994 -156.18194) (xy 60.796531 -156.220473) (xy 60.829192 -156.264098) (xy 60.855312 -156.311928)
			(xy 60.874358 -156.362988) (xy 60.885943 -156.41624) (xy 60.889832 -156.470598) (xy 61.604973 -156.470598)
			(xy 61.608862 -156.41624) (xy 61.620447 -156.362989) (xy 61.639493 -156.31193) (xy 61.665612 -156.264101)
			(xy 61.698273 -156.220476) (xy 61.73681 -156.181943) (xy 61.780439 -156.149288) (xy 61.828271 -156.123174)
			(xy 61.879333 -156.104134) (xy 61.932585 -156.092555) (xy 61.986943 -156.088673) (xy 62.0413 -156.092568)
			(xy 62.094549 -156.104158) (xy 62.145607 -156.12321) (xy 62.193434 -156.149334) (xy 62.215522 -156.165296)
			(xy 62.234534 -156.178892) (xy 62.276417 -156.199624) (xy 62.321385 -156.21235) (xy 62.367922 -156.21664)
			(xy 62.414459 -156.21235) (xy 62.459427 -156.199624) (xy 62.50131 -156.178892) (xy 62.520322 -156.165296)
			(xy 62.542406 -156.149333) (xy 62.59023 -156.123215) (xy 62.641285 -156.104169) (xy 62.69453 -156.092583)
			(xy 62.748882 -156.088693) (xy 62.803235 -156.092578) (xy 62.856481 -156.104159) (xy 62.907537 -156.1232)
			(xy 62.955364 -156.149313) (xy 62.998987 -156.181967) (xy 63.03752 -156.220497) (xy 63.070176 -156.264119)
			(xy 63.096292 -156.311944) (xy 63.115335 -156.362999) (xy 63.126919 -156.416245) (xy 63.130807 -156.470598)
			(xy 63.508983 -156.470598) (xy 63.512871 -156.416242) (xy 63.524456 -156.362994) (xy 63.543501 -156.311936)
			(xy 63.569619 -156.264108) (xy 63.602277 -156.220485) (xy 63.640812 -156.181954) (xy 63.684439 -156.149299)
			(xy 63.732269 -156.123186) (xy 63.783329 -156.104145) (xy 63.836578 -156.092566) (xy 63.890934 -156.088683)
			(xy 63.945289 -156.092576) (xy 63.998536 -156.104165) (xy 64.049593 -156.123214) (xy 64.097418 -156.149336)
			(xy 64.119506 -156.165296) (xy 64.138518 -156.178892) (xy 64.180401 -156.199624) (xy 64.225369 -156.21235)
			(xy 64.271906 -156.21664) (xy 64.318443 -156.21235) (xy 64.363411 -156.199624) (xy 64.405294 -156.178892)
			(xy 64.424306 -156.165296) (xy 64.44639 -156.149331) (xy 64.494216 -156.123211) (xy 64.545272 -156.104163)
			(xy 64.598519 -156.092575) (xy 64.652873 -156.088684) (xy 64.707228 -156.092568) (xy 64.760477 -156.104148)
			(xy 64.811535 -156.123188) (xy 64.859364 -156.149302) (xy 64.90299 -156.181957) (xy 64.941524 -156.220488)
			(xy 64.974182 -156.264111) (xy 65.000299 -156.311938) (xy 65.019344 -156.362995) (xy 65.030928 -156.416243)
			(xy 65.034816 -156.470598) (xy 65.030929 -156.524952) (xy 65.019345 -156.5782) (xy 65.000301 -156.629258)
			(xy 64.974185 -156.677085) (xy 64.941527 -156.720709) (xy 64.902994 -156.75924) (xy 64.859368 -156.791895)
			(xy 64.81154 -156.81801) (xy 64.760481 -156.837051) (xy 64.707233 -156.848632) (xy 64.652878 -156.852516)
			(xy 64.598523 -156.848625) (xy 64.545276 -156.837038) (xy 64.49422 -156.817991) (xy 64.446394 -156.791871)
			(xy 64.424306 -156.775912) (xy 64.405294 -156.762316) (xy 64.363411 -156.741584) (xy 64.318443 -156.728858)
			(xy 64.271906 -156.724568) (xy 64.225369 -156.728858) (xy 64.180401 -156.741584) (xy 64.138518 -156.762316)
			(xy 64.119506 -156.775912) (xy 64.097414 -156.791867) (xy 64.049588 -156.817988) (xy 63.998532 -156.837037)
			(xy 63.945284 -156.848625) (xy 63.890929 -156.852517) (xy 63.836573 -156.848633) (xy 63.783324 -156.837053)
			(xy 63.732265 -156.818012) (xy 63.684435 -156.791898) (xy 63.640809 -156.759243) (xy 63.602274 -156.720711)
			(xy 63.569616 -156.677087) (xy 63.543499 -156.62926) (xy 63.524454 -156.578202) (xy 63.512871 -156.524953)
			(xy 63.508983 -156.470598) (xy 63.130807 -156.470598) (xy 63.126919 -156.52495) (xy 63.115337 -156.578196)
			(xy 63.096294 -156.629251) (xy 63.070178 -156.677077) (xy 63.037523 -156.720699) (xy 62.998991 -156.75923)
			(xy 62.955368 -156.791884) (xy 62.907542 -156.817998) (xy 62.856486 -156.83704) (xy 62.803239 -156.848621)
			(xy 62.748887 -156.852507) (xy 62.694535 -156.848617) (xy 62.641289 -156.837032) (xy 62.590234 -156.817987)
			(xy 62.54241 -156.79187) (xy 62.520322 -156.775912) (xy 62.50131 -156.762316) (xy 62.459427 -156.741584)
			(xy 62.414459 -156.728858) (xy 62.367922 -156.724568) (xy 62.321385 -156.728858) (xy 62.276417 -156.741584)
			(xy 62.234534 -156.762316) (xy 62.215522 -156.775912) (xy 62.19343 -156.791868) (xy 62.145603 -156.817992)
			(xy 62.094545 -156.837043) (xy 62.041295 -156.848633) (xy 61.986938 -156.852527) (xy 61.93258 -156.848644)
			(xy 61.879328 -156.837064) (xy 61.828267 -156.818024) (xy 61.780435 -156.79191) (xy 61.736806 -156.759254)
			(xy 61.69827 -156.720721) (xy 61.66561 -156.677095) (xy 61.639491 -156.629266) (xy 61.620446 -156.578206)
			(xy 61.608861 -156.524955) (xy 61.604973 -156.470598) (xy 60.889832 -156.470598) (xy 60.885944 -156.524956)
			(xy 60.874359 -156.578207) (xy 60.855314 -156.629268) (xy 60.829195 -156.677098) (xy 60.796535 -156.720724)
			(xy 60.757998 -156.759257) (xy 60.714369 -156.791914) (xy 60.666536 -156.818028) (xy 60.615474 -156.837069)
			(xy 60.562221 -156.848649) (xy 60.507863 -156.852532) (xy 60.453505 -156.848638) (xy 60.400255 -156.837048)
			(xy 60.349196 -156.817997) (xy 60.301369 -156.791874) (xy 60.27928 -156.775912) (xy 60.260268 -156.762316)
			(xy 60.218385 -156.741584) (xy 60.173417 -156.728858) (xy 60.12688 -156.724568) (xy 60.080343 -156.728858)
			(xy 60.035375 -156.741584) (xy 59.993492 -156.762316) (xy 59.97448 -156.775912) (xy 59.952389 -156.791865)
			(xy 59.904565 -156.817982) (xy 59.853511 -156.837027) (xy 59.800266 -156.848612) (xy 59.745914 -156.852501)
			(xy 59.691562 -156.848616) (xy 59.638317 -156.837035) (xy 59.587261 -156.817994) (xy 59.539435 -156.79188)
			(xy 59.495813 -156.759226) (xy 59.457282 -156.720696) (xy 59.424626 -156.677075) (xy 59.398511 -156.629249)
			(xy 59.379469 -156.578195) (xy 59.367886 -156.524949) (xy 59.363999 -156.470598) (xy 59.003139 -156.470598)
			(xy 58.999251 -156.524957) (xy 58.987666 -156.57821) (xy 58.96862 -156.629272) (xy 58.9425 -156.677104)
			(xy 58.909838 -156.720731) (xy 58.8713 -156.759265) (xy 58.827669 -156.791922) (xy 58.779835 -156.818037)
			(xy 58.728771 -156.837078) (xy 58.675516 -156.848657) (xy 58.621156 -156.852539) (xy 58.566797 -156.848644)
			(xy 58.513545 -156.837053) (xy 58.462485 -156.818) (xy 58.414657 -156.791875) (xy 58.392568 -156.775912)
			(xy 58.373556 -156.762316) (xy 58.331673 -156.741584) (xy 58.286705 -156.728858) (xy 58.240168 -156.724568)
			(xy 58.193631 -156.728858) (xy 58.148663 -156.741584) (xy 58.10678 -156.762316) (xy 58.087768 -156.775912)
			(xy 58.065677 -156.791864) (xy 58.017854 -156.817979) (xy 57.966801 -156.837022) (xy 57.913557 -156.848606)
			(xy 57.859207 -156.852494) (xy 57.804857 -156.848608) (xy 57.751613 -156.837026) (xy 57.70056 -156.817985)
			(xy 57.652736 -156.791872) (xy 57.609115 -156.759218) (xy 57.570585 -156.720689) (xy 57.537931 -156.677069)
			(xy 57.511817 -156.629245) (xy 57.492775 -156.578191) (xy 57.481193 -156.524948) (xy 57.477306 -156.470598)
			(xy 29.4005 -156.470598) (xy 29.4005 -158.361084) (xy 57.477323 -158.361084) (xy 57.481213 -158.306737)
			(xy 57.492797 -158.253496) (xy 57.51184 -158.202446) (xy 57.537955 -158.154626) (xy 57.57061 -158.111009)
			(xy 57.60914 -158.072483) (xy 57.65276 -158.039833) (xy 57.700583 -158.013723) (xy 57.751636 -157.994685)
			(xy 57.804878 -157.983107) (xy 57.859225 -157.979223) (xy 57.913573 -157.983114) (xy 57.966813 -157.9947)
			(xy 58.017863 -158.013745) (xy 58.065682 -158.039861) (xy 58.087768 -158.055818) (xy 58.10678 -158.069414)
			(xy 58.148663 -158.090146) (xy 58.193631 -158.102872) (xy 58.240168 -158.107162) (xy 58.286705 -158.102872)
			(xy 58.331673 -158.090146) (xy 58.373556 -158.069414) (xy 58.392568 -158.055818) (xy 58.414633 -158.03982)
			(xy 58.462462 -158.013691) (xy 58.513523 -157.994635) (xy 58.566777 -157.983041) (xy 58.621138 -157.979143)
			(xy 58.675501 -157.983023) (xy 58.728758 -157.9946) (xy 58.779826 -158.01364) (xy 58.827663 -158.039753)
			(xy 58.871297 -158.07241) (xy 58.909839 -158.110944) (xy 58.942505 -158.154571) (xy 58.968628 -158.202404)
			(xy 58.987678 -158.253467) (xy 58.999266 -158.306722) (xy 59.003157 -158.361084) (xy 59.364016 -158.361084)
			(xy 59.367906 -158.306735) (xy 59.379491 -158.253493) (xy 59.398535 -158.202441) (xy 59.424651 -158.15462)
			(xy 59.457307 -158.111002) (xy 59.495838 -158.072475) (xy 59.53946 -158.039825) (xy 59.587285 -158.013715)
			(xy 59.638339 -157.994677) (xy 59.691583 -157.983099) (xy 59.745932 -157.979216) (xy 59.800281 -157.983108)
			(xy 59.853523 -157.994695) (xy 59.904574 -158.013742) (xy 59.952394 -158.03986) (xy 59.97448 -158.055818)
			(xy 59.993492 -158.069414) (xy 60.035375 -158.090146) (xy 60.080343 -158.102872) (xy 60.12688 -158.107162)
			(xy 60.173417 -158.102872) (xy 60.218385 -158.090146) (xy 60.260268 -158.069414) (xy 60.27928 -158.055818)
			(xy 60.301344 -158.039821) (xy 60.349173 -158.013694) (xy 60.400233 -157.99464) (xy 60.453485 -157.983047)
			(xy 60.507845 -157.979151) (xy 60.562206 -157.983031) (xy 60.615462 -157.994609) (xy 60.666527 -158.013648)
			(xy 60.714363 -158.039762) (xy 60.757996 -158.072418) (xy 60.796536 -158.110951) (xy 60.8292 -158.154577)
			(xy 60.855322 -158.202409) (xy 60.874371 -158.253471) (xy 60.885959 -158.306724) (xy 60.889849 -158.361084)
			(xy 61.604991 -158.361084) (xy 61.608881 -158.30673) (xy 61.620468 -158.253482) (xy 61.639515 -158.202425)
			(xy 61.665634 -158.154599) (xy 61.698295 -158.110977) (xy 61.736831 -158.072448) (xy 61.780459 -158.039795)
			(xy 61.82829 -158.013685) (xy 61.879351 -157.994647) (xy 61.932601 -157.983071) (xy 61.986956 -157.979191)
			(xy 62.041311 -157.983087) (xy 62.094557 -157.994679) (xy 62.145612 -158.013731) (xy 62.193435 -158.039856)
			(xy 62.215522 -158.055818) (xy 62.234534 -158.069414) (xy 62.276417 -158.090146) (xy 62.321385 -158.102872)
			(xy 62.367922 -158.107162) (xy 62.414459 -158.102872) (xy 62.459427 -158.090146) (xy 62.50131 -158.069414)
			(xy 62.520322 -158.055818) (xy 62.542385 -158.039825) (xy 62.590211 -158.013704) (xy 62.641267 -157.994656)
			(xy 62.694514 -157.983068) (xy 62.748869 -157.979176) (xy 62.803224 -157.983059) (xy 62.856473 -157.994638)
			(xy 62.907533 -158.013678) (xy 62.955362 -158.039791) (xy 62.998989 -158.072445) (xy 63.037524 -158.110976)
			(xy 63.070184 -158.154598) (xy 63.096302 -158.202425) (xy 63.115348 -158.253482) (xy 63.126934 -158.30673)
			(xy 63.130824 -158.361084) (xy 63.509001 -158.361084) (xy 63.512891 -158.306732) (xy 63.524476 -158.253486)
			(xy 63.543522 -158.202431) (xy 63.56964 -158.154607) (xy 63.602299 -158.110987) (xy 63.640834 -158.072458)
			(xy 63.68446 -158.039807) (xy 63.732288 -158.013696) (xy 63.783346 -157.994659) (xy 63.836594 -157.983082)
			(xy 63.890947 -157.979201) (xy 63.945299 -157.983095) (xy 63.998544 -157.994685) (xy 64.049597 -158.013735)
			(xy 64.09742 -158.039857) (xy 64.119506 -158.055818) (xy 64.138518 -158.069414) (xy 64.180401 -158.090146)
			(xy 64.225369 -158.102872) (xy 64.271906 -158.107162) (xy 64.318443 -158.102872) (xy 64.363411 -158.090146)
			(xy 64.405294 -158.069414) (xy 64.424306 -158.055818) (xy 64.44637 -158.039823) (xy 64.494196 -158.0137)
			(xy 64.545254 -157.99465) (xy 64.598503 -157.98306) (xy 64.65286 -157.979166) (xy 64.707217 -157.983048)
			(xy 64.760469 -157.994627) (xy 64.811531 -158.013667) (xy 64.859363 -158.03978) (xy 64.902991 -158.072435)
			(xy 64.941529 -158.110966) (xy 64.97419 -158.15459) (xy 65.00031 -158.202419) (xy 65.019357 -158.253478)
			(xy 65.030944 -158.306727) (xy 65.034834 -158.361084) (xy 65.030948 -158.415442) (xy 65.019366 -158.468692)
			(xy 65.000323 -158.519753) (xy 64.974207 -158.567583) (xy 64.966798 -158.57748) (xy 66.784121 -158.57748)
			(xy 66.788012 -158.523131) (xy 66.799597 -158.46989) (xy 66.818642 -158.418839) (xy 66.844758 -158.371018)
			(xy 66.877414 -158.327401) (xy 66.915946 -158.288876) (xy 66.959568 -158.256226) (xy 67.007392 -158.230117)
			(xy 67.058446 -158.21108) (xy 67.111689 -158.199503) (xy 67.166038 -158.195621) (xy 67.220386 -158.199514)
			(xy 67.273627 -158.211102) (xy 67.324677 -158.230149) (xy 67.372497 -158.256268) (xy 67.394582 -158.272226)
			(xy 67.413594 -158.285822) (xy 67.455477 -158.306554) (xy 67.500445 -158.31928) (xy 67.546982 -158.32357)
			(xy 67.593519 -158.31928) (xy 67.638487 -158.306554) (xy 67.68037 -158.285822) (xy 67.699382 -158.272226)
			(xy 67.721439 -158.256219) (xy 67.769267 -158.230091) (xy 67.820328 -158.211036) (xy 67.873581 -158.199442)
			(xy 67.927941 -158.195545) (xy 67.982303 -158.199425) (xy 68.035559 -158.211003) (xy 68.086626 -158.230042)
			(xy 68.134463 -158.256155) (xy 68.178096 -158.288811) (xy 68.216637 -158.327344) (xy 68.249302 -158.370971)
			(xy 68.275425 -158.418802) (xy 68.294475 -158.469865) (xy 68.306063 -158.523119) (xy 68.309955 -158.57748)
			(xy 68.306069 -158.631841) (xy 68.300961 -158.655325) (xy 69.733264 -158.655325) (xy 69.737148 -158.600969)
			(xy 69.748729 -158.547718) (xy 69.76777 -158.496658) (xy 69.793884 -158.448827) (xy 69.82654 -158.405199)
			(xy 69.865072 -158.366664) (xy 69.908696 -158.334004) (xy 69.956525 -158.307885) (xy 70.007583 -158.288839)
			(xy 70.060833 -158.277254) (xy 70.115189 -158.273364) (xy 70.169546 -158.27725) (xy 70.222796 -158.288833)
			(xy 70.273856 -158.307876) (xy 70.321685 -158.333992) (xy 70.343776 -158.34995) (xy 70.362788 -158.363546)
			(xy 70.404671 -158.384278) (xy 70.449639 -158.397004) (xy 70.496176 -158.401294) (xy 70.542713 -158.397004)
			(xy 70.587681 -158.384278) (xy 70.629564 -158.363546) (xy 70.648576 -158.34995) (xy 70.670704 -158.334045)
			(xy 70.718529 -158.307926) (xy 70.769584 -158.288879) (xy 70.82283 -158.277293) (xy 70.877184 -158.273403)
			(xy 70.931537 -158.277288) (xy 70.984784 -158.28887) (xy 71.035841 -158.307912) (xy 71.083668 -158.334027)
			(xy 71.127291 -158.366683) (xy 71.165823 -158.405215) (xy 71.198478 -158.448839) (xy 71.224592 -158.496667)
			(xy 71.243633 -158.547724) (xy 71.255213 -158.600972) (xy 71.259097 -158.655325) (xy 71.255206 -158.709678)
			(xy 71.243619 -158.762924) (xy 71.224571 -158.813979) (xy 71.198451 -158.861803) (xy 71.16579 -158.905423)
			(xy 71.127253 -158.94395) (xy 71.083626 -158.9766) (xy 71.035795 -159.002709) (xy 70.984736 -159.021744)
			(xy 70.931487 -159.033319) (xy 70.877133 -159.037197) (xy 70.82278 -159.0333) (xy 70.769536 -159.021707)
			(xy 70.718483 -159.002653) (xy 70.670662 -158.976528) (xy 70.648576 -158.960566) (xy 70.629564 -158.94697)
			(xy 70.587681 -158.926238) (xy 70.542713 -158.913512) (xy 70.496176 -158.909222) (xy 70.449639 -158.913512)
			(xy 70.404671 -158.926238) (xy 70.362788 -158.94697) (xy 70.343776 -158.960566) (xy 70.321728 -158.976581)
			(xy 70.273901 -159.002703) (xy 70.222844 -159.021753) (xy 70.169596 -159.033342) (xy 70.11524 -159.037236)
			(xy 70.060883 -159.033354) (xy 70.007632 -159.021775) (xy 69.956571 -159.002736) (xy 69.908739 -158.976623)
			(xy 69.86511 -158.943969) (xy 69.826573 -158.905439) (xy 69.793912 -158.861816) (xy 69.767791 -158.813988)
			(xy 69.748743 -158.76293) (xy 69.737156 -158.709681) (xy 69.733264 -158.655325) (xy 68.300961 -158.655325)
			(xy 68.294486 -158.685096) (xy 68.275442 -158.736161) (xy 68.249324 -158.783995) (xy 68.216664 -158.827625)
			(xy 68.178127 -158.866162) (xy 68.134497 -158.898823) (xy 68.086663 -158.924941) (xy 68.035599 -158.943986)
			(xy 67.982344 -158.955569) (xy 67.927982 -158.959455) (xy 67.873621 -158.955564) (xy 67.820367 -158.943976)
			(xy 67.769305 -158.924926) (xy 67.721473 -158.898803) (xy 67.699382 -158.882842) (xy 67.68037 -158.869246)
			(xy 67.638487 -158.848514) (xy 67.593519 -158.835788) (xy 67.546982 -158.831498) (xy 67.500445 -158.835788)
			(xy 67.455477 -158.848514) (xy 67.413594 -158.869246) (xy 67.394582 -158.882842) (xy 67.372462 -158.898755)
			(xy 67.32464 -158.924868) (xy 67.273588 -158.94391) (xy 67.220346 -158.955492) (xy 67.165997 -158.959379)
			(xy 67.111649 -158.955491) (xy 67.058407 -158.943908) (xy 67.007355 -158.924866) (xy 66.959533 -158.898752)
			(xy 66.915915 -158.866098) (xy 66.877387 -158.827568) (xy 66.844736 -158.783947) (xy 66.818625 -158.736124)
			(xy 66.799585 -158.685071) (xy 66.788006 -158.631828) (xy 66.784121 -158.57748) (xy 64.966798 -158.57748)
			(xy 64.941549 -158.61121) (xy 64.903015 -158.649745) (xy 64.859389 -158.682403) (xy 64.811559 -158.70852)
			(xy 64.760499 -158.727564) (xy 64.707248 -158.739147) (xy 64.652891 -158.743034) (xy 64.598534 -158.739145)
			(xy 64.545284 -158.727559) (xy 64.494225 -158.708513) (xy 64.446396 -158.682393) (xy 64.424306 -158.666434)
			(xy 64.405294 -158.652838) (xy 64.363411 -158.632106) (xy 64.318443 -158.61938) (xy 64.271906 -158.61509)
			(xy 64.225369 -158.61938) (xy 64.180401 -158.632106) (xy 64.138518 -158.652838) (xy 64.119506 -158.666434)
			(xy 64.097393 -158.682359) (xy 64.049569 -158.708478) (xy 63.998514 -158.727524) (xy 63.945268 -158.739109)
			(xy 63.890916 -158.742999) (xy 63.836563 -158.739114) (xy 63.783316 -158.727533) (xy 63.73226 -158.708491)
			(xy 63.684433 -158.682377) (xy 63.64081 -158.649721) (xy 63.602279 -158.61119) (xy 63.569624 -158.567567)
			(xy 63.543509 -158.51974) (xy 63.524468 -158.468684) (xy 63.512886 -158.415437) (xy 63.509001 -158.361084)
			(xy 63.130824 -158.361084) (xy 63.126939 -158.415439) (xy 63.115357 -158.468688) (xy 63.096315 -158.519747)
			(xy 63.0702 -158.567575) (xy 63.037545 -158.611201) (xy 62.999013 -158.649734) (xy 62.955389 -158.682392)
			(xy 62.907561 -158.708509) (xy 62.856503 -158.727553) (xy 62.803255 -158.739137) (xy 62.7489 -158.743024)
			(xy 62.694545 -158.739137) (xy 62.641297 -158.727553) (xy 62.590239 -158.708509) (xy 62.542412 -158.682392)
			(xy 62.520322 -158.666434) (xy 62.50131 -158.652838) (xy 62.459427 -158.632106) (xy 62.414459 -158.61938)
			(xy 62.367922 -158.61509) (xy 62.321385 -158.61938) (xy 62.276417 -158.632106) (xy 62.234534 -158.652838)
			(xy 62.215522 -158.666434) (xy 62.193409 -158.682361) (xy 62.145583 -158.708482) (xy 62.094527 -158.72753)
			(xy 62.04128 -158.739118) (xy 61.986925 -158.743009) (xy 61.93257 -158.739125) (xy 61.879321 -158.727544)
			(xy 61.828262 -158.708502) (xy 61.780433 -158.682388) (xy 61.736808 -158.649732) (xy 61.698274 -158.611199)
			(xy 61.665617 -158.567575) (xy 61.639502 -158.519747) (xy 61.620459 -158.468688) (xy 61.608877 -158.41544)
			(xy 61.604991 -158.361084) (xy 60.889849 -158.361084) (xy 60.885963 -158.415445) (xy 60.87438 -158.468699)
			(xy 60.855335 -158.519763) (xy 60.829217 -158.567596) (xy 60.796557 -158.611225) (xy 60.758019 -158.649762)
			(xy 60.714389 -158.682421) (xy 60.666556 -158.708539) (xy 60.615492 -158.727582) (xy 60.562237 -158.739165)
			(xy 60.507876 -158.743049) (xy 60.453516 -158.739158) (xy 60.400263 -158.727569) (xy 60.349201 -158.708519)
			(xy 60.301371 -158.682396) (xy 60.27928 -158.666434) (xy 60.260268 -158.652838) (xy 60.218385 -158.632106)
			(xy 60.173417 -158.61938) (xy 60.12688 -158.61509) (xy 60.080343 -158.61938) (xy 60.035375 -158.632106)
			(xy 59.993492 -158.652838) (xy 59.97448 -158.666434) (xy 59.952368 -158.682357) (xy 59.904545 -158.708471)
			(xy 59.853493 -158.727514) (xy 59.80025 -158.739096) (xy 59.745901 -158.742984) (xy 59.691552 -158.739097)
			(xy 59.638309 -158.727514) (xy 59.587257 -158.708472) (xy 59.539434 -158.682358) (xy 59.495814 -158.649704)
			(xy 59.457286 -158.611175) (xy 59.424634 -158.567554) (xy 59.398522 -158.51973) (xy 59.379482 -158.468677)
			(xy 59.367901 -158.415434) (xy 59.364016 -158.361084) (xy 59.003157 -158.361084) (xy 58.99927 -158.415447)
			(xy 58.987687 -158.468703) (xy 58.968641 -158.519768) (xy 58.942522 -158.567602) (xy 58.90986 -158.611232)
			(xy 58.871321 -158.64977) (xy 58.82769 -158.68243) (xy 58.779854 -158.708547) (xy 58.728788 -158.727591)
			(xy 58.675532 -158.739173) (xy 58.621169 -158.743057) (xy 58.566807 -158.739164) (xy 58.513553 -158.727574)
			(xy 58.46249 -158.708522) (xy 58.414659 -158.682397) (xy 58.392568 -158.666434) (xy 58.373556 -158.652838)
			(xy 58.331673 -158.632106) (xy 58.286705 -158.61938) (xy 58.240168 -158.61509) (xy 58.193631 -158.61938)
			(xy 58.148663 -158.632106) (xy 58.10678 -158.652838) (xy 58.087768 -158.666434) (xy 58.065656 -158.682356)
			(xy 58.017834 -158.708468) (xy 57.966783 -158.727509) (xy 57.913542 -158.73909) (xy 57.859194 -158.742977)
			(xy 57.804847 -158.739089) (xy 57.751606 -158.727506) (xy 57.700555 -158.708464) (xy 57.652734 -158.68235)
			(xy 57.609116 -158.649696) (xy 57.57059 -158.611168) (xy 57.537939 -158.567548) (xy 57.511828 -158.519725)
			(xy 57.492788 -158.468674) (xy 57.481208 -158.415432) (xy 57.477323 -158.361084) (xy 29.4005 -158.361084)
			(xy 29.4005 -160.402318) (xy 57.477279 -160.402318) (xy 57.481164 -160.347964) (xy 57.492745 -160.294716)
			(xy 57.511786 -160.243658) (xy 57.5379 -160.19583) (xy 57.570554 -160.152205) (xy 57.609085 -160.113671)
			(xy 57.652708 -160.081014) (xy 57.700534 -160.054897) (xy 57.751591 -160.035852) (xy 57.804838 -160.024267)
			(xy 57.859192 -160.020379) (xy 57.913546 -160.024265) (xy 57.966794 -160.035847) (xy 58.017851 -160.05489)
			(xy 58.065678 -160.081005) (xy 58.087768 -160.096962) (xy 58.10678 -160.110558) (xy 58.148663 -160.13129)
			(xy 58.193631 -160.144016) (xy 58.240168 -160.148306) (xy 58.286705 -160.144016) (xy 58.331673 -160.13129)
			(xy 58.373556 -160.110558) (xy 58.392568 -160.096962) (xy 58.414685 -160.08104) (xy 58.462511 -160.054918)
			(xy 58.513568 -160.035869) (xy 58.566816 -160.02428) (xy 58.621172 -160.020388) (xy 58.675528 -160.024272)
			(xy 58.728778 -160.035853) (xy 58.779838 -160.054894) (xy 58.827667 -160.081009) (xy 58.871294 -160.113666)
			(xy 58.909828 -160.152199) (xy 58.942485 -160.195824) (xy 58.968601 -160.243653) (xy 58.987644 -160.294712)
			(xy 58.999226 -160.347962) (xy 59.003112 -160.402318) (xy 59.363971 -160.402318) (xy 59.367857 -160.347962)
			(xy 59.379438 -160.294713) (xy 59.39848 -160.243653) (xy 59.424595 -160.195824) (xy 59.457251 -160.152198)
			(xy 59.495783 -160.113663) (xy 59.539408 -160.081005) (xy 59.587236 -160.054888) (xy 59.638294 -160.035843)
			(xy 59.691543 -160.024259) (xy 59.745899 -160.020371) (xy 59.800254 -160.024259) (xy 59.853503 -160.035843)
			(xy 59.904562 -160.054887) (xy 59.95239 -160.081004) (xy 59.97448 -160.096962) (xy 59.993492 -160.110558)
			(xy 60.035375 -160.13129) (xy 60.080343 -160.144016) (xy 60.12688 -160.148306) (xy 60.173417 -160.144016)
			(xy 60.218385 -160.13129) (xy 60.260268 -160.110558) (xy 60.27928 -160.096962) (xy 60.301397 -160.081041)
			(xy 60.349222 -160.054921) (xy 60.400278 -160.035873) (xy 60.453525 -160.024286) (xy 60.507879 -160.020396)
			(xy 60.562233 -160.02428) (xy 60.615481 -160.035861) (xy 60.666539 -160.054903) (xy 60.714367 -160.081018)
			(xy 60.757992 -160.113674) (xy 60.796524 -160.152206) (xy 60.82918 -160.19583) (xy 60.855296 -160.243658)
			(xy 60.874338 -160.294715) (xy 60.885919 -160.347964) (xy 60.889804 -160.402318) (xy 61.604946 -160.402318)
			(xy 61.608832 -160.347956) (xy 61.620415 -160.294701) (xy 61.63946 -160.243637) (xy 61.665578 -160.195803)
			(xy 61.698239 -160.152173) (xy 61.736777 -160.113636) (xy 61.780407 -160.080976) (xy 61.828241 -160.054858)
			(xy 61.879306 -160.035814) (xy 61.932561 -160.024231) (xy 61.986923 -160.020346) (xy 62.041284 -160.024238)
			(xy 62.094538 -160.035827) (xy 62.1456 -160.054877) (xy 62.193431 -160.081) (xy 62.215522 -160.096962)
			(xy 62.234534 -160.110558) (xy 62.276417 -160.13129) (xy 62.321385 -160.144016) (xy 62.367922 -160.148306)
			(xy 62.414459 -160.144016) (xy 62.459427 -160.13129) (xy 62.50131 -160.110558) (xy 62.520322 -160.096962)
			(xy 62.542438 -160.081044) (xy 62.59026 -160.054931) (xy 62.641312 -160.03589) (xy 62.694554 -160.024308)
			(xy 62.748902 -160.020421) (xy 62.803251 -160.024308) (xy 62.856493 -160.035891) (xy 62.907545 -160.054933)
			(xy 62.955366 -160.081047) (xy 62.998985 -160.113701) (xy 63.037512 -160.15223) (xy 63.070164 -160.195851)
			(xy 63.096275 -160.243674) (xy 63.115315 -160.294727) (xy 63.126895 -160.347969) (xy 63.130779 -160.402318)
			(xy 63.508956 -160.402318) (xy 63.512841 -160.347959) (xy 63.524424 -160.294706) (xy 63.543467 -160.243643)
			(xy 63.569585 -160.195811) (xy 63.602243 -160.152183) (xy 63.640779 -160.113646) (xy 63.684407 -160.080987)
			(xy 63.732239 -160.054869) (xy 63.783301 -160.035825) (xy 63.836554 -160.024242) (xy 63.890913 -160.020356)
			(xy 63.945272 -160.024246) (xy 63.998524 -160.035833) (xy 64.049585 -160.054881) (xy 64.097416 -160.081002)
			(xy 64.119506 -160.096962) (xy 64.138518 -160.110558) (xy 64.180401 -160.13129) (xy 64.225369 -160.144016)
			(xy 64.271906 -160.148306) (xy 64.318443 -160.144016) (xy 64.363411 -160.13129) (xy 64.405294 -160.110558)
			(xy 64.424306 -160.096962) (xy 64.446422 -160.081043) (xy 64.494245 -160.054927) (xy 64.545299 -160.035883)
			(xy 64.598543 -160.024299) (xy 64.652893 -160.020411) (xy 64.707244 -160.024298) (xy 64.760488 -160.03588)
			(xy 64.811542 -160.054922) (xy 64.859367 -160.081036) (xy 64.902988 -160.113691) (xy 64.941517 -160.152221)
			(xy 64.97417 -160.195843) (xy 65.000283 -160.243668) (xy 65.019324 -160.294722) (xy 65.030904 -160.347967)
			(xy 65.034789 -160.402318) (xy 65.030899 -160.456668) (xy 65.019313 -160.509912) (xy 65.000268 -160.560965)
			(xy 64.974151 -160.608787) (xy 64.941493 -160.652406) (xy 64.90296 -160.690933) (xy 64.859336 -160.723584)
			(xy 64.81151 -160.749693) (xy 64.760454 -160.76873) (xy 64.707208 -160.780308) (xy 64.652857 -160.784189)
			(xy 64.598507 -160.780295) (xy 64.545264 -160.768706) (xy 64.494213 -160.749658) (xy 64.446392 -160.723538)
			(xy 64.424306 -160.707578) (xy 64.405294 -160.693982) (xy 64.363411 -160.67325) (xy 64.318443 -160.660524)
			(xy 64.271906 -160.656234) (xy 64.225369 -160.660524) (xy 64.180401 -160.67325) (xy 64.138518 -160.693982)
			(xy 64.119506 -160.707578) (xy 64.097446 -160.723579) (xy 64.049618 -160.749704) (xy 63.998559 -160.768757)
			(xy 63.945308 -160.780349) (xy 63.890949 -160.784244) (xy 63.83659 -160.780363) (xy 63.783336 -160.768785)
			(xy 63.732272 -160.749746) (xy 63.684437 -160.723632) (xy 63.640806 -160.690977) (xy 63.602267 -160.652445)
			(xy 63.569604 -160.608819) (xy 63.543482 -160.56099) (xy 63.524434 -160.509929) (xy 63.512846 -160.456677)
			(xy 63.508956 -160.402318) (xy 63.130779 -160.402318) (xy 63.12689 -160.456666) (xy 63.115305 -160.509908)
			(xy 63.09626 -160.560959) (xy 63.070145 -160.608779) (xy 63.037489 -160.652397) (xy 62.998958 -160.690922)
			(xy 62.955336 -160.723572) (xy 62.907512 -160.749682) (xy 62.856458 -160.768719) (xy 62.803215 -160.780297)
			(xy 62.748866 -160.784179) (xy 62.694518 -160.780287) (xy 62.641277 -160.7687) (xy 62.590227 -160.749654)
			(xy 62.542407 -160.723536) (xy 62.520322 -160.707578) (xy 62.50131 -160.693982) (xy 62.459427 -160.67325)
			(xy 62.414459 -160.660524) (xy 62.367922 -160.656234) (xy 62.321385 -160.660524) (xy 62.276417 -160.67325)
			(xy 62.234534 -160.693982) (xy 62.215522 -160.707578) (xy 62.193461 -160.72358) (xy 62.145633 -160.749708)
			(xy 62.094572 -160.768763) (xy 62.041319 -160.780357) (xy 61.986959 -160.784254) (xy 61.932597 -160.780374)
			(xy 61.87934 -160.768796) (xy 61.828274 -160.749757) (xy 61.780437 -160.723644) (xy 61.736804 -160.690988)
			(xy 61.698263 -160.652454) (xy 61.665598 -160.608827) (xy 61.639475 -160.560996) (xy 61.620425 -160.509933)
			(xy 61.608837 -160.456679) (xy 61.604946 -160.402318) (xy 60.889804 -160.402318) (xy 60.885914 -160.456672)
			(xy 60.874328 -160.509919) (xy 60.855281 -160.560975) (xy 60.829161 -160.6088) (xy 60.796501 -160.652421)
			(xy 60.757964 -160.69095) (xy 60.714337 -160.723602) (xy 60.666506 -160.749712) (xy 60.615447 -160.768749)
			(xy 60.562197 -160.780325) (xy 60.507843 -160.784204) (xy 60.453489 -160.780309) (xy 60.400243 -160.768716)
			(xy 60.349189 -160.749664) (xy 60.301366 -160.72354) (xy 60.27928 -160.707578) (xy 60.260268 -160.693982)
			(xy 60.218385 -160.67325) (xy 60.173417 -160.660524) (xy 60.12688 -160.656234) (xy 60.080343 -160.660524)
			(xy 60.035375 -160.67325) (xy 59.993492 -160.693982) (xy 59.97448 -160.707578) (xy 59.95242 -160.723577)
			(xy 59.904595 -160.749698) (xy 59.853538 -160.768747) (xy 59.80029 -160.780336) (xy 59.745935 -160.784229)
			(xy 59.691579 -160.780346) (xy 59.638329 -160.768767) (xy 59.587269 -160.749727) (xy 59.539438 -160.723614)
			(xy 59.49581 -160.69096) (xy 59.457274 -160.652429) (xy 59.424614 -160.608806) (xy 59.398495 -160.560979)
			(xy 59.379448 -160.509922) (xy 59.367862 -160.456673) (xy 59.363971 -160.402318) (xy 59.003112 -160.402318)
			(xy 58.999221 -160.456674) (xy 58.987634 -160.509922) (xy 58.968586 -160.56098) (xy 58.942466 -160.608806)
			(xy 58.909804 -160.652428) (xy 58.871266 -160.690958) (xy 58.827637 -160.72361) (xy 58.779805 -160.749721)
			(xy 58.728743 -160.768757) (xy 58.675492 -160.780333) (xy 58.621136 -160.784212) (xy 58.566781 -160.780315)
			(xy 58.513533 -160.768721) (xy 58.462478 -160.749667) (xy 58.414655 -160.723541) (xy 58.392568 -160.707578)
			(xy 58.373556 -160.693982) (xy 58.331673 -160.67325) (xy 58.286705 -160.660524) (xy 58.240168 -160.656234)
			(xy 58.193631 -160.660524) (xy 58.148663 -160.67325) (xy 58.10678 -160.693982) (xy 58.087768 -160.707578)
			(xy 58.065709 -160.723576) (xy 58.017884 -160.749695) (xy 57.966828 -160.768743) (xy 57.913582 -160.78033)
			(xy 57.859228 -160.784221) (xy 57.804874 -160.780338) (xy 57.751625 -160.768758) (xy 57.700567 -160.749718)
			(xy 57.652738 -160.723606) (xy 57.609112 -160.690952) (xy 57.570578 -160.652422) (xy 57.537919 -160.6088)
			(xy 57.511801 -160.560975) (xy 57.492755 -160.509919) (xy 57.481169 -160.456672) (xy 57.477279 -160.402318)
			(xy 29.4005 -160.402318) (xy 29.4005 -162.312102) (xy 57.477299 -162.312102) (xy 57.481186 -162.257751)
			(xy 57.492769 -162.204507) (xy 57.511811 -162.153453) (xy 57.537925 -162.105628) (xy 57.57058 -162.062007)
			(xy 57.609111 -162.023477) (xy 57.652732 -161.990823) (xy 57.700557 -161.964709) (xy 57.751612 -161.945668)
			(xy 57.804856 -161.934086) (xy 57.859207 -161.930199) (xy 57.913558 -161.934088) (xy 57.966803 -161.945672)
			(xy 58.017856 -161.964715) (xy 58.06568 -161.990831) (xy 58.087768 -162.006788) (xy 58.10678 -162.020384)
			(xy 58.148663 -162.041116) (xy 58.193631 -162.053842) (xy 58.240168 -162.058132) (xy 58.286705 -162.053842)
			(xy 58.331673 -162.041116) (xy 58.373556 -162.020384) (xy 58.392568 -162.006788) (xy 58.414661 -161.990831)
			(xy 58.462488 -161.964705) (xy 58.513547 -161.945653) (xy 58.566798 -161.934062) (xy 58.621156 -161.930168)
			(xy 58.675515 -161.934049) (xy 58.728769 -161.945628) (xy 58.779832 -161.964669) (xy 58.827666 -161.990783)
			(xy 58.871295 -162.02344) (xy 58.909833 -162.061973) (xy 58.942494 -162.1056) (xy 58.968614 -162.15343)
			(xy 58.98766 -162.204491) (xy 58.999245 -162.257744) (xy 59.003133 -162.312102) (xy 59.363992 -162.312102)
			(xy 59.367879 -162.25775) (xy 59.379462 -162.204504) (xy 59.398505 -162.153448) (xy 59.424621 -162.105622)
			(xy 59.457277 -162.062) (xy 59.495809 -162.023469) (xy 59.539432 -161.990814) (xy 59.587259 -161.9647)
			(xy 59.638315 -161.945659) (xy 59.691561 -161.934078) (xy 59.745914 -161.930192) (xy 59.800267 -161.934082)
			(xy 59.853512 -161.945667) (xy 59.904567 -161.964712) (xy 59.952392 -161.99083) (xy 59.97448 -162.006788)
			(xy 59.993492 -162.020384) (xy 60.035375 -162.041116) (xy 60.080343 -162.053842) (xy 60.12688 -162.058132)
			(xy 60.173417 -162.053842) (xy 60.218385 -162.041116) (xy 60.260268 -162.020384) (xy 60.27928 -162.006788)
			(xy 60.301372 -161.990832) (xy 60.349199 -161.964708) (xy 60.400257 -161.945658) (xy 60.453506 -161.934068)
			(xy 60.507863 -161.930175) (xy 60.562221 -161.934057) (xy 60.615472 -161.945637) (xy 60.666534 -161.964678)
			(xy 60.714365 -161.990792) (xy 60.757993 -162.023448) (xy 60.79653 -162.06198) (xy 60.82919 -162.105606)
			(xy 60.855308 -162.153435) (xy 60.874353 -162.204495) (xy 60.885938 -162.257745) (xy 60.889825 -162.312102)
			(xy 61.604967 -162.312102) (xy 61.608855 -162.257744) (xy 61.620439 -162.204492) (xy 61.639485 -162.153431)
			(xy 61.665604 -162.105601) (xy 61.698265 -162.061975) (xy 61.736802 -162.023441) (xy 61.780431 -161.990785)
			(xy 61.828264 -161.96467) (xy 61.879327 -161.945629) (xy 61.932579 -161.93405) (xy 61.986938 -161.930167)
			(xy 62.041296 -161.934061) (xy 62.094547 -161.945651) (xy 62.145605 -161.964702) (xy 62.193433 -161.990826)
			(xy 62.215522 -162.006788) (xy 62.234534 -162.020384) (xy 62.276417 -162.041116) (xy 62.321385 -162.053842)
			(xy 62.367922 -162.058132) (xy 62.414459 -162.053842) (xy 62.459427 -162.041116) (xy 62.50131 -162.020384)
			(xy 62.520322 -162.006788) (xy 62.542413 -161.990835) (xy 62.590237 -161.964719) (xy 62.641291 -161.945674)
			(xy 62.694536 -161.934089) (xy 62.748887 -161.9302) (xy 62.803238 -161.934085) (xy 62.856484 -161.945667)
			(xy 62.907539 -161.964708) (xy 62.955365 -161.990821) (xy 62.998987 -162.023475) (xy 63.037518 -162.062005)
			(xy 63.070173 -162.105626) (xy 63.096288 -162.153451) (xy 63.11533 -162.204506) (xy 63.126913 -162.257751)
			(xy 63.1308 -162.312102) (xy 63.508977 -162.312102) (xy 63.512864 -162.257746) (xy 63.524448 -162.204497)
			(xy 63.543493 -162.153438) (xy 63.569611 -162.105609) (xy 63.602269 -162.061984) (xy 63.640805 -162.023452)
			(xy 63.684431 -161.990796) (xy 63.732262 -161.964682) (xy 63.783322 -161.945641) (xy 63.836573 -161.93406)
			(xy 63.890929 -161.930177) (xy 63.945285 -161.934069) (xy 63.998534 -161.945657) (xy 64.049591 -161.964706)
			(xy 64.097417 -161.990828) (xy 64.119506 -162.006788) (xy 64.138518 -162.020384) (xy 64.180401 -162.041116)
			(xy 64.225369 -162.053842) (xy 64.271906 -162.058132) (xy 64.318443 -162.053842) (xy 64.363411 -162.041116)
			(xy 64.405294 -162.020384) (xy 64.424306 -162.006788) (xy 64.446398 -161.990834) (xy 64.494223 -161.964715)
			(xy 64.545278 -161.945668) (xy 64.598524 -161.934081) (xy 64.652878 -161.93019) (xy 64.707232 -161.934075)
			(xy 64.760479 -161.945655) (xy 64.811537 -161.964696) (xy 64.859365 -161.99081) (xy 64.902989 -162.023465)
			(xy 64.941522 -162.061996) (xy 64.974179 -162.105618) (xy 65.000296 -162.153445) (xy 65.019339 -162.204502)
			(xy 65.030922 -162.257749) (xy 65.03481 -162.312102) (xy 65.030922 -162.366456) (xy 65.019338 -162.419703)
			(xy 65.000294 -162.470759) (xy 64.974177 -162.518586) (xy 64.941519 -162.562208) (xy 64.902986 -162.600738)
			(xy 64.859361 -162.633393) (xy 64.811533 -162.659506) (xy 64.760475 -162.678546) (xy 64.707227 -162.690126)
			(xy 64.652873 -162.69401) (xy 64.59852 -162.690118) (xy 64.545273 -162.678531) (xy 64.494218 -162.659483)
			(xy 64.446394 -162.633363) (xy 64.424306 -162.617404) (xy 64.405294 -162.603808) (xy 64.363411 -162.583076)
			(xy 64.318443 -162.57035) (xy 64.271906 -162.56606) (xy 64.225369 -162.57035) (xy 64.180401 -162.583076)
			(xy 64.138518 -162.603808) (xy 64.119506 -162.617404) (xy 64.097421 -162.63337) (xy 64.049595 -162.659492)
			(xy 63.998538 -162.678542) (xy 63.94529 -162.690131) (xy 63.890934 -162.694023) (xy 63.836577 -162.69014)
			(xy 63.783327 -162.678561) (xy 63.732266 -162.65952) (xy 63.684436 -162.633406) (xy 63.640808 -162.600751)
			(xy 63.602273 -162.562219) (xy 63.569613 -162.518595) (xy 63.543495 -162.470767) (xy 63.52445 -162.419708)
			(xy 63.512865 -162.366459) (xy 63.508977 -162.312102) (xy 63.1308 -162.312102) (xy 63.126912 -162.366454)
			(xy 63.115329 -162.419699) (xy 63.096286 -162.470753) (xy 63.07017 -162.518578) (xy 63.037515 -162.562199)
			(xy 62.998983 -162.600728) (xy 62.95536 -162.633381) (xy 62.907535 -162.659494) (xy 62.856479 -162.678535)
			(xy 62.803234 -162.690115) (xy 62.748882 -162.694) (xy 62.694531 -162.69011) (xy 62.641286 -162.678525)
			(xy 62.590233 -162.659479) (xy 62.542409 -162.633362) (xy 62.520322 -162.617404) (xy 62.50131 -162.603808)
			(xy 62.459427 -162.583076) (xy 62.414459 -162.57035) (xy 62.367922 -162.56606) (xy 62.321385 -162.57035)
			(xy 62.276417 -162.583076) (xy 62.234534 -162.603808) (xy 62.215522 -162.617404) (xy 62.193437 -162.633371)
			(xy 62.14561 -162.659496) (xy 62.094551 -162.678548) (xy 62.041301 -162.690139) (xy 61.986943 -162.694033)
			(xy 61.932584 -162.690151) (xy 61.879331 -162.678572) (xy 61.828268 -162.659532) (xy 61.780435 -162.633418)
			(xy 61.736806 -162.600762) (xy 61.698268 -162.562229) (xy 61.665607 -162.518603) (xy 61.639487 -162.470773)
			(xy 61.620441 -162.419712) (xy 61.608855 -162.366461) (xy 61.604967 -162.312102) (xy 60.889825 -162.312102)
			(xy 60.885937 -162.36646) (xy 60.874352 -162.41971) (xy 60.855306 -162.470769) (xy 60.829187 -162.518598)
			(xy 60.796527 -162.562223) (xy 60.75799 -162.600756) (xy 60.714361 -162.633411) (xy 60.666529 -162.659524)
			(xy 60.615468 -162.678564) (xy 60.562216 -162.690143) (xy 60.507858 -162.694025) (xy 60.453501 -162.690131)
			(xy 60.400252 -162.678541) (xy 60.349195 -162.65949) (xy 60.301368 -162.633366) (xy 60.27928 -162.617404)
			(xy 60.260268 -162.603808) (xy 60.218385 -162.583076) (xy 60.173417 -162.57035) (xy 60.12688 -162.56606)
			(xy 60.080343 -162.57035) (xy 60.035375 -162.583076) (xy 59.993492 -162.603808) (xy 59.97448 -162.617404)
			(xy 59.952396 -162.633368) (xy 59.904572 -162.659486) (xy 59.853517 -162.678532) (xy 59.800272 -162.690118)
			(xy 59.745919 -162.694008) (xy 59.691566 -162.690123) (xy 59.63832 -162.678542) (xy 59.587263 -162.659502)
			(xy 59.539436 -162.633388) (xy 59.495812 -162.600734) (xy 59.45728 -162.562204) (xy 59.424623 -162.518582)
			(xy 59.398507 -162.470757) (xy 59.379464 -162.419701) (xy 59.36788 -162.366455) (xy 59.363992 -162.312102)
			(xy 59.003133 -162.312102) (xy 58.999244 -162.366461) (xy 58.987659 -162.419713) (xy 58.968612 -162.470774)
			(xy 58.942492 -162.518604) (xy 58.90983 -162.56223) (xy 58.871292 -162.600763) (xy 58.827662 -162.633419)
			(xy 58.779828 -162.659533) (xy 58.728764 -162.678573) (xy 58.675511 -162.690151) (xy 58.621151 -162.694032)
			(xy 58.566793 -162.690137) (xy 58.513542 -162.678545) (xy 58.462484 -162.659493) (xy 58.414657 -162.633367)
			(xy 58.392568 -162.617404) (xy 58.373556 -162.603808) (xy 58.331673 -162.583076) (xy 58.286705 -162.57035)
			(xy 58.240168 -162.56606) (xy 58.193631 -162.57035) (xy 58.148663 -162.583076) (xy 58.10678 -162.603808)
			(xy 58.087768 -162.617404) (xy 58.065684 -162.633367) (xy 58.017861 -162.659483) (xy 57.966807 -162.678527)
			(xy 57.913563 -162.690111) (xy 57.859212 -162.694001) (xy 57.804861 -162.690115) (xy 57.751616 -162.678534)
			(xy 57.700561 -162.659493) (xy 57.652736 -162.63338) (xy 57.609114 -162.600726) (xy 57.570583 -162.562197)
			(xy 57.537928 -162.518576) (xy 57.511813 -162.470752) (xy 57.49277 -162.419698) (xy 57.481187 -162.366453)
			(xy 57.477299 -162.312102) (xy 29.4005 -162.312102) (xy 29.4005 -173.178385) (xy 47.641754 -173.178385)
			(xy 47.641754 -173.097275) (xy 47.649704 -173.016556) (xy 47.665527 -172.937005) (xy 47.689072 -172.859389)
			(xy 47.720111 -172.784453) (xy 47.758346 -172.712921) (xy 47.803408 -172.645481) (xy 47.854863 -172.582782)
			(xy 47.912216 -172.525429) (xy 47.974915 -172.473974) (xy 48.042355 -172.428912) (xy 48.113887 -172.390677)
			(xy 48.188823 -172.359638) (xy 48.266439 -172.336093) (xy 48.34599 -172.32027) (xy 48.426709 -172.31232)
			(xy 48.507819 -172.31232) (xy 48.588538 -172.32027) (xy 48.668089 -172.336093) (xy 48.745705 -172.359638)
			(xy 48.820641 -172.390677) (xy 48.892173 -172.428912) (xy 48.959613 -172.473974) (xy 49.022312 -172.525429)
			(xy 49.079665 -172.582782) (xy 49.13112 -172.645481) (xy 49.176182 -172.712921) (xy 49.214417 -172.784453)
			(xy 49.245456 -172.859389) (xy 49.269001 -172.937005) (xy 49.284824 -173.016556) (xy 49.292774 -173.097275)
			(xy 49.293272 -173.13783) (xy 49.292774 -173.178385) (xy 51.141874 -173.178385) (xy 51.141874 -173.097275)
			(xy 51.149824 -173.016556) (xy 51.165647 -172.937005) (xy 51.189192 -172.859389) (xy 51.220231 -172.784453)
			(xy 51.258466 -172.712921) (xy 51.303528 -172.645481) (xy 51.354983 -172.582782) (xy 51.412336 -172.525429)
			(xy 51.475035 -172.473974) (xy 51.542475 -172.428912) (xy 51.614007 -172.390677) (xy 51.688943 -172.359638)
			(xy 51.766559 -172.336093) (xy 51.84611 -172.32027) (xy 51.926829 -172.31232) (xy 52.007939 -172.31232)
			(xy 52.088658 -172.32027) (xy 52.168209 -172.336093) (xy 52.245825 -172.359638) (xy 52.320761 -172.390677)
			(xy 52.392293 -172.428912) (xy 52.459733 -172.473974) (xy 52.522432 -172.525429) (xy 52.579785 -172.582782)
			(xy 52.63124 -172.645481) (xy 52.676302 -172.712921) (xy 52.714537 -172.784453) (xy 52.745576 -172.859389)
			(xy 52.769121 -172.937005) (xy 52.784944 -173.016556) (xy 52.792894 -173.097275) (xy 52.793392 -173.13783)
			(xy 52.792894 -173.178385) (xy 52.784944 -173.259104) (xy 52.769121 -173.338655) (xy 52.745576 -173.416271)
			(xy 52.714537 -173.491207) (xy 52.676302 -173.562739) (xy 52.63124 -173.630179) (xy 52.579785 -173.692878)
			(xy 52.522432 -173.750231) (xy 52.459733 -173.801686) (xy 52.392293 -173.846748) (xy 52.320761 -173.884983)
			(xy 52.245825 -173.916022) (xy 52.168209 -173.939567) (xy 52.088658 -173.95539) (xy 52.007939 -173.96334)
			(xy 51.926829 -173.96334) (xy 51.84611 -173.95539) (xy 51.766559 -173.939567) (xy 51.688943 -173.916022)
			(xy 51.614007 -173.884983) (xy 51.542475 -173.846748) (xy 51.475035 -173.801686) (xy 51.412336 -173.750231)
			(xy 51.354983 -173.692878) (xy 51.303528 -173.630179) (xy 51.258466 -173.562739) (xy 51.220231 -173.491207)
			(xy 51.189192 -173.416271) (xy 51.165647 -173.338655) (xy 51.149824 -173.259104) (xy 51.141874 -173.178385)
			(xy 49.292774 -173.178385) (xy 49.284824 -173.259104) (xy 49.269001 -173.338655) (xy 49.245456 -173.416271)
			(xy 49.214417 -173.491207) (xy 49.176182 -173.562739) (xy 49.13112 -173.630179) (xy 49.079665 -173.692878)
			(xy 49.022312 -173.750231) (xy 48.959613 -173.801686) (xy 48.892173 -173.846748) (xy 48.820641 -173.884983)
			(xy 48.745705 -173.916022) (xy 48.668089 -173.939567) (xy 48.588538 -173.95539) (xy 48.507819 -173.96334)
			(xy 48.426709 -173.96334) (xy 48.34599 -173.95539) (xy 48.266439 -173.939567) (xy 48.188823 -173.916022)
			(xy 48.113887 -173.884983) (xy 48.042355 -173.846748) (xy 47.974915 -173.801686) (xy 47.912216 -173.750231)
			(xy 47.854863 -173.692878) (xy 47.803408 -173.630179) (xy 47.758346 -173.562739) (xy 47.720111 -173.491207)
			(xy 47.689072 -173.416271) (xy 47.665527 -173.338655) (xy 47.649704 -173.259104) (xy 47.641754 -173.178385)
			(xy 29.4005 -173.178385) (xy 29.4005 -174.500286) (xy 28.84932 -175.051466) (xy 28.834317 -175.067076)
			(xy 28.809327 -175.102427) (xy 28.790695 -175.141505) (xy 28.778963 -175.183177) (xy 28.77447 -175.226236)
			(xy 28.777346 -175.269432) (xy 28.787509 -175.311515) (xy 28.804663 -175.351264) (xy 28.828312 -175.387526)
			(xy 28.857769 -175.419251) (xy 28.87472 -175.43272) (xy 58.286396 -175.43272) (xy 76.800456 -156.91866)
			(xy 76.800456 -147.21459) (xy 80.97901 -143.036036) (xy 81.31937 -143.036036) (xy 82.6262 -141.72946)
			(xy 82.637554 -141.717314) (xy 82.654155 -141.688519) (xy 82.662759 -141.656416) (xy 82.663284 -141.639798)
			(xy 82.663284 -137.121646) (xy 83.420204 -136.364472) (xy 83.420204 -115.435126) (xy 81.158588 -113.17351)
			(xy 81.158588 -107.592114) (xy 81.155794 -107.578906) (xy 81.150633 -107.552608) (xy 81.146867 -107.499149)
			(xy 81.150619 -107.445689) (xy 81.155794 -107.419394) (xy 81.158588 -107.406186) (xy 81.158588 -102.275894)
			(xy 82.9056 -100.529136) (xy 82.916952 -100.516989) (xy 82.933547 -100.488194) (xy 82.942145 -100.456091)
			(xy 82.942684 -100.439474) (xy 82.942684 -94.678246) (xy 85.877908 -91.742768) (xy 92.023184 -91.742768)
			(xy 93.465396 -93.185234) (xy 93.465396 -94.259654) (xy 93.413072 -94.311978) (xy 93.413072 -94.38259)
			(xy 92.302838 -95.492824) (xy 92.232226 -95.492824) (xy 92.165678 -95.559372) (xy 92.154213 -95.571503)
			(xy 92.137495 -95.600381) (xy 92.128839 -95.632607) (xy 92.128837 -95.665976) (xy 92.137488 -95.698203)
			(xy 92.154202 -95.727084) (xy 92.165678 -95.739204) (xy 92.18676 -95.760286) (xy 92.215208 -95.769684)
			(xy 92.252831 -95.782824) (xy 92.325136 -95.816339) (xy 92.393242 -95.857724) (xy 92.456298 -95.90646)
			(xy 92.513513 -95.961938) (xy 92.564169 -96.023461) (xy 92.607634 -96.09026) (xy 92.643362 -96.161498)
			(xy 92.657676 -96.19869) (xy 92.669427 -96.231745) (xy 92.687124 -96.299636) (xy 92.698051 -96.368939)
			(xy 92.702102 -96.438981) (xy 92.699237 -96.509081) (xy 92.69476 -96.543876) (xy 92.689159 -96.580491)
			(xy 92.671342 -96.652392) (xy 92.6592 -96.687386) (xy 92.649887 -96.712336) (xy 92.628021 -96.760902)
			(xy 92.615512 -96.784414) (xy 92.611194 -96.792542) (xy 92.593364 -96.823498) (xy 92.552393 -96.882024)
			(xy 92.505757 -96.936144) (xy 92.453925 -96.985312) (xy 92.397421 -97.029029) (xy 92.367354 -97.04832)
			(xy 92.35396 -97.057253) (xy 92.331812 -97.080607) (xy 92.316216 -97.108761) (xy 92.308163 -97.139923)
			(xy 92.307664 -97.156016) (xy 92.307664 -97.16008) (xy 93.154506 -97.16008) (xy 93.158522 -97.04381)
			(xy 93.170549 -96.928095) (xy 93.190531 -96.813485) (xy 93.218373 -96.700526) (xy 93.253942 -96.589758)
			(xy 93.297068 -96.481707) (xy 93.347545 -96.376889) (xy 93.405134 -96.275804) (xy 93.46956 -96.178932)
			(xy 93.540515 -96.086736) (xy 93.617662 -95.999655) (xy 93.700633 -95.918104) (xy 93.789033 -95.842472)
			(xy 93.88244 -95.773118) (xy 93.980409 -95.710375) (xy 94.082473 -95.654539) (xy 94.188147 -95.605878)
			(xy 94.296926 -95.564624) (xy 94.408291 -95.530973) (xy 94.521714 -95.505085) (xy 94.636651 -95.487084)
			(xy 94.752557 -95.477055) (xy 94.868879 -95.475047) (xy 94.985062 -95.481069) (xy 95.100553 -95.495092)
			(xy 95.214801 -95.51705) (xy 95.327262 -95.546837) (xy 95.4374 -95.584312) (xy 95.54469 -95.629297)
			(xy 95.648621 -95.681576) (xy 95.748697 -95.740901) (xy 95.844443 -95.806989) (xy 95.9354 -95.879525)
			(xy 96.021136 -95.958164) (xy 96.101243 -96.04253) (xy 96.175339 -96.132222) (xy 96.243069 -96.226812)
			(xy 96.304113 -96.32585) (xy 96.358178 -96.428863) (xy 96.405008 -96.53536) (xy 96.444379 -96.644835)
			(xy 96.476103 -96.756765) (xy 96.500029 -96.870617) (xy 96.516043 -96.985849) (xy 96.52407 -97.101911)
			(xy 96.524572 -97.16008) (xy 96.52407 -97.218249) (xy 96.516043 -97.334311) (xy 96.500029 -97.449543)
			(xy 96.476103 -97.563395) (xy 96.444379 -97.675325) (xy 96.405008 -97.7848) (xy 96.358178 -97.891297)
			(xy 96.304113 -97.99431) (xy 96.243069 -98.093348) (xy 96.175339 -98.187938) (xy 96.101243 -98.27763)
			(xy 96.021136 -98.361996) (xy 95.9354 -98.440635) (xy 95.844443 -98.513171) (xy 95.748697 -98.579259)
			(xy 95.648621 -98.638584) (xy 95.54469 -98.690863) (xy 95.4374 -98.735848) (xy 95.327262 -98.773323)
			(xy 95.214801 -98.80311) (xy 95.100553 -98.825068) (xy 94.985062 -98.839091) (xy 94.868879 -98.845113)
			(xy 94.752557 -98.843105) (xy 94.636651 -98.833076) (xy 94.521714 -98.815075) (xy 94.408291 -98.789187)
			(xy 94.296926 -98.755536) (xy 94.188147 -98.714282) (xy 94.082473 -98.665621) (xy 93.980409 -98.609785)
			(xy 93.88244 -98.547042) (xy 93.789033 -98.477688) (xy 93.700633 -98.402056) (xy 93.617662 -98.320505)
			(xy 93.540515 -98.233424) (xy 93.46956 -98.141228) (xy 93.405134 -98.044356) (xy 93.347545 -97.943271)
			(xy 93.297068 -97.838453) (xy 93.253942 -97.730402) (xy 93.218373 -97.619634) (xy 93.190531 -97.506675)
			(xy 93.170549 -97.392065) (xy 93.158522 -97.27635) (xy 93.154506 -97.16008) (xy 92.307664 -97.16008)
			(xy 92.307664 -97.679002) (xy 91.647772 -98.339148) (xy 91.099132 -98.887788) (xy 90.482166 -98.887788)
			(xy 87.320882 -102.049072) (xy 92.029532 -102.049072) (xy 92.033603 -101.99345) (xy 92.045729 -101.939013)
			(xy 92.065652 -101.886922) (xy 92.092948 -101.838287) (xy 92.127034 -101.794144) (xy 92.167183 -101.755435)
			(xy 92.212541 -101.722984) (xy 92.262141 -101.697483) (xy 92.314925 -101.679476) (xy 92.369768 -101.669346)
			(xy 92.425502 -101.667309) (xy 92.480939 -101.673409) (xy 92.534896 -101.687515) (xy 92.586225 -101.709327)
			(xy 92.633831 -101.738381) (xy 92.676699 -101.774056) (xy 92.713916 -101.815593) (xy 92.744689 -101.862106)
			(xy 92.768361 -101.912603) (xy 92.77228 -101.925628) (xy 94.75165 -101.925628) (xy 94.755721 -101.870006)
			(xy 94.767847 -101.815569) (xy 94.78777 -101.763478) (xy 94.815066 -101.714843) (xy 94.849152 -101.6707)
			(xy 94.889301 -101.631991) (xy 94.934659 -101.59954) (xy 94.984259 -101.574039) (xy 95.037043 -101.556032)
			(xy 95.091886 -101.545902) (xy 95.14762 -101.543865) (xy 95.203057 -101.549965) (xy 95.257014 -101.564071)
			(xy 95.308343 -101.585883) (xy 95.355949 -101.614937) (xy 95.398817 -101.650612) (xy 95.436034 -101.692149)
			(xy 95.466807 -101.738662) (xy 95.490479 -101.789159) (xy 95.506547 -101.842566) (xy 95.514667 -101.897742)
			(xy 95.515176 -101.925628) (xy 95.514667 -101.953514) (xy 95.506547 -102.00869) (xy 95.490479 -102.062097)
			(xy 95.466807 -102.112594) (xy 95.436034 -102.159107) (xy 95.398817 -102.200644) (xy 95.355949 -102.236319)
			(xy 95.308343 -102.265373) (xy 95.257014 -102.287185) (xy 95.203057 -102.301291) (xy 95.14762 -102.307391)
			(xy 95.091886 -102.305354) (xy 95.037043 -102.295224) (xy 94.984259 -102.277217) (xy 94.934659 -102.251716)
			(xy 94.889301 -102.219265) (xy 94.849152 -102.180556) (xy 94.815066 -102.136413) (xy 94.78777 -102.087778)
			(xy 94.767847 -102.035687) (xy 94.755721 -101.98125) (xy 94.75165 -101.925628) (xy 92.77228 -101.925628)
			(xy 92.784429 -101.96601) (xy 92.792549 -102.021186) (xy 92.793058 -102.049072) (xy 92.792549 -102.076958)
			(xy 92.784429 -102.132134) (xy 92.768361 -102.185541) (xy 92.744689 -102.236038) (xy 92.713916 -102.282551)
			(xy 92.676699 -102.324088) (xy 92.633831 -102.359763) (xy 92.586225 -102.388817) (xy 92.534896 -102.410629)
			(xy 92.480939 -102.424735) (xy 92.425502 -102.430835) (xy 92.369768 -102.428798) (xy 92.314925 -102.418668)
			(xy 92.262141 -102.400661) (xy 92.212541 -102.37516) (xy 92.167183 -102.342709) (xy 92.127034 -102.304)
			(xy 92.092948 -102.259857) (xy 92.065652 -102.211222) (xy 92.045729 -102.159131) (xy 92.033603 -102.104694)
			(xy 92.029532 -102.049072) (xy 87.320882 -102.049072) (xy 87.268304 -102.10165) (xy 87.259414 -102.133146)
			(xy 87.251329 -102.159512) (xy 87.228624 -102.209769) (xy 87.198923 -102.256234) (xy 87.162843 -102.297941)
			(xy 87.121136 -102.334021) (xy 87.074671 -102.363723) (xy 87.024415 -102.386429) (xy 86.998048 -102.394512)
			(xy 86.966552 -102.403402) (xy 86.675722 -102.694232) (xy 93.32036 -102.694232) (xy 93.324431 -102.63861)
			(xy 93.336557 -102.584173) (xy 93.35648 -102.532082) (xy 93.383776 -102.483447) (xy 93.417862 -102.439304)
			(xy 93.458011 -102.400595) (xy 93.503369 -102.368144) (xy 93.552969 -102.342643) (xy 93.605753 -102.324636)
			(xy 93.660596 -102.314506) (xy 93.71633 -102.312469) (xy 93.771767 -102.318569) (xy 93.825724 -102.332675)
			(xy 93.877053 -102.354487) (xy 93.924659 -102.383541) (xy 93.967527 -102.419216) (xy 94.004744 -102.460753)
			(xy 94.035517 -102.507266) (xy 94.059189 -102.557763) (xy 94.075257 -102.61117) (xy 94.083377 -102.666346)
			(xy 94.083886 -102.694232) (xy 94.083377 -102.722118) (xy 94.075257 -102.777294) (xy 94.059189 -102.830701)
			(xy 94.035517 -102.881198) (xy 94.004744 -102.927711) (xy 93.967527 -102.969248) (xy 93.924659 -103.004923)
			(xy 93.877053 -103.033977) (xy 93.825724 -103.055789) (xy 93.771767 -103.069895) (xy 93.71633 -103.075995)
			(xy 93.660596 -103.073958) (xy 93.605753 -103.063828) (xy 93.552969 -103.045821) (xy 93.503369 -103.02032)
			(xy 93.458011 -102.987869) (xy 93.417862 -102.94916) (xy 93.383776 -102.905017) (xy 93.35648 -102.856382)
			(xy 93.336557 -102.804291) (xy 93.324431 -102.749854) (xy 93.32036 -102.694232) (xy 86.675722 -102.694232)
			(xy 86.028276 -103.341678) (xy 94.72625 -103.341678) (xy 94.730321 -103.286056) (xy 94.742447 -103.231619)
			(xy 94.76237 -103.179528) (xy 94.789666 -103.130893) (xy 94.823752 -103.08675) (xy 94.863901 -103.048041)
			(xy 94.909259 -103.01559) (xy 94.958859 -102.990089) (xy 95.011643 -102.972082) (xy 95.066486 -102.961952)
			(xy 95.12222 -102.959915) (xy 95.177657 -102.966015) (xy 95.231614 -102.980121) (xy 95.282943 -103.001933)
			(xy 95.330549 -103.030987) (xy 95.373417 -103.066662) (xy 95.410634 -103.108199) (xy 95.441407 -103.154712)
			(xy 95.465079 -103.205209) (xy 95.481147 -103.258616) (xy 95.489267 -103.313792) (xy 95.489776 -103.341678)
			(xy 95.489267 -103.369564) (xy 95.481147 -103.42474) (xy 95.465079 -103.478147) (xy 95.441407 -103.528644)
			(xy 95.410634 -103.575157) (xy 95.373417 -103.616694) (xy 95.330549 -103.652369) (xy 95.282943 -103.681423)
			(xy 95.231614 -103.703235) (xy 95.177657 -103.717341) (xy 95.12222 -103.723441) (xy 95.066486 -103.721404)
			(xy 95.011643 -103.711274) (xy 94.958859 -103.693267) (xy 94.909259 -103.667766) (xy 94.863901 -103.635315)
			(xy 94.823752 -103.596606) (xy 94.789666 -103.552463) (xy 94.76237 -103.503828) (xy 94.742447 -103.451737)
			(xy 94.730321 -103.3973) (xy 94.72625 -103.341678) (xy 86.028276 -103.341678) (xy 85.111844 -104.25811)
			(xy 85.111844 -108.909866) (xy 86.877404 -108.909866) (xy 86.881424 -108.719215) (xy 86.893478 -108.528902)
			(xy 86.913544 -108.339267) (xy 86.941587 -108.150646) (xy 86.977556 -107.963376) (xy 87.021388 -107.777788)
			(xy 87.073005 -107.594213) (xy 87.132315 -107.412977) (xy 87.199213 -107.234402) (xy 87.273579 -107.058807)
			(xy 87.355281 -106.886502) (xy 87.444175 -106.717795) (xy 87.540101 -106.552985) (xy 87.64289 -106.392366)
			(xy 87.752359 -106.236223) (xy 87.868313 -106.084834) (xy 87.990547 -105.938467) (xy 88.118841 -105.797383)
			(xy 88.252969 -105.661834) (xy 88.392693 -105.532059) (xy 88.537763 -105.408289) (xy 88.687921 -105.290746)
			(xy 88.842902 -105.179637) (xy 89.002429 -105.07516) (xy 89.166218 -104.977501) (xy 89.333978 -104.886834)
			(xy 89.505412 -104.80332) (xy 89.680214 -104.727107) (xy 89.858073 -104.658331) (xy 90.038674 -104.597113)
			(xy 90.221694 -104.543564) (xy 90.40681 -104.497778) (xy 90.593691 -104.459836) (xy 90.782006 -104.429807)
			(xy 90.971419 -104.407742) (xy 91.161593 -104.393683) (xy 91.352192 -104.387653) (xy 91.542875 -104.389663)
			(xy 91.733304 -104.39971) (xy 91.92314 -104.417776) (xy 92.112046 -104.443829) (xy 92.299685 -104.477822)
			(xy 92.485725 -104.519695) (xy 92.669834 -104.569374) (xy 92.851685 -104.62677) (xy 93.030955 -104.691781)
			(xy 93.207325 -104.764292) (xy 93.380481 -104.844173) (xy 93.550116 -104.931283) (xy 93.715928 -105.025467)
			(xy 93.877622 -105.126558) (xy 94.03491 -105.234374) (xy 94.187513 -105.348726) (xy 94.335161 -105.469409)
			(xy 94.477589 -105.59621) (xy 94.614545 -105.728901) (xy 94.745786 -105.867249) (xy 94.871078 -106.011006)
			(xy 94.990198 -106.159917) (xy 95.102934 -106.313718) (xy 95.209087 -106.472134) (xy 95.308467 -106.634885)
			(xy 95.400897 -106.80168) (xy 95.486214 -106.972224) (xy 95.564266 -107.146212) (xy 95.634913 -107.323337)
			(xy 95.698031 -107.503282) (xy 95.753507 -107.685728) (xy 95.801242 -107.870351) (xy 95.841152 -108.056821)
			(xy 95.873165 -108.244809) (xy 95.897225 -108.433979) (xy 95.913288 -108.623995) (xy 95.921327 -108.814519)
			(xy 95.92183 -108.909866) (xy 95.921327 -109.005213) (xy 95.913288 -109.195737) (xy 95.897225 -109.385753)
			(xy 95.873165 -109.574923) (xy 95.841152 -109.762911) (xy 95.801242 -109.949381) (xy 95.753507 -110.134004)
			(xy 95.698031 -110.31645) (xy 95.634913 -110.496395) (xy 95.564266 -110.67352) (xy 95.486214 -110.847508)
			(xy 95.400897 -111.018052) (xy 95.308467 -111.184847) (xy 95.209087 -111.347598) (xy 95.102934 -111.506014)
			(xy 94.990198 -111.659815) (xy 94.871078 -111.808726) (xy 94.745786 -111.952483) (xy 94.614545 -112.090831)
			(xy 94.477589 -112.223522) (xy 94.335161 -112.350323) (xy 94.187513 -112.471006) (xy 94.03491 -112.585358)
			(xy 93.877622 -112.693174) (xy 93.715928 -112.794265) (xy 93.550116 -112.888449) (xy 93.380481 -112.975559)
			(xy 93.207325 -113.05544) (xy 93.030955 -113.127951) (xy 92.851685 -113.192962) (xy 92.669834 -113.250358)
			(xy 92.485725 -113.300037) (xy 92.299685 -113.34191) (xy 92.112046 -113.375903) (xy 91.92314 -113.401956)
			(xy 91.733304 -113.420022) (xy 91.542875 -113.430069) (xy 91.352192 -113.432079) (xy 91.161593 -113.426049)
			(xy 90.971419 -113.41199) (xy 90.782006 -113.389925) (xy 90.593691 -113.359896) (xy 90.40681 -113.321954)
			(xy 90.221694 -113.276168) (xy 90.038674 -113.222619) (xy 89.858073 -113.161401) (xy 89.680214 -113.092625)
			(xy 89.505412 -113.016412) (xy 89.333978 -112.932898) (xy 89.166218 -112.842231) (xy 89.002429 -112.744572)
			(xy 88.842902 -112.640095) (xy 88.687921 -112.528986) (xy 88.537763 -112.411443) (xy 88.392693 -112.287673)
			(xy 88.252969 -112.157898) (xy 88.118841 -112.022349) (xy 87.990547 -111.881265) (xy 87.868313 -111.734898)
			(xy 87.752359 -111.583509) (xy 87.64289 -111.427366) (xy 87.540101 -111.266747) (xy 87.444175 -111.101937)
			(xy 87.355281 -110.93323) (xy 87.273579 -110.760925) (xy 87.199213 -110.58533) (xy 87.132315 -110.406755)
			(xy 87.073005 -110.225519) (xy 87.021388 -110.041944) (xy 86.977556 -109.856356) (xy 86.941587 -109.669086)
			(xy 86.913544 -109.480465) (xy 86.893478 -109.29083) (xy 86.881424 -109.100517) (xy 86.877404 -108.909866)
			(xy 85.111844 -108.909866) (xy 85.111844 -113.743232) (xy 85.812376 -114.443764) (xy 85.812376 -137.355834)
			(xy 85.092286 -138.075924) (xy 85.081422 -138.087348) (xy 85.065177 -138.114352) (xy 85.056094 -138.14453)
			(xy 85.054948 -138.160252) (xy 85.054948 -138.739118) (xy 85.057406 -138.762207) (xy 85.069624 -138.806997)
			(xy 85.089764 -138.848828) (xy 85.117158 -138.886312) (xy 85.150896 -138.918206) (xy 85.18986 -138.943451)
			(xy 85.232756 -138.961209) (xy 85.278162 -138.970892) (xy 85.324572 -138.972178) (xy 85.370444 -138.965025)
			(xy 85.392514 -138.957812) (xy 85.409532 -138.951716) (xy 85.446104 -138.939732) (xy 85.52118 -138.922787)
			(xy 85.597647 -138.914043) (xy 85.67461 -138.913602) (xy 85.751171 -138.92147) (xy 85.826436 -138.937554)
			(xy 85.899526 -138.961667) (xy 85.969587 -138.993526) (xy 86.0358 -139.032761) (xy 86.097393 -139.078912)
			(xy 86.153645 -139.13144) (xy 86.2039 -139.189732) (xy 86.24757 -139.253108) (xy 86.266274 -139.286742)
			(xy 86.280498 -139.314428) (xy 86.291632 -139.335126) (xy 86.320324 -139.372345) (xy 86.35537 -139.403655)
			(xy 86.395574 -139.427988) (xy 86.439567 -139.444515) (xy 86.485848 -139.452673) (xy 86.53284 -139.452182)
			(xy 86.578941 -139.443061) (xy 86.62258 -139.42562) (xy 86.662268 -139.400453) (xy 86.679786 -139.384786)
			(xy 86.719156 -139.345416) (xy 86.75751 -139.307316) (xy 86.810088 -139.307316) (xy 86.884256 -139.233148)
			(xy 86.884256 -139.180316) (xy 86.883829 -139.165611) (xy 86.877076 -139.136986) (xy 86.863947 -139.110668)
			(xy 86.845141 -139.088055) (xy 86.821657 -139.070349) (xy 86.794743 -139.05849) (xy 86.78037 -139.055348)
			(xy 86.743456 -139.048009) (xy 86.67131 -139.026564) (xy 86.601827 -138.997631) (xy 86.535783 -138.961531)
			(xy 86.473915 -138.918668) (xy 86.416912 -138.869519) (xy 86.365409 -138.814633) (xy 86.319982 -138.754622)
			(xy 86.281137 -138.690154) (xy 86.249308 -138.62195) (xy 86.224848 -138.550769) (xy 86.208032 -138.477406)
			(xy 86.199045 -138.402678) (xy 86.19799 -138.327419) (xy 86.204877 -138.252469) (xy 86.21963 -138.178663)
			(xy 86.242084 -138.106825) (xy 86.271989 -138.037754) (xy 86.309011 -137.972223) (xy 86.352738 -137.910962)
			(xy 86.402681 -137.854653) (xy 86.458284 -137.803925) (xy 86.518926 -137.759344) (xy 86.583932 -137.721407)
			(xy 86.652576 -137.690537) (xy 86.724093 -137.667078) (xy 86.797685 -137.651291) (xy 86.872531 -137.643354)
			(xy 86.947797 -137.643354) (xy 87.022643 -137.651291) (xy 87.096235 -137.667078) (xy 87.167752 -137.690537)
			(xy 87.236396 -137.721407) (xy 87.301402 -137.759344) (xy 87.362044 -137.803925) (xy 87.417647 -137.854653)
			(xy 87.46759 -137.910962) (xy 87.511317 -137.972223) (xy 87.548339 -138.037754) (xy 87.578244 -138.106825)
			(xy 87.600698 -138.178663) (xy 87.615451 -138.252469) (xy 87.622338 -138.327419) (xy 87.621283 -138.402678)
			(xy 87.612296 -138.477406) (xy 87.59548 -138.550769) (xy 87.57102 -138.62195) (xy 87.539191 -138.690154)
			(xy 87.500346 -138.754622) (xy 87.454919 -138.814633) (xy 87.403416 -138.869519) (xy 87.346413 -138.918668)
			(xy 87.284545 -138.961531) (xy 87.218501 -138.997631) (xy 87.149018 -139.026564) (xy 87.076872 -139.048009)
			(xy 87.039958 -139.055348) (xy 87.025569 -139.058434) (xy 86.998637 -139.070277) (xy 86.975143 -139.087986)
			(xy 86.956342 -139.110616) (xy 86.943239 -139.136958) (xy 86.936534 -139.165605) (xy 86.936072 -139.180316)
			(xy 86.936617 -139.196964) (xy 86.945237 -139.229126) (xy 86.961886 -139.257961) (xy 86.985429 -139.281507)
			(xy 87.014263 -139.298158) (xy 87.046424 -139.306781) (xy 87.063072 -139.307316) (xy 87.469218 -139.307316)
			(xy 87.485312 -139.306842) (xy 87.516475 -139.298781) (xy 87.544627 -139.283175) (xy 87.567977 -139.26102)
			(xy 87.576914 -139.247626) (xy 87.598257 -139.214519) (xy 87.647162 -139.152765) (xy 87.702586 -139.096787)
			(xy 87.76385 -139.04727) (xy 87.830206 -139.004819) (xy 87.900843 -138.969953) (xy 87.974898 -138.943097)
			(xy 88.051464 -138.924581) (xy 88.129606 -138.91463) (xy 88.20837 -138.913366) (xy 88.286791 -138.920805)
			(xy 88.325452 -138.928348) (xy 88.363421 -138.936782) (xy 88.437388 -138.960841) (xy 88.50829 -138.992824)
			(xy 88.57528 -139.032351) (xy 88.637559 -139.078949) (xy 88.66632 -139.105132) (xy 88.691702 -139.129413)
			(xy 88.738067 -139.182182) (xy 88.779002 -139.239267) (xy 88.814108 -139.30011) (xy 88.843043 -139.364119)
			(xy 88.865524 -139.430669) (xy 88.873838 -139.464796) (xy 88.878234 -139.481314) (xy 88.894505 -139.511359)
			(xy 88.918163 -139.536011) (xy 88.947513 -139.553505) (xy 88.980452 -139.562585) (xy 88.997536 -139.563094)
			(xy 89.050368 -139.563094) (xy 89.124536 -139.488926) (xy 89.124536 -139.06119) (xy 89.124045 -139.045283)
			(xy 89.116174 -139.014457) (xy 89.100925 -138.986535) (xy 89.079244 -138.963252) (xy 89.066116 -138.954256)
			(xy 89.034918 -138.933695) (xy 88.976581 -138.887005) (xy 88.923456 -138.83446) (xy 88.876129 -138.776638)
			(xy 88.83512 -138.714175) (xy 88.800881 -138.64776) (xy 88.773789 -138.578123) (xy 88.754142 -138.506031)
			(xy 88.742156 -138.432278) (xy 88.737964 -138.357674) (xy 88.741611 -138.283042) (xy 88.753057 -138.209203)
			(xy 88.772176 -138.136969) (xy 88.798758 -138.067136) (xy 88.83251 -138.000472) (xy 88.873061 -137.937712)
			(xy 88.919964 -137.879545) (xy 88.972704 -137.826613) (xy 89.030698 -137.779497) (xy 89.09331 -137.738717)
			(xy 89.15985 -137.704721) (xy 89.229585 -137.677884) (xy 89.301749 -137.658501) (xy 89.375546 -137.646785)
			(xy 89.450164 -137.642865) (xy 89.524782 -137.646785) (xy 89.598579 -137.658501) (xy 89.670743 -137.677884)
			(xy 89.740478 -137.704721) (xy 89.807018 -137.738717) (xy 89.86963 -137.779497) (xy 89.927624 -137.826613)
			(xy 89.980364 -137.879545) (xy 90.027267 -137.937712) (xy 90.067818 -138.000472) (xy 90.10157 -138.067136)
			(xy 90.128152 -138.136969) (xy 90.147271 -138.209203) (xy 90.158717 -138.283042) (xy 90.162237 -138.35507)
			(xy 91.277951 -138.35507) (xy 91.281986 -138.279366) (xy 91.294045 -138.204521) (xy 91.313991 -138.13138)
			(xy 91.341598 -138.060775) (xy 91.376554 -137.993504) (xy 91.418462 -137.930329) (xy 91.466848 -137.871967)
			(xy 91.521164 -137.819079) (xy 91.580793 -137.772264) (xy 91.645061 -137.732052) (xy 91.713238 -137.6989)
			(xy 91.784554 -137.673182) (xy 91.858199 -137.65519) (xy 91.933339 -137.645128) (xy 92.009123 -137.643109)
			(xy 92.084693 -137.649158) (xy 92.159191 -137.663205) (xy 92.231774 -137.685091) (xy 92.30162 -137.714568)
			(xy 92.367937 -137.751303) (xy 92.429973 -137.794878) (xy 92.487026 -137.8448) (xy 92.53845 -137.900504)
			(xy 92.583661 -137.961359) (xy 92.622148 -138.026674) (xy 92.653474 -138.09571) (xy 92.677284 -138.167685)
			(xy 92.693309 -138.241783) (xy 92.701368 -138.317164) (xy 92.701872 -138.35507) (xy 92.701368 -138.392976)
			(xy 92.693309 -138.468357) (xy 92.677284 -138.542455) (xy 92.653474 -138.61443) (xy 92.622148 -138.683466)
			(xy 92.583661 -138.748781) (xy 92.53845 -138.809636) (xy 92.487026 -138.86534) (xy 92.429973 -138.915262)
			(xy 92.367937 -138.958837) (xy 92.30162 -138.995572) (xy 92.231774 -139.025049) (xy 92.159191 -139.046935)
			(xy 92.084693 -139.060982) (xy 92.009123 -139.067031) (xy 91.933339 -139.065012) (xy 91.858199 -139.05495)
			(xy 91.784554 -139.036958) (xy 91.713238 -139.01124) (xy 91.645061 -138.978088) (xy 91.580793 -138.937876)
			(xy 91.521164 -138.891061) (xy 91.466848 -138.838173) (xy 91.418462 -138.779811) (xy 91.376554 -138.716636)
			(xy 91.341598 -138.649365) (xy 91.313991 -138.57876) (xy 91.294045 -138.505619) (xy 91.281986 -138.430774)
			(xy 91.277951 -138.35507) (xy 90.162237 -138.35507) (xy 90.162364 -138.357674) (xy 90.158172 -138.432278)
			(xy 90.146186 -138.506031) (xy 90.126539 -138.578123) (xy 90.099447 -138.64776) (xy 90.065208 -138.714175)
			(xy 90.024199 -138.776638) (xy 89.976872 -138.83446) (xy 89.923747 -138.887005) (xy 89.86541 -138.933695)
			(xy 89.834212 -138.954256) (xy 89.821084 -138.963256) (xy 89.799387 -138.986528) (xy 89.784132 -139.01445)
			(xy 89.776271 -139.045281) (xy 89.775792 -139.06119) (xy 89.775792 -139.43584) (xy 89.776297 -139.452533)
			(xy 89.784967 -139.484774) (xy 89.801703 -139.513662) (xy 89.82536 -139.53722) (xy 89.854318 -139.553836)
			(xy 89.886594 -139.562372) (xy 89.91998 -139.562243) (xy 89.95219 -139.553459) (xy 89.981019 -139.536621)
			(xy 90.004494 -139.512881) (xy 90.021007 -139.483864) (xy 90.025728 -139.467844) (xy 90.02649 -139.464796)
			(xy 90.027252 -139.462002) (xy 90.02776 -139.460224) (xy 90.038212 -139.418991) (xy 90.067638 -139.339176)
			(xy 90.106377 -139.263444) (xy 90.129614 -139.227814) (xy 90.151564 -139.196087) (xy 90.2013 -139.137103)
			(xy 90.257122 -139.083845) (xy 90.318377 -139.036936) (xy 90.384347 -138.996927) (xy 90.454256 -138.964288)
			(xy 90.527286 -138.939401) (xy 90.602579 -138.922559) (xy 90.679251 -138.913959) (xy 90.756404 -138.913702)
			(xy 90.833133 -138.92179) (xy 90.908536 -138.93813) (xy 90.98173 -138.962529) (xy 91.051856 -138.994701)
			(xy 91.11809 -139.034269) (xy 91.14917 -139.057126) (xy 91.178083 -139.079557) (xy 91.231642 -139.129429)
			(xy 91.279802 -139.184531) (xy 91.322057 -139.244282) (xy 91.357961 -139.308052) (xy 91.387134 -139.375168)
			(xy 91.40927 -139.444923) (xy 91.424135 -139.516579) (xy 91.428316 -139.552934) (xy 91.431635 -139.590048)
			(xy 91.431457 -139.664566) (xy 91.423494 -139.738658) (xy 91.407834 -139.811512) (xy 91.38465 -139.882332)
			(xy 91.354193 -139.950342) (xy 91.316798 -140.014798) (xy 91.272874 -140.074994) (xy 91.222902 -140.130273)
			(xy 91.167428 -140.180029) (xy 91.10706 -140.223717) (xy 91.042458 -140.260859) (xy 90.97433 -140.291049)
			(xy 90.90342 -140.313957) (xy 90.830505 -140.329331) (xy 90.756383 -140.337004) (xy 90.681865 -140.336891)
			(xy 90.607766 -140.328994) (xy 90.534898 -140.313399) (xy 90.464058 -140.290277) (xy 90.396021 -140.259881)
			(xy 90.331532 -140.222543) (xy 90.271296 -140.178673) (xy 90.215973 -140.128749) (xy 90.166168 -140.07332)
			(xy 90.122427 -140.01299) (xy 90.085227 -139.948421) (xy 90.054977 -139.88032) (xy 90.043 -139.845034)
			(xy 90.033856 -139.81684) (xy 89.970102 -139.751308) (xy 89.95803 -139.739654) (xy 89.929166 -139.722567)
			(xy 89.896844 -139.713598) (xy 89.863302 -139.713366) (xy 89.83086 -139.721888) (xy 89.801762 -139.738574)
			(xy 89.789508 -139.750038) (xy 89.647014 -139.892278) (xy 89.635568 -139.912394) (xy 89.619379 -139.955748)
			(xy 89.611303 -140.001316) (xy 89.611605 -140.047592) (xy 89.620275 -140.093051) (xy 89.637027 -140.13619)
			(xy 89.661308 -140.175586) (xy 89.692317 -140.209938) (xy 89.72903 -140.238113) (xy 89.749376 -140.249148)
			(xy 89.782565 -140.265026) (xy 89.845786 -140.302667) (xy 89.904786 -140.34663) (xy 89.958935 -140.396445)
			(xy 90.007657 -140.451581) (xy 90.05043 -140.511449) (xy 90.086798 -140.57541) (xy 90.116373 -140.642783)
			(xy 90.13884 -140.712847) (xy 90.153958 -140.784854) (xy 90.161567 -140.858038) (xy 90.161576 -140.89507)
			(xy 91.277951 -140.89507) (xy 91.281986 -140.819366) (xy 91.294045 -140.744521) (xy 91.313991 -140.67138)
			(xy 91.341598 -140.600775) (xy 91.376554 -140.533504) (xy 91.418462 -140.470329) (xy 91.466848 -140.411967)
			(xy 91.521164 -140.359079) (xy 91.580793 -140.312264) (xy 91.645061 -140.272052) (xy 91.713238 -140.2389)
			(xy 91.784554 -140.213182) (xy 91.858199 -140.19519) (xy 91.933339 -140.185128) (xy 92.009123 -140.183109)
			(xy 92.084693 -140.189158) (xy 92.159191 -140.203205) (xy 92.231774 -140.225091) (xy 92.30162 -140.254568)
			(xy 92.367937 -140.291303) (xy 92.429973 -140.334878) (xy 92.487026 -140.3848) (xy 92.53845 -140.440504)
			(xy 92.583661 -140.501359) (xy 92.622148 -140.566674) (xy 92.653474 -140.63571) (xy 92.677284 -140.707685)
			(xy 92.693309 -140.781783) (xy 92.701368 -140.857164) (xy 92.701872 -140.89507) (xy 92.701368 -140.932976)
			(xy 92.693309 -141.008357) (xy 92.677284 -141.082455) (xy 92.653474 -141.15443) (xy 92.622148 -141.223466)
			(xy 92.583661 -141.288781) (xy 92.53845 -141.349636) (xy 92.487026 -141.40534) (xy 92.429973 -141.455262)
			(xy 92.367937 -141.498837) (xy 92.30162 -141.535572) (xy 92.231774 -141.565049) (xy 92.159191 -141.586935)
			(xy 92.084693 -141.600982) (xy 92.009123 -141.607031) (xy 91.933339 -141.605012) (xy 91.858199 -141.59495)
			(xy 91.784554 -141.576958) (xy 91.713238 -141.55124) (xy 91.645061 -141.518088) (xy 91.580793 -141.477876)
			(xy 91.521164 -141.431061) (xy 91.466848 -141.378173) (xy 91.418462 -141.319811) (xy 91.376554 -141.256636)
			(xy 91.341598 -141.189365) (xy 91.313991 -141.11876) (xy 91.294045 -141.045619) (xy 91.281986 -140.970774)
			(xy 91.277951 -140.89507) (xy 90.161576 -140.89507) (xy 90.161585 -140.931616) (xy 90.154012 -141.004803)
			(xy 90.138928 -141.076818) (xy 90.116496 -141.146893) (xy 90.086953 -141.21428) (xy 90.050616 -141.278259)
			(xy 90.007872 -141.338148) (xy 89.983818 -141.365986) (xy 89.960875 -141.391371) (xy 89.910884 -141.438098)
			(xy 89.856643 -141.479816) (xy 89.827862 -141.49832) (xy 89.814467 -141.507252) (xy 89.792318 -141.530606)
			(xy 89.776721 -141.55876) (xy 89.768668 -141.589923) (xy 89.768172 -141.606016) (xy 89.768172 -141.670532)
			(xy 89.380822 -142.057882) (xy 89.369961 -142.069307) (xy 89.353724 -142.096312) (xy 89.344652 -142.12649)
			(xy 89.343484 -142.14221) (xy 89.343484 -142.16507) (xy 90.007951 -142.16507) (xy 90.011986 -142.089366)
			(xy 90.024045 -142.014521) (xy 90.043991 -141.94138) (xy 90.071598 -141.870775) (xy 90.106554 -141.803504)
			(xy 90.148462 -141.740329) (xy 90.196848 -141.681967) (xy 90.251164 -141.629079) (xy 90.310793 -141.582264)
			(xy 90.375061 -141.542052) (xy 90.443238 -141.5089) (xy 90.514554 -141.483182) (xy 90.588199 -141.46519)
			(xy 90.663339 -141.455128) (xy 90.739123 -141.453109) (xy 90.814693 -141.459158) (xy 90.889191 -141.473205)
			(xy 90.961774 -141.495091) (xy 91.03162 -141.524568) (xy 91.097937 -141.561303) (xy 91.159973 -141.604878)
			(xy 91.165918 -141.61008) (xy 93.15476 -141.61008) (xy 93.158776 -141.49381) (xy 93.170803 -141.378095)
			(xy 93.190785 -141.263485) (xy 93.218627 -141.150526) (xy 93.254196 -141.039758) (xy 93.297322 -140.931707)
			(xy 93.347799 -140.826889) (xy 93.405388 -140.725804) (xy 93.469814 -140.628932) (xy 93.540769 -140.536736)
			(xy 93.617916 -140.449655) (xy 93.700887 -140.368104) (xy 93.789287 -140.292472) (xy 93.882694 -140.223118)
			(xy 93.980663 -140.160375) (xy 94.082727 -140.104539) (xy 94.188401 -140.055878) (xy 94.29718 -140.014624)
			(xy 94.408545 -139.980973) (xy 94.521968 -139.955085) (xy 94.636905 -139.937084) (xy 94.752811 -139.927055)
			(xy 94.869133 -139.925047) (xy 94.985316 -139.931069) (xy 95.100807 -139.945092) (xy 95.215055 -139.96705)
			(xy 95.327516 -139.996837) (xy 95.437654 -140.034312) (xy 95.544944 -140.079297) (xy 95.648875 -140.131576)
			(xy 95.748951 -140.190901) (xy 95.844697 -140.256989) (xy 95.935654 -140.329525) (xy 96.02139 -140.408164)
			(xy 96.101497 -140.49253) (xy 96.175593 -140.582222) (xy 96.243323 -140.676812) (xy 96.304367 -140.77585)
			(xy 96.358432 -140.878863) (xy 96.405262 -140.98536) (xy 96.444633 -141.094835) (xy 96.476357 -141.206765)
			(xy 96.500283 -141.320617) (xy 96.516297 -141.435849) (xy 96.524324 -141.551911) (xy 96.524826 -141.61008)
			(xy 96.524324 -141.668249) (xy 96.516297 -141.784311) (xy 96.500283 -141.899543) (xy 96.476357 -142.013395)
			(xy 96.444633 -142.125325) (xy 96.405262 -142.2348) (xy 96.358432 -142.341297) (xy 96.304367 -142.44431)
			(xy 96.243323 -142.543348) (xy 96.175593 -142.637938) (xy 96.101497 -142.72763) (xy 96.02139 -142.811996)
			(xy 95.935654 -142.890635) (xy 95.844697 -142.963171) (xy 95.748951 -143.029259) (xy 95.648875 -143.088584)
			(xy 95.544944 -143.140863) (xy 95.437654 -143.185848) (xy 95.327516 -143.223323) (xy 95.215055 -143.25311)
			(xy 95.100807 -143.275068) (xy 94.985316 -143.289091) (xy 94.869133 -143.295113) (xy 94.752811 -143.293105)
			(xy 94.636905 -143.283076) (xy 94.521968 -143.265075) (xy 94.408545 -143.239187) (xy 94.29718 -143.205536)
			(xy 94.188401 -143.164282) (xy 94.082727 -143.115621) (xy 93.980663 -143.059785) (xy 93.882694 -142.997042)
			(xy 93.789287 -142.927688) (xy 93.700887 -142.852056) (xy 93.617916 -142.770505) (xy 93.540769 -142.683424)
			(xy 93.469814 -142.591228) (xy 93.405388 -142.494356) (xy 93.347799 -142.393271) (xy 93.297322 -142.288453)
			(xy 93.254196 -142.180402) (xy 93.218627 -142.069634) (xy 93.190785 -141.956675) (xy 93.170803 -141.842065)
			(xy 93.158776 -141.72635) (xy 93.15476 -141.61008) (xy 91.165918 -141.61008) (xy 91.217026 -141.6548)
			(xy 91.26845 -141.710504) (xy 91.313661 -141.771359) (xy 91.352148 -141.836674) (xy 91.383474 -141.90571)
			(xy 91.407284 -141.977685) (xy 91.423309 -142.051783) (xy 91.431368 -142.127164) (xy 91.431872 -142.16507)
			(xy 91.431368 -142.202976) (xy 91.423309 -142.278357) (xy 91.407284 -142.352455) (xy 91.383474 -142.42443)
			(xy 91.352148 -142.493466) (xy 91.313661 -142.558781) (xy 91.26845 -142.619636) (xy 91.217026 -142.67534)
			(xy 91.159973 -142.725262) (xy 91.097937 -142.768837) (xy 91.03162 -142.805572) (xy 90.961774 -142.835049)
			(xy 90.889191 -142.856935) (xy 90.814693 -142.870982) (xy 90.739123 -142.877031) (xy 90.663339 -142.875012)
			(xy 90.588199 -142.86495) (xy 90.514554 -142.846958) (xy 90.443238 -142.82124) (xy 90.375061 -142.788088)
			(xy 90.310793 -142.747876) (xy 90.251164 -142.701061) (xy 90.196848 -142.648173) (xy 90.148462 -142.589811)
			(xy 90.106554 -142.526636) (xy 90.071598 -142.459365) (xy 90.043991 -142.38876) (xy 90.024045 -142.315619)
			(xy 90.011986 -142.240774) (xy 90.007951 -142.16507) (xy 89.343484 -142.16507) (xy 89.343484 -142.546832)
			(xy 85.741002 -146.149568) (xy 85.725047 -146.16625) (xy 85.698853 -146.204253) (xy 85.679948 -146.24636)
			(xy 85.668953 -146.291188) (xy 85.666228 -146.337263) (xy 85.671863 -146.383074) (xy 85.685673 -146.427115)
			(xy 85.707205 -146.467942) (xy 85.735751 -146.504211) (xy 85.752686 -146.5199) (xy 85.772744 -146.538177)
			(xy 85.808001 -146.579425) (xy 85.837059 -146.625253) (xy 85.85933 -146.674735) (xy 85.874367 -146.726873)
			(xy 85.881865 -146.780616) (xy 85.881673 -146.834879) (xy 85.873795 -146.888567) (xy 85.85839 -146.940598)
			(xy 85.835769 -146.989921) (xy 85.806388 -147.035542) (xy 85.77084 -147.07654) (xy 85.729842 -147.112088)
			(xy 85.684221 -147.141469) (xy 85.634898 -147.16409) (xy 85.582867 -147.179495) (xy 85.529178 -147.187373)
			(xy 85.474915 -147.187565) (xy 85.421173 -147.180067) (xy 85.369034 -147.16503) (xy 85.319552 -147.142758)
			(xy 85.273725 -147.113701) (xy 85.232476 -147.078443) (xy 85.214206 -147.05838) (xy 85.198579 -147.041377)
			(xy 85.162319 -147.012786) (xy 85.121487 -146.991221) (xy 85.07743 -146.977393) (xy 85.031599 -146.971757)
			(xy 84.985504 -146.9745) (xy 84.940665 -146.985532) (xy 84.898559 -147.004487) (xy 84.860573 -147.030742)
			(xy 84.843874 -147.046696) (xy 84.538566 -147.352004) (xy 86.714582 -147.352004) (xy 86.718653 -147.296382)
			(xy 86.730779 -147.241945) (xy 86.750702 -147.189854) (xy 86.777998 -147.141219) (xy 86.812084 -147.097076)
			(xy 86.852233 -147.058367) (xy 86.897591 -147.025916) (xy 86.947191 -147.000415) (xy 86.999975 -146.982408)
			(xy 87.054818 -146.972278) (xy 87.110552 -146.970241) (xy 87.165989 -146.976341) (xy 87.219946 -146.990447)
			(xy 87.271275 -147.012259) (xy 87.318881 -147.041313) (xy 87.361749 -147.076988) (xy 87.398966 -147.118525)
			(xy 87.429739 -147.165038) (xy 87.453411 -147.215535) (xy 87.469479 -147.268942) (xy 87.477599 -147.324118)
			(xy 87.478108 -147.352004) (xy 87.477599 -147.37989) (xy 87.469479 -147.435066) (xy 87.453411 -147.488473)
			(xy 87.429739 -147.53897) (xy 87.398966 -147.585483) (xy 87.361749 -147.62702) (xy 87.318881 -147.662695)
			(xy 87.271275 -147.691749) (xy 87.219946 -147.713561) (xy 87.165989 -147.727667) (xy 87.110552 -147.733767)
			(xy 87.054818 -147.73173) (xy 86.999975 -147.7216) (xy 86.947191 -147.703593) (xy 86.897591 -147.678092)
			(xy 86.852233 -147.645641) (xy 86.812084 -147.606932) (xy 86.777998 -147.562789) (xy 86.750702 -147.514154)
			(xy 86.730779 -147.462063) (xy 86.718653 -147.407626) (xy 86.714582 -147.352004) (xy 84.538566 -147.352004)
			(xy 83.999578 -147.890992) (xy 83.9845 -147.906712) (xy 83.959414 -147.942318) (xy 83.940765 -147.981679)
			(xy 83.929098 -148.023642) (xy 83.924756 -148.06698) (xy 83.927864 -148.110424) (xy 83.938333 -148.152703)
			(xy 83.955856 -148.192578) (xy 83.979919 -148.228882) (xy 83.994498 -148.245068) (xy 84.01376 -148.264605)
			(xy 84.047047 -148.308217) (xy 84.073743 -148.356147) (xy 84.093299 -148.407407) (xy 84.105311 -148.46094)
			(xy 84.109531 -148.515641) (xy 84.105872 -148.570382) (xy 84.09441 -148.624035) (xy 84.075381 -148.675493)
			(xy 84.049177 -148.723695) (xy 84.01634 -148.767646) (xy 83.977545 -148.80644) (xy 83.933594 -148.839278)
			(xy 83.885393 -148.865481) (xy 83.833935 -148.88451) (xy 83.780282 -148.895972) (xy 83.72554 -148.899631)
			(xy 83.670839 -148.895411) (xy 83.617307 -148.883399) (xy 83.566047 -148.863843) (xy 83.518117 -148.837147)
			(xy 83.474505 -148.80386) (xy 83.455002 -148.784564) (xy 83.438864 -148.769923) (xy 83.402563 -148.745831)
			(xy 83.362681 -148.728289) (xy 83.320391 -148.717811) (xy 83.276933 -148.714705) (xy 83.233582 -148.719063)
			(xy 83.191612 -148.730756) (xy 83.152253 -148.749441) (xy 83.116661 -148.77457) (xy 83.100926 -148.789644)
			(xy 82.98815 -148.90242) (xy 85.31428 -148.90242) (xy 85.318351 -148.846798) (xy 85.330477 -148.792361)
			(xy 85.3504 -148.74027) (xy 85.377696 -148.691635) (xy 85.411782 -148.647492) (xy 85.451931 -148.608783)
			(xy 85.497289 -148.576332) (xy 85.546889 -148.550831) (xy 85.599673 -148.532824) (xy 85.654516 -148.522694)
			(xy 85.71025 -148.520657) (xy 85.765687 -148.526757) (xy 85.819644 -148.540863) (xy 85.870973 -148.562675)
			(xy 85.918579 -148.591729) (xy 85.961447 -148.627404) (xy 85.998664 -148.668941) (xy 86.029437 -148.715454)
			(xy 86.053109 -148.765951) (xy 86.069177 -148.819358) (xy 86.077297 -148.874534) (xy 86.077806 -148.90242)
			(xy 86.077297 -148.930306) (xy 86.069177 -148.985482) (xy 86.053109 -149.038889) (xy 86.029437 -149.089386)
			(xy 85.998664 -149.135899) (xy 85.961447 -149.177436) (xy 85.918579 -149.213111) (xy 85.870973 -149.242165)
			(xy 85.819644 -149.263977) (xy 85.765687 -149.278083) (xy 85.71025 -149.284183) (xy 85.654516 -149.282146)
			(xy 85.599673 -149.272016) (xy 85.546889 -149.254009) (xy 85.497289 -149.228508) (xy 85.451931 -149.196057)
			(xy 85.411782 -149.157348) (xy 85.377696 -149.113205) (xy 85.3504 -149.06457) (xy 85.330477 -149.012479)
			(xy 85.318351 -148.958042) (xy 85.31428 -148.90242) (xy 82.98815 -148.90242) (xy 82.587846 -149.302724)
			(xy 82.576978 -149.314146) (xy 82.560725 -149.341149) (xy 82.551638 -149.371328) (xy 82.550508 -149.387052)
			(xy 82.550508 -149.43201) (xy 82.56651 -149.460712) (xy 82.579427 -149.485052) (xy 82.598893 -149.536602)
			(xy 82.610739 -149.590415) (xy 82.614718 -149.645374) (xy 82.610747 -149.700333) (xy 82.598908 -149.754148)
			(xy 82.579449 -149.8057) (xy 82.576237 -149.81174) (xy 83.9122 -149.81174) (xy 83.916271 -149.756118)
			(xy 83.928397 -149.701681) (xy 83.94832 -149.64959) (xy 83.975616 -149.600955) (xy 84.009702 -149.556812)
			(xy 84.049851 -149.518103) (xy 84.095209 -149.485652) (xy 84.144809 -149.460151) (xy 84.197593 -149.442144)
			(xy 84.252436 -149.432014) (xy 84.30817 -149.429977) (xy 84.363607 -149.436077) (xy 84.417564 -149.450183)
			(xy 84.468893 -149.471995) (xy 84.516499 -149.501049) (xy 84.559367 -149.536724) (xy 84.596584 -149.578261)
			(xy 84.627357 -149.624774) (xy 84.651029 -149.675271) (xy 84.667097 -149.728678) (xy 84.675217 -149.783854)
			(xy 84.675726 -149.81174) (xy 84.675217 -149.839626) (xy 84.667097 -149.894802) (xy 84.651029 -149.948209)
			(xy 84.627357 -149.998706) (xy 84.596584 -150.045219) (xy 84.559367 -150.086756) (xy 84.516499 -150.122431)
			(xy 84.468893 -150.151485) (xy 84.417564 -150.173297) (xy 84.363607 -150.187403) (xy 84.30817 -150.193503)
			(xy 84.252436 -150.191466) (xy 84.197593 -150.181336) (xy 84.144809 -150.163329) (xy 84.095209 -150.137828)
			(xy 84.049851 -150.105377) (xy 84.009702 -150.066668) (xy 83.975616 -150.022525) (xy 83.94832 -149.97389)
			(xy 83.928397 -149.921799) (xy 83.916271 -149.867362) (xy 83.9122 -149.81174) (xy 82.576237 -149.81174)
			(xy 82.56651 -149.830028) (xy 82.550508 -149.85873) (xy 82.550508 -151.212804) (xy 84.390482 -151.212804)
			(xy 84.394553 -151.157182) (xy 84.406679 -151.102745) (xy 84.426602 -151.050654) (xy 84.453898 -151.002019)
			(xy 84.487984 -150.957876) (xy 84.528133 -150.919167) (xy 84.573491 -150.886716) (xy 84.623091 -150.861215)
			(xy 84.675875 -150.843208) (xy 84.730718 -150.833078) (xy 84.786452 -150.831041) (xy 84.841889 -150.837141)
			(xy 84.895846 -150.851247) (xy 84.947175 -150.873059) (xy 84.994781 -150.902113) (xy 85.037649 -150.937788)
			(xy 85.074866 -150.979325) (xy 85.105639 -151.025838) (xy 85.129311 -151.076335) (xy 85.145379 -151.129742)
			(xy 85.153499 -151.184918) (xy 85.154008 -151.212804) (xy 85.153499 -151.24069) (xy 85.145379 -151.295866)
			(xy 85.129311 -151.349273) (xy 85.105639 -151.39977) (xy 85.074866 -151.446283) (xy 85.037649 -151.48782)
			(xy 84.994781 -151.523495) (xy 84.947175 -151.552549) (xy 84.895846 -151.574361) (xy 84.841889 -151.588467)
			(xy 84.786452 -151.594567) (xy 84.730718 -151.59253) (xy 84.675875 -151.5824) (xy 84.623091 -151.564393)
			(xy 84.573491 -151.538892) (xy 84.528133 -151.506441) (xy 84.487984 -151.467732) (xy 84.453898 -151.423589)
			(xy 84.426602 -151.374954) (xy 84.406679 -151.322863) (xy 84.394553 -151.268426) (xy 84.390482 -151.212804)
			(xy 82.550508 -151.212804) (xy 82.550508 -153.359866) (xy 86.877404 -153.359866) (xy 86.881424 -153.169215)
			(xy 86.893478 -152.978902) (xy 86.913544 -152.789267) (xy 86.941587 -152.600646) (xy 86.977556 -152.413376)
			(xy 87.021388 -152.227788) (xy 87.073005 -152.044213) (xy 87.132315 -151.862977) (xy 87.199213 -151.684402)
			(xy 87.273579 -151.508807) (xy 87.355281 -151.336502) (xy 87.444175 -151.167795) (xy 87.540101 -151.002985)
			(xy 87.64289 -150.842366) (xy 87.752359 -150.686223) (xy 87.868313 -150.534834) (xy 87.990547 -150.388467)
			(xy 88.118841 -150.247383) (xy 88.252969 -150.111834) (xy 88.392693 -149.982059) (xy 88.537763 -149.858289)
			(xy 88.687921 -149.740746) (xy 88.842902 -149.629637) (xy 89.002429 -149.52516) (xy 89.166218 -149.427501)
			(xy 89.333978 -149.336834) (xy 89.505412 -149.25332) (xy 89.680214 -149.177107) (xy 89.858073 -149.108331)
			(xy 90.038674 -149.047113) (xy 90.221694 -148.993564) (xy 90.40681 -148.947778) (xy 90.593691 -148.909836)
			(xy 90.782006 -148.879807) (xy 90.971419 -148.857742) (xy 91.161593 -148.843683) (xy 91.352192 -148.837653)
			(xy 91.542875 -148.839663) (xy 91.733304 -148.84971) (xy 91.92314 -148.867776) (xy 92.112046 -148.893829)
			(xy 92.299685 -148.927822) (xy 92.485725 -148.969695) (xy 92.669834 -149.019374) (xy 92.851685 -149.07677)
			(xy 93.030955 -149.141781) (xy 93.207325 -149.214292) (xy 93.380481 -149.294173) (xy 93.550116 -149.381283)
			(xy 93.715928 -149.475467) (xy 93.877622 -149.576558) (xy 94.03491 -149.684374) (xy 94.187513 -149.798726)
			(xy 94.335161 -149.919409) (xy 94.477589 -150.04621) (xy 94.614545 -150.178901) (xy 94.745786 -150.317249)
			(xy 94.871078 -150.461006) (xy 94.990198 -150.609917) (xy 95.102934 -150.763718) (xy 95.209087 -150.922134)
			(xy 95.308467 -151.084885) (xy 95.400897 -151.25168) (xy 95.486214 -151.422224) (xy 95.564266 -151.596212)
			(xy 95.634913 -151.773337) (xy 95.698031 -151.953282) (xy 95.753507 -152.135728) (xy 95.801242 -152.320351)
			(xy 95.841152 -152.506821) (xy 95.873165 -152.694809) (xy 95.897225 -152.883979) (xy 95.913288 -153.073995)
			(xy 95.921327 -153.264519) (xy 95.92183 -153.359866) (xy 95.921327 -153.455213) (xy 95.913288 -153.645737)
			(xy 95.897225 -153.835753) (xy 95.873165 -154.024923) (xy 95.841152 -154.212911) (xy 95.801242 -154.399381)
			(xy 95.753507 -154.584004) (xy 95.698031 -154.76645) (xy 95.634913 -154.946395) (xy 95.564266 -155.12352)
			(xy 95.486214 -155.297508) (xy 95.400897 -155.468052) (xy 95.308467 -155.634847) (xy 95.209087 -155.797598)
			(xy 95.102934 -155.956014) (xy 94.990198 -156.109815) (xy 94.871078 -156.258726) (xy 94.745786 -156.402483)
			(xy 94.614545 -156.540831) (xy 94.477589 -156.673522) (xy 94.335161 -156.800323) (xy 94.187513 -156.921006)
			(xy 94.03491 -157.035358) (xy 93.877622 -157.143174) (xy 93.715928 -157.244265) (xy 93.550116 -157.338449)
			(xy 93.380481 -157.425559) (xy 93.207325 -157.50544) (xy 93.030955 -157.577951) (xy 92.851685 -157.642962)
			(xy 92.669834 -157.700358) (xy 92.485725 -157.750037) (xy 92.299685 -157.79191) (xy 92.112046 -157.825903)
			(xy 91.92314 -157.851956) (xy 91.733304 -157.870022) (xy 91.542875 -157.880069) (xy 91.352192 -157.882079)
			(xy 91.161593 -157.876049) (xy 90.971419 -157.86199) (xy 90.782006 -157.839925) (xy 90.593691 -157.809896)
			(xy 90.40681 -157.771954) (xy 90.221694 -157.726168) (xy 90.038674 -157.672619) (xy 89.858073 -157.611401)
			(xy 89.680214 -157.542625) (xy 89.505412 -157.466412) (xy 89.333978 -157.382898) (xy 89.166218 -157.292231)
			(xy 89.002429 -157.194572) (xy 88.842902 -157.090095) (xy 88.687921 -156.978986) (xy 88.537763 -156.861443)
			(xy 88.392693 -156.737673) (xy 88.252969 -156.607898) (xy 88.118841 -156.472349) (xy 87.990547 -156.331265)
			(xy 87.868313 -156.184898) (xy 87.752359 -156.033509) (xy 87.64289 -155.877366) (xy 87.540101 -155.716747)
			(xy 87.444175 -155.551937) (xy 87.355281 -155.38323) (xy 87.273579 -155.210925) (xy 87.199213 -155.03533)
			(xy 87.132315 -154.856755) (xy 87.073005 -154.675519) (xy 87.021388 -154.491944) (xy 86.977556 -154.306356)
			(xy 86.941587 -154.119086) (xy 86.913544 -153.930465) (xy 86.893478 -153.74083) (xy 86.881424 -153.550517)
			(xy 86.877404 -153.359866) (xy 82.550508 -153.359866) (xy 82.550508 -155.93187) (xy 82.040476 -156.442156)
			(xy 82.040476 -157.045152) (xy 73.434448 -165.65118) (xy 89.533982 -165.65118) (xy 89.538053 -165.595558)
			(xy 89.550179 -165.541121) (xy 89.570102 -165.48903) (xy 89.597398 -165.440395) (xy 89.631484 -165.396252)
			(xy 89.671633 -165.357543) (xy 89.716991 -165.325092) (xy 89.766591 -165.299591) (xy 89.819375 -165.281584)
			(xy 89.874218 -165.271454) (xy 89.929952 -165.269417) (xy 89.985389 -165.275517) (xy 90.039346 -165.289623)
			(xy 90.090675 -165.311435) (xy 90.138281 -165.340489) (xy 90.181149 -165.376164) (xy 90.218366 -165.417701)
			(xy 90.249139 -165.464214) (xy 90.272811 -165.514711) (xy 90.288879 -165.568118) (xy 90.296999 -165.623294)
			(xy 90.297508 -165.65118) (xy 90.296999 -165.679066) (xy 90.288879 -165.734242) (xy 90.272811 -165.787649)
			(xy 90.249139 -165.838146) (xy 90.218366 -165.884659) (xy 90.181149 -165.926196) (xy 90.138281 -165.961871)
			(xy 90.090675 -165.990925) (xy 90.039346 -166.012737) (xy 89.985389 -166.026843) (xy 89.929952 -166.032943)
			(xy 89.874218 -166.030906) (xy 89.819375 -166.020776) (xy 89.766591 -166.002769) (xy 89.716991 -165.977268)
			(xy 89.671633 -165.944817) (xy 89.631484 -165.906108) (xy 89.597398 -165.861965) (xy 89.570102 -165.81333)
			(xy 89.550179 -165.761239) (xy 89.538053 -165.706802) (xy 89.533982 -165.65118) (xy 73.434448 -165.65118)
			(xy 68.924932 -170.160696) (xy 68.908914 -170.177453) (xy 68.882635 -170.215636) (xy 68.863709 -170.257948)
			(xy 68.852761 -170.302989) (xy 68.850154 -170.349268) (xy 68.855974 -170.395253) (xy 68.870028 -170.439423)
			(xy 68.891852 -170.480316) (xy 68.905882 -170.49877) (xy 68.92286 -170.520849) (xy 68.950908 -170.568965)
			(xy 68.971663 -170.620648) (xy 68.984683 -170.674799) (xy 68.989692 -170.730267) (xy 68.989329 -170.736768)
			(xy 69.344538 -170.736768) (xy 69.348609 -170.681146) (xy 69.360735 -170.626709) (xy 69.380658 -170.574618)
			(xy 69.407954 -170.525983) (xy 69.44204 -170.48184) (xy 69.482189 -170.443131) (xy 69.527547 -170.41068)
			(xy 69.577147 -170.385179) (xy 69.629931 -170.367172) (xy 69.684774 -170.357042) (xy 69.740508 -170.355005)
			(xy 69.795945 -170.361105) (xy 69.849902 -170.375211) (xy 69.901231 -170.397023) (xy 69.948837 -170.426077)
			(xy 69.991705 -170.461752) (xy 70.028922 -170.503289) (xy 70.059695 -170.549802) (xy 70.083367 -170.600299)
			(xy 70.099435 -170.653706) (xy 70.107555 -170.708882) (xy 70.108064 -170.736768) (xy 70.472552 -170.736768)
			(xy 70.476623 -170.681146) (xy 70.488749 -170.626709) (xy 70.508672 -170.574618) (xy 70.535968 -170.525983)
			(xy 70.570054 -170.48184) (xy 70.610203 -170.443131) (xy 70.655561 -170.41068) (xy 70.705161 -170.385179)
			(xy 70.757945 -170.367172) (xy 70.812788 -170.357042) (xy 70.868522 -170.355005) (xy 70.923959 -170.361105)
			(xy 70.977916 -170.375211) (xy 71.029245 -170.397023) (xy 71.076851 -170.426077) (xy 71.119719 -170.461752)
			(xy 71.156936 -170.503289) (xy 71.187709 -170.549802) (xy 71.211381 -170.600299) (xy 71.227449 -170.653706)
			(xy 71.235569 -170.708882) (xy 71.236078 -170.736768) (xy 71.586342 -170.736768) (xy 71.590413 -170.681146)
			(xy 71.602539 -170.626709) (xy 71.622462 -170.574618) (xy 71.649758 -170.525983) (xy 71.683844 -170.48184)
			(xy 71.723993 -170.443131) (xy 71.769351 -170.41068) (xy 71.818951 -170.385179) (xy 71.871735 -170.367172)
			(xy 71.926578 -170.357042) (xy 71.982312 -170.355005) (xy 72.037749 -170.361105) (xy 72.091706 -170.375211)
			(xy 72.143035 -170.397023) (xy 72.190641 -170.426077) (xy 72.233509 -170.461752) (xy 72.270726 -170.503289)
			(xy 72.301499 -170.549802) (xy 72.325171 -170.600299) (xy 72.341239 -170.653706) (xy 72.349359 -170.708882)
			(xy 72.349868 -170.736768) (xy 72.349359 -170.764654) (xy 72.341239 -170.81983) (xy 72.325171 -170.873237)
			(xy 72.301499 -170.923734) (xy 72.270726 -170.970247) (xy 72.233509 -171.011784) (xy 72.190641 -171.047459)
			(xy 72.143035 -171.076513) (xy 72.091706 -171.098325) (xy 72.037749 -171.112431) (xy 71.982312 -171.118531)
			(xy 71.926578 -171.116494) (xy 71.871735 -171.106364) (xy 71.818951 -171.088357) (xy 71.769351 -171.062856)
			(xy 71.723993 -171.030405) (xy 71.683844 -170.991696) (xy 71.649758 -170.947553) (xy 71.622462 -170.898918)
			(xy 71.602539 -170.846827) (xy 71.590413 -170.79239) (xy 71.586342 -170.736768) (xy 71.236078 -170.736768)
			(xy 71.235569 -170.764654) (xy 71.227449 -170.81983) (xy 71.211381 -170.873237) (xy 71.187709 -170.923734)
			(xy 71.156936 -170.970247) (xy 71.119719 -171.011784) (xy 71.076851 -171.047459) (xy 71.029245 -171.076513)
			(xy 70.977916 -171.098325) (xy 70.923959 -171.112431) (xy 70.868522 -171.118531) (xy 70.812788 -171.116494)
			(xy 70.757945 -171.106364) (xy 70.705161 -171.088357) (xy 70.655561 -171.062856) (xy 70.610203 -171.030405)
			(xy 70.570054 -170.991696) (xy 70.535968 -170.947553) (xy 70.508672 -170.898918) (xy 70.488749 -170.846827)
			(xy 70.476623 -170.79239) (xy 70.472552 -170.736768) (xy 70.108064 -170.736768) (xy 70.107555 -170.764654)
			(xy 70.099435 -170.81983) (xy 70.083367 -170.873237) (xy 70.059695 -170.923734) (xy 70.028922 -170.970247)
			(xy 69.991705 -171.011784) (xy 69.948837 -171.047459) (xy 69.901231 -171.076513) (xy 69.849902 -171.098325)
			(xy 69.795945 -171.112431) (xy 69.740508 -171.118531) (xy 69.684774 -171.116494) (xy 69.629931 -171.106364)
			(xy 69.577147 -171.088357) (xy 69.527547 -171.062856) (xy 69.482189 -171.030405) (xy 69.44204 -170.991696)
			(xy 69.407954 -170.947553) (xy 69.380658 -170.898918) (xy 69.360735 -170.846827) (xy 69.348609 -170.79239)
			(xy 69.344538 -170.736768) (xy 68.989329 -170.736768) (xy 68.986583 -170.785875) (xy 68.975422 -170.84044)
			(xy 68.956446 -170.892802) (xy 68.930059 -170.941849) (xy 68.896822 -170.986538) (xy 68.85744 -171.02592)
			(xy 68.812751 -171.059158) (xy 68.763704 -171.085545) (xy 68.711342 -171.104521) (xy 68.656778 -171.115683)
			(xy 68.60117 -171.118792) (xy 68.545702 -171.113784) (xy 68.49155 -171.100764) (xy 68.439867 -171.08001)
			(xy 68.391751 -171.051961) (xy 68.369688 -171.034964) (xy 68.35125 -171.020899) (xy 68.310366 -170.999022)
			(xy 68.26619 -170.984931) (xy 68.22019 -170.979093) (xy 68.173894 -170.981703) (xy 68.128842 -170.992674)
			(xy 68.08653 -171.011642) (xy 68.048364 -171.037975) (xy 68.031614 -171.054014) (xy 67.593197 -171.492418)
			(xy 90.183968 -171.492418) (xy 90.188039 -171.436796) (xy 90.200165 -171.382359) (xy 90.220088 -171.330268)
			(xy 90.247384 -171.281633) (xy 90.28147 -171.23749) (xy 90.321619 -171.198781) (xy 90.366977 -171.16633)
			(xy 90.416577 -171.140829) (xy 90.469361 -171.122822) (xy 90.524204 -171.112692) (xy 90.579938 -171.110655)
			(xy 90.635375 -171.116755) (xy 90.689332 -171.130861) (xy 90.740661 -171.152673) (xy 90.788267 -171.181727)
			(xy 90.831135 -171.217402) (xy 90.868352 -171.258939) (xy 90.899125 -171.305452) (xy 90.922797 -171.355949)
			(xy 90.938865 -171.409356) (xy 90.946985 -171.464532) (xy 90.947494 -171.492418) (xy 90.946985 -171.520304)
			(xy 90.938865 -171.57548) (xy 90.922797 -171.628887) (xy 90.899125 -171.679384) (xy 90.868352 -171.725897)
			(xy 90.831135 -171.767434) (xy 90.788267 -171.803109) (xy 90.740661 -171.832163) (xy 90.689332 -171.853975)
			(xy 90.635375 -171.868081) (xy 90.579938 -171.874181) (xy 90.524204 -171.872144) (xy 90.469361 -171.862014)
			(xy 90.416577 -171.844007) (xy 90.366977 -171.818506) (xy 90.321619 -171.786055) (xy 90.28147 -171.747346)
			(xy 90.247384 -171.703203) (xy 90.220088 -171.654568) (xy 90.200165 -171.602477) (xy 90.188039 -171.54804)
			(xy 90.183968 -171.492418) (xy 67.593197 -171.492418) (xy 59.519058 -179.566316) (xy 58.958988 -179.566316)
			(xy 58.943984 -179.567954) (xy 58.915316 -179.577368) (xy 58.889658 -179.593248) (xy 58.878724 -179.603654)
			(xy 58.56605 -179.916328) (xy 30.951932 -179.916328) (xy 30.944566 -179.916836) (xy 30.658562 -180.20284)
			(xy 30.651834 -180.22572) (xy 30.646073 -180.273057) (xy 30.649243 -180.320637) (xy 30.661233 -180.366791)
			(xy 30.681622 -180.409898) (xy 30.709693 -180.448446) (xy 30.744462 -180.481081) (xy 30.784709 -180.506658)
			(xy 30.806644 -180.516022) (xy 30.829919 -180.525426) (xy 30.875537 -180.546392) (xy 30.89783 -180.557932)
			(xy 30.935173 -180.578125) (xy 31.006424 -180.624289) (xy 31.073224 -180.676689) (xy 31.135027 -180.734899)
			(xy 31.19133 -180.798443) (xy 31.241676 -180.866805) (xy 31.285652 -180.939427) (xy 31.322903 -181.015719)
			(xy 31.353123 -181.095058) (xy 31.376067 -181.176798) (xy 31.391549 -181.260275) (xy 31.399441 -181.344807)
			(xy 31.399679 -181.429706) (xy 31.399348 -181.433486) (xy 34.599874 -181.433486) (xy 34.599874 -181.346586)
			(xy 34.607892 -181.260057) (xy 34.62386 -181.174637) (xy 34.647641 -181.091055) (xy 34.679033 -181.010023)
			(xy 34.717767 -180.932234) (xy 34.763514 -180.85835) (xy 34.815883 -180.789003) (xy 34.874427 -180.724783)
			(xy 34.938647 -180.666239) (xy 35.007994 -180.61387) (xy 35.081878 -180.568123) (xy 35.159667 -180.529389)
			(xy 35.240699 -180.497997) (xy 35.324281 -180.474216) (xy 35.409701 -180.458248) (xy 35.49623 -180.45023)
			(xy 35.58313 -180.45023) (xy 35.669659 -180.458248) (xy 35.755079 -180.474216) (xy 35.838661 -180.497997)
			(xy 35.919693 -180.529389) (xy 35.997482 -180.568123) (xy 36.071366 -180.61387) (xy 36.140713 -180.666239)
			(xy 36.204933 -180.724783) (xy 36.263477 -180.789003) (xy 36.315846 -180.85835) (xy 36.361593 -180.932234)
			(xy 36.400327 -181.010023) (xy 36.431719 -181.091055) (xy 36.4555 -181.174637) (xy 36.471468 -181.260057)
			(xy 36.479486 -181.346586) (xy 36.479988 -181.390036) (xy 36.479486 -181.433486) (xy 36.471468 -181.520015)
			(xy 36.4555 -181.605435) (xy 36.431719 -181.689017) (xy 36.400327 -181.770049) (xy 36.361593 -181.847838)
			(xy 36.315846 -181.921722) (xy 36.263477 -181.991069) (xy 36.204933 -182.055289) (xy 36.140713 -182.113833)
			(xy 36.071366 -182.166202) (xy 35.997482 -182.211949) (xy 35.919693 -182.250683) (xy 35.838661 -182.282075)
			(xy 35.755079 -182.305856) (xy 35.669659 -182.321824) (xy 35.58313 -182.329842) (xy 35.49623 -182.329842)
			(xy 35.409701 -182.321824) (xy 35.324281 -182.305856) (xy 35.240699 -182.282075) (xy 35.159667 -182.250683)
			(xy 35.081878 -182.211949) (xy 35.007994 -182.166202) (xy 34.938647 -182.113833) (xy 34.874427 -182.055289)
			(xy 34.815883 -181.991069) (xy 34.763514 -181.921722) (xy 34.717767 -181.847838) (xy 34.679033 -181.770049)
			(xy 34.647641 -181.689017) (xy 34.62386 -181.605435) (xy 34.607892 -181.520015) (xy 34.599874 -181.433486)
			(xy 31.399348 -181.433486) (xy 31.392263 -181.514281) (xy 31.385256 -181.556152) (xy 31.376583 -181.601331)
			(xy 31.351571 -181.689867) (xy 31.318031 -181.775537) (xy 31.276285 -181.857521) (xy 31.226732 -181.935037)
			(xy 31.169845 -182.007343) (xy 31.106168 -182.073747) (xy 31.036311 -182.133615) (xy 30.998922 -182.160418)
			(xy 30.976725 -182.175723) (xy 30.93085 -182.204063) (xy 30.907228 -182.21706) (xy 30.868799 -182.237285)
			(xy 30.788932 -182.271397) (xy 30.706259 -182.297999) (xy 30.621486 -182.316865) (xy 30.535335 -182.327834)
			(xy 30.448539 -182.330813) (xy 30.361838 -182.325776) (xy 30.275971 -182.312766) (xy 30.19167 -182.291894)
			(xy 30.109652 -182.263338) (xy 30.030616 -182.227342) (xy 29.955236 -182.18421) (xy 29.884155 -182.134313)
			(xy 29.817976 -182.078073) (xy 29.757266 -182.015972) (xy 29.70254 -181.948536) (xy 29.654265 -181.876343)
			(xy 29.612853 -181.800005) (xy 29.578656 -181.720174) (xy 29.551965 -181.637531) (xy 29.541978 -181.595268)
			(xy 29.53385 -181.5592) (xy 29.507942 -181.533292) (xy 29.49581 -181.521831) (xy 29.466931 -181.505122)
			(xy 29.434708 -181.496471) (xy 29.401344 -181.496471) (xy 29.369121 -181.505122) (xy 29.340242 -181.521831)
			(xy 29.32811 -181.533292) (xy 28.461716 -182.399686) (xy 28.461716 -183.973486) (xy 29.519874 -183.973486)
			(xy 29.519874 -183.886586) (xy 29.527892 -183.800057) (xy 29.54386 -183.714637) (xy 29.567641 -183.631055)
			(xy 29.599033 -183.550023) (xy 29.637767 -183.472234) (xy 29.683514 -183.39835) (xy 29.735883 -183.329003)
			(xy 29.794427 -183.264783) (xy 29.858647 -183.206239) (xy 29.927994 -183.15387) (xy 30.001878 -183.108123)
			(xy 30.079667 -183.069389) (xy 30.160699 -183.037997) (xy 30.244281 -183.014216) (xy 30.329701 -182.998248)
			(xy 30.41623 -182.99023) (xy 30.50313 -182.99023) (xy 30.589659 -182.998248) (xy 30.675079 -183.014216)
			(xy 30.758661 -183.037997) (xy 30.839693 -183.069389) (xy 30.917482 -183.108123) (xy 30.991366 -183.15387)
			(xy 31.060713 -183.206239) (xy 31.124933 -183.264783) (xy 31.183477 -183.329003) (xy 31.235846 -183.39835)
			(xy 31.281593 -183.472234) (xy 31.320327 -183.550023) (xy 31.351719 -183.631055) (xy 31.3755 -183.714637)
			(xy 31.391468 -183.800057) (xy 31.399486 -183.886586) (xy 31.399988 -183.930036) (xy 31.399486 -183.973486)
			(xy 34.599874 -183.973486) (xy 34.599874 -183.886586) (xy 34.607892 -183.800057) (xy 34.62386 -183.714637)
			(xy 34.647641 -183.631055) (xy 34.679033 -183.550023) (xy 34.717767 -183.472234) (xy 34.763514 -183.39835)
			(xy 34.815883 -183.329003) (xy 34.874427 -183.264783) (xy 34.938647 -183.206239) (xy 35.007994 -183.15387)
			(xy 35.081878 -183.108123) (xy 35.159667 -183.069389) (xy 35.240699 -183.037997) (xy 35.324281 -183.014216)
			(xy 35.409701 -182.998248) (xy 35.49623 -182.99023) (xy 35.58313 -182.99023) (xy 35.669659 -182.998248)
			(xy 35.755079 -183.014216) (xy 35.838661 -183.037997) (xy 35.919693 -183.069389) (xy 35.997482 -183.108123)
			(xy 36.071366 -183.15387) (xy 36.140713 -183.206239) (xy 36.204933 -183.264783) (xy 36.263477 -183.329003)
			(xy 36.315846 -183.39835) (xy 36.361593 -183.472234) (xy 36.400327 -183.550023) (xy 36.431719 -183.631055)
			(xy 36.4555 -183.714637) (xy 36.471468 -183.800057) (xy 36.479486 -183.886586) (xy 36.479988 -183.930036)
			(xy 36.479486 -183.973486) (xy 36.471468 -184.060015) (xy 36.4555 -184.145435) (xy 36.431719 -184.229017)
			(xy 36.400327 -184.310049) (xy 36.361593 -184.387838) (xy 36.315846 -184.461722) (xy 36.263477 -184.531069)
			(xy 36.204933 -184.595289) (xy 36.140713 -184.653833) (xy 36.07398 -184.704228) (xy 39.818818 -184.704228)
			(xy 39.819523 -184.645605) (xy 39.828091 -184.528667) (xy 39.844787 -184.412611) (xy 39.86953 -184.298001)
			(xy 39.902199 -184.185393) (xy 39.942635 -184.075335) (xy 39.990642 -183.968363) (xy 40.045986 -183.864996)
			(xy 40.108399 -183.765737) (xy 40.177577 -183.671068) (xy 40.253183 -183.58145) (xy 40.334851 -183.497318)
			(xy 40.422182 -183.419081) (xy 40.514753 -183.34712) (xy 40.612113 -183.281784) (xy 40.713789 -183.223392)
			(xy 40.819288 -183.172226) (xy 40.928095 -183.128537) (xy 41.039682 -183.092535) (xy 41.153506 -183.064397)
			(xy 41.269014 -183.044259) (xy 41.385645 -183.032218) (xy 41.502832 -183.028334) (xy 41.620004 -183.032625)
			(xy 41.736593 -183.045071) (xy 41.85203 -183.065611) (xy 41.965756 -183.094144) (xy 42.077217 -183.130533)
			(xy 42.185872 -183.174601) (xy 42.291192 -183.226133) (xy 42.392665 -183.284878) (xy 42.489797 -183.350552)
			(xy 42.501941 -183.36006) (xy 43.327831 -183.36006) (xy 43.331866 -183.284356) (xy 43.343925 -183.209511)
			(xy 43.363871 -183.13637) (xy 43.391478 -183.065765) (xy 43.426434 -182.998494) (xy 43.468342 -182.935319)
			(xy 43.516728 -182.876957) (xy 43.571044 -182.824069) (xy 43.630673 -182.777254) (xy 43.694941 -182.737042)
			(xy 43.763118 -182.70389) (xy 43.834434 -182.678172) (xy 43.908079 -182.66018) (xy 43.983219 -182.650118)
			(xy 44.059003 -182.648099) (xy 44.134573 -182.654148) (xy 44.209071 -182.668195) (xy 44.281654 -182.690081)
			(xy 44.3515 -182.719558) (xy 44.417817 -182.756293) (xy 44.479853 -182.799868) (xy 44.536906 -182.84979)
			(xy 44.58833 -182.905494) (xy 44.633541 -182.966349) (xy 44.672028 -183.031664) (xy 44.703354 -183.1007)
			(xy 44.727164 -183.172675) (xy 44.743189 -183.246773) (xy 44.751248 -183.322154) (xy 44.751752 -183.36006)
			(xy 45.867831 -183.36006) (xy 45.871866 -183.284356) (xy 45.883925 -183.209511) (xy 45.903871 -183.13637)
			(xy 45.931478 -183.065765) (xy 45.966434 -182.998494) (xy 46.008342 -182.935319) (xy 46.056728 -182.876957)
			(xy 46.111044 -182.824069) (xy 46.170673 -182.777254) (xy 46.234941 -182.737042) (xy 46.303118 -182.70389)
			(xy 46.374434 -182.678172) (xy 46.448079 -182.66018) (xy 46.523219 -182.650118) (xy 46.599003 -182.648099)
			(xy 46.674573 -182.654148) (xy 46.749071 -182.668195) (xy 46.821654 -182.690081) (xy 46.8915 -182.719558)
			(xy 46.957817 -182.756293) (xy 47.019853 -182.799868) (xy 47.076906 -182.84979) (xy 47.12833 -182.905494)
			(xy 47.173541 -182.966349) (xy 47.212028 -183.031664) (xy 47.243354 -183.1007) (xy 47.267164 -183.172675)
			(xy 47.283189 -183.246773) (xy 47.291248 -183.322154) (xy 47.291752 -183.36006) (xy 48.407831 -183.36006)
			(xy 48.411866 -183.284356) (xy 48.423925 -183.209511) (xy 48.443871 -183.13637) (xy 48.471478 -183.065765)
			(xy 48.506434 -182.998494) (xy 48.548342 -182.935319) (xy 48.596728 -182.876957) (xy 48.651044 -182.824069)
			(xy 48.710673 -182.777254) (xy 48.774941 -182.737042) (xy 48.843118 -182.70389) (xy 48.914434 -182.678172)
			(xy 48.988079 -182.66018) (xy 49.063219 -182.650118) (xy 49.139003 -182.648099) (xy 49.214573 -182.654148)
			(xy 49.289071 -182.668195) (xy 49.361654 -182.690081) (xy 49.4315 -182.719558) (xy 49.497817 -182.756293)
			(xy 49.559853 -182.799868) (xy 49.616906 -182.84979) (xy 49.66833 -182.905494) (xy 49.713541 -182.966349)
			(xy 49.752028 -183.031664) (xy 49.783354 -183.1007) (xy 49.807164 -183.172675) (xy 49.823189 -183.246773)
			(xy 49.831248 -183.322154) (xy 49.831752 -183.36006) (xy 50.947831 -183.36006) (xy 50.951866 -183.284356)
			(xy 50.963925 -183.209511) (xy 50.983871 -183.13637) (xy 51.011478 -183.065765) (xy 51.046434 -182.998494)
			(xy 51.088342 -182.935319) (xy 51.136728 -182.876957) (xy 51.191044 -182.824069) (xy 51.250673 -182.777254)
			(xy 51.314941 -182.737042) (xy 51.383118 -182.70389) (xy 51.454434 -182.678172) (xy 51.528079 -182.66018)
			(xy 51.603219 -182.650118) (xy 51.679003 -182.648099) (xy 51.754573 -182.654148) (xy 51.829071 -182.668195)
			(xy 51.901654 -182.690081) (xy 51.9715 -182.719558) (xy 52.037817 -182.756293) (xy 52.099853 -182.799868)
			(xy 52.156906 -182.84979) (xy 52.20833 -182.905494) (xy 52.253541 -182.966349) (xy 52.292028 -183.031664)
			(xy 52.323354 -183.1007) (xy 52.347164 -183.172675) (xy 52.363189 -183.246773) (xy 52.371248 -183.322154)
			(xy 52.371752 -183.36006) (xy 53.487831 -183.36006) (xy 53.491866 -183.284356) (xy 53.503925 -183.209511)
			(xy 53.523871 -183.13637) (xy 53.551478 -183.065765) (xy 53.586434 -182.998494) (xy 53.628342 -182.935319)
			(xy 53.676728 -182.876957) (xy 53.731044 -182.824069) (xy 53.790673 -182.777254) (xy 53.854941 -182.737042)
			(xy 53.923118 -182.70389) (xy 53.994434 -182.678172) (xy 54.068079 -182.66018) (xy 54.143219 -182.650118)
			(xy 54.219003 -182.648099) (xy 54.294573 -182.654148) (xy 54.369071 -182.668195) (xy 54.441654 -182.690081)
			(xy 54.5115 -182.719558) (xy 54.577817 -182.756293) (xy 54.639853 -182.799868) (xy 54.696906 -182.84979)
			(xy 54.74833 -182.905494) (xy 54.793541 -182.966349) (xy 54.832028 -183.031664) (xy 54.863354 -183.1007)
			(xy 54.887164 -183.172675) (xy 54.903189 -183.246773) (xy 54.911248 -183.322154) (xy 54.911752 -183.36006)
			(xy 56.027831 -183.36006) (xy 56.031866 -183.284356) (xy 56.043925 -183.209511) (xy 56.063871 -183.13637)
			(xy 56.091478 -183.065765) (xy 56.126434 -182.998494) (xy 56.168342 -182.935319) (xy 56.216728 -182.876957)
			(xy 56.271044 -182.824069) (xy 56.330673 -182.777254) (xy 56.394941 -182.737042) (xy 56.463118 -182.70389)
			(xy 56.534434 -182.678172) (xy 56.608079 -182.66018) (xy 56.683219 -182.650118) (xy 56.759003 -182.648099)
			(xy 56.834573 -182.654148) (xy 56.909071 -182.668195) (xy 56.981654 -182.690081) (xy 57.0515 -182.719558)
			(xy 57.117817 -182.756293) (xy 57.179853 -182.799868) (xy 57.236906 -182.84979) (xy 57.28833 -182.905494)
			(xy 57.333541 -182.966349) (xy 57.372028 -183.031664) (xy 57.403354 -183.1007) (xy 57.427164 -183.172675)
			(xy 57.443189 -183.246773) (xy 57.451248 -183.322154) (xy 57.451752 -183.36006) (xy 58.567831 -183.36006)
			(xy 58.571866 -183.284356) (xy 58.583925 -183.209511) (xy 58.603871 -183.13637) (xy 58.631478 -183.065765)
			(xy 58.666434 -182.998494) (xy 58.708342 -182.935319) (xy 58.756728 -182.876957) (xy 58.811044 -182.824069)
			(xy 58.870673 -182.777254) (xy 58.934941 -182.737042) (xy 59.003118 -182.70389) (xy 59.074434 -182.678172)
			(xy 59.148079 -182.66018) (xy 59.223219 -182.650118) (xy 59.299003 -182.648099) (xy 59.374573 -182.654148)
			(xy 59.449071 -182.668195) (xy 59.521654 -182.690081) (xy 59.5915 -182.719558) (xy 59.657817 -182.756293)
			(xy 59.719853 -182.799868) (xy 59.776906 -182.84979) (xy 59.82833 -182.905494) (xy 59.873541 -182.966349)
			(xy 59.912028 -183.031664) (xy 59.943354 -183.1007) (xy 59.967164 -183.172675) (xy 59.983189 -183.246773)
			(xy 59.991248 -183.322154) (xy 59.991752 -183.36006) (xy 61.107831 -183.36006) (xy 61.111866 -183.284356)
			(xy 61.123925 -183.209511) (xy 61.143871 -183.13637) (xy 61.171478 -183.065765) (xy 61.206434 -182.998494)
			(xy 61.248342 -182.935319) (xy 61.296728 -182.876957) (xy 61.351044 -182.824069) (xy 61.410673 -182.777254)
			(xy 61.474941 -182.737042) (xy 61.543118 -182.70389) (xy 61.614434 -182.678172) (xy 61.688079 -182.66018)
			(xy 61.763219 -182.650118) (xy 61.839003 -182.648099) (xy 61.914573 -182.654148) (xy 61.989071 -182.668195)
			(xy 62.061654 -182.690081) (xy 62.1315 -182.719558) (xy 62.197817 -182.756293) (xy 62.259853 -182.799868)
			(xy 62.316906 -182.84979) (xy 62.36833 -182.905494) (xy 62.413541 -182.966349) (xy 62.452028 -183.031664)
			(xy 62.483354 -183.1007) (xy 62.507164 -183.172675) (xy 62.523189 -183.246773) (xy 62.531248 -183.322154)
			(xy 62.531752 -183.36006) (xy 62.531248 -183.397966) (xy 62.523189 -183.473347) (xy 62.507164 -183.547445)
			(xy 62.483354 -183.61942) (xy 62.452028 -183.688456) (xy 62.413541 -183.753771) (xy 62.36833 -183.814626)
			(xy 62.316906 -183.87033) (xy 62.259853 -183.920252) (xy 62.197817 -183.963827) (xy 62.1315 -184.000562)
			(xy 62.061654 -184.030039) (xy 61.989071 -184.051925) (xy 61.914573 -184.065972) (xy 61.839003 -184.072021)
			(xy 61.763219 -184.070002) (xy 61.688079 -184.05994) (xy 61.614434 -184.041948) (xy 61.543118 -184.01623)
			(xy 61.474941 -183.983078) (xy 61.410673 -183.942866) (xy 61.351044 -183.896051) (xy 61.296728 -183.843163)
			(xy 61.248342 -183.784801) (xy 61.206434 -183.721626) (xy 61.171478 -183.654355) (xy 61.143871 -183.58375)
			(xy 61.123925 -183.510609) (xy 61.111866 -183.435764) (xy 61.107831 -183.36006) (xy 59.991752 -183.36006)
			(xy 59.991248 -183.397966) (xy 59.983189 -183.473347) (xy 59.967164 -183.547445) (xy 59.943354 -183.61942)
			(xy 59.912028 -183.688456) (xy 59.873541 -183.753771) (xy 59.82833 -183.814626) (xy 59.776906 -183.87033)
			(xy 59.719853 -183.920252) (xy 59.657817 -183.963827) (xy 59.5915 -184.000562) (xy 59.521654 -184.030039)
			(xy 59.449071 -184.051925) (xy 59.374573 -184.065972) (xy 59.299003 -184.072021) (xy 59.223219 -184.070002)
			(xy 59.148079 -184.05994) (xy 59.074434 -184.041948) (xy 59.003118 -184.01623) (xy 58.934941 -183.983078)
			(xy 58.870673 -183.942866) (xy 58.811044 -183.896051) (xy 58.756728 -183.843163) (xy 58.708342 -183.784801)
			(xy 58.666434 -183.721626) (xy 58.631478 -183.654355) (xy 58.603871 -183.58375) (xy 58.583925 -183.510609)
			(xy 58.571866 -183.435764) (xy 58.567831 -183.36006) (xy 57.451752 -183.36006) (xy 57.451248 -183.397966)
			(xy 57.443189 -183.473347) (xy 57.427164 -183.547445) (xy 57.403354 -183.61942) (xy 57.372028 -183.688456)
			(xy 57.333541 -183.753771) (xy 57.28833 -183.814626) (xy 57.236906 -183.87033) (xy 57.179853 -183.920252)
			(xy 57.117817 -183.963827) (xy 57.0515 -184.000562) (xy 56.981654 -184.030039) (xy 56.909071 -184.051925)
			(xy 56.834573 -184.065972) (xy 56.759003 -184.072021) (xy 56.683219 -184.070002) (xy 56.608079 -184.05994)
			(xy 56.534434 -184.041948) (xy 56.463118 -184.01623) (xy 56.394941 -183.983078) (xy 56.330673 -183.942866)
			(xy 56.271044 -183.896051) (xy 56.216728 -183.843163) (xy 56.168342 -183.784801) (xy 56.126434 -183.721626)
			(xy 56.091478 -183.654355) (xy 56.063871 -183.58375) (xy 56.043925 -183.510609) (xy 56.031866 -183.435764)
			(xy 56.027831 -183.36006) (xy 54.911752 -183.36006) (xy 54.911248 -183.397966) (xy 54.903189 -183.473347)
			(xy 54.887164 -183.547445) (xy 54.863354 -183.61942) (xy 54.832028 -183.688456) (xy 54.793541 -183.753771)
			(xy 54.74833 -183.814626) (xy 54.696906 -183.87033) (xy 54.639853 -183.920252) (xy 54.577817 -183.963827)
			(xy 54.5115 -184.000562) (xy 54.441654 -184.030039) (xy 54.369071 -184.051925) (xy 54.294573 -184.065972)
			(xy 54.219003 -184.072021) (xy 54.143219 -184.070002) (xy 54.068079 -184.05994) (xy 53.994434 -184.041948)
			(xy 53.923118 -184.01623) (xy 53.854941 -183.983078) (xy 53.790673 -183.942866) (xy 53.731044 -183.896051)
			(xy 53.676728 -183.843163) (xy 53.628342 -183.784801) (xy 53.586434 -183.721626) (xy 53.551478 -183.654355)
			(xy 53.523871 -183.58375) (xy 53.503925 -183.510609) (xy 53.491866 -183.435764) (xy 53.487831 -183.36006)
			(xy 52.371752 -183.36006) (xy 52.371248 -183.397966) (xy 52.363189 -183.473347) (xy 52.347164 -183.547445)
			(xy 52.323354 -183.61942) (xy 52.292028 -183.688456) (xy 52.253541 -183.753771) (xy 52.20833 -183.814626)
			(xy 52.156906 -183.87033) (xy 52.099853 -183.920252) (xy 52.037817 -183.963827) (xy 51.9715 -184.000562)
			(xy 51.901654 -184.030039) (xy 51.829071 -184.051925) (xy 51.754573 -184.065972) (xy 51.679003 -184.072021)
			(xy 51.603219 -184.070002) (xy 51.528079 -184.05994) (xy 51.454434 -184.041948) (xy 51.383118 -184.01623)
			(xy 51.314941 -183.983078) (xy 51.250673 -183.942866) (xy 51.191044 -183.896051) (xy 51.136728 -183.843163)
			(xy 51.088342 -183.784801) (xy 51.046434 -183.721626) (xy 51.011478 -183.654355) (xy 50.983871 -183.58375)
			(xy 50.963925 -183.510609) (xy 50.951866 -183.435764) (xy 50.947831 -183.36006) (xy 49.831752 -183.36006)
			(xy 49.831248 -183.397966) (xy 49.823189 -183.473347) (xy 49.807164 -183.547445) (xy 49.783354 -183.61942)
			(xy 49.752028 -183.688456) (xy 49.713541 -183.753771) (xy 49.66833 -183.814626) (xy 49.616906 -183.87033)
			(xy 49.559853 -183.920252) (xy 49.497817 -183.963827) (xy 49.4315 -184.000562) (xy 49.361654 -184.030039)
			(xy 49.289071 -184.051925) (xy 49.214573 -184.065972) (xy 49.139003 -184.072021) (xy 49.063219 -184.070002)
			(xy 48.988079 -184.05994) (xy 48.914434 -184.041948) (xy 48.843118 -184.01623) (xy 48.774941 -183.983078)
			(xy 48.710673 -183.942866) (xy 48.651044 -183.896051) (xy 48.596728 -183.843163) (xy 48.548342 -183.784801)
			(xy 48.506434 -183.721626) (xy 48.471478 -183.654355) (xy 48.443871 -183.58375) (xy 48.423925 -183.510609)
			(xy 48.411866 -183.435764) (xy 48.407831 -183.36006) (xy 47.291752 -183.36006) (xy 47.291248 -183.397966)
			(xy 47.283189 -183.473347) (xy 47.267164 -183.547445) (xy 47.243354 -183.61942) (xy 47.212028 -183.688456)
			(xy 47.173541 -183.753771) (xy 47.12833 -183.814626) (xy 47.076906 -183.87033) (xy 47.019853 -183.920252)
			(xy 46.957817 -183.963827) (xy 46.8915 -184.000562) (xy 46.821654 -184.030039) (xy 46.749071 -184.051925)
			(xy 46.674573 -184.065972) (xy 46.599003 -184.072021) (xy 46.523219 -184.070002) (xy 46.448079 -184.05994)
			(xy 46.374434 -184.041948) (xy 46.303118 -184.01623) (xy 46.234941 -183.983078) (xy 46.170673 -183.942866)
			(xy 46.111044 -183.896051) (xy 46.056728 -183.843163) (xy 46.008342 -183.784801) (xy 45.966434 -183.721626)
			(xy 45.931478 -183.654355) (xy 45.903871 -183.58375) (xy 45.883925 -183.510609) (xy 45.871866 -183.435764)
			(xy 45.867831 -183.36006) (xy 44.751752 -183.36006) (xy 44.751248 -183.397966) (xy 44.743189 -183.473347)
			(xy 44.727164 -183.547445) (xy 44.703354 -183.61942) (xy 44.672028 -183.688456) (xy 44.633541 -183.753771)
			(xy 44.58833 -183.814626) (xy 44.536906 -183.87033) (xy 44.479853 -183.920252) (xy 44.417817 -183.963827)
			(xy 44.3515 -184.000562) (xy 44.281654 -184.030039) (xy 44.209071 -184.051925) (xy 44.134573 -184.065972)
			(xy 44.059003 -184.072021) (xy 43.983219 -184.070002) (xy 43.908079 -184.05994) (xy 43.834434 -184.041948)
			(xy 43.763118 -184.01623) (xy 43.694941 -183.983078) (xy 43.630673 -183.942866) (xy 43.571044 -183.896051)
			(xy 43.516728 -183.843163) (xy 43.468342 -183.784801) (xy 43.426434 -183.721626) (xy 43.391478 -183.654355)
			(xy 43.363871 -183.58375) (xy 43.343925 -183.510609) (xy 43.331866 -183.435764) (xy 43.327831 -183.36006)
			(xy 42.501941 -183.36006) (xy 42.582117 -183.422834) (xy 42.669176 -183.501374) (xy 42.750551 -183.585789)
			(xy 42.825845 -183.675669) (xy 42.894694 -183.770578) (xy 42.956761 -183.870054) (xy 43.011746 -183.973612)
			(xy 43.059381 -184.080751) (xy 43.099434 -184.190948) (xy 43.131712 -184.303669) (xy 43.156056 -184.418365)
			(xy 43.172348 -184.534478) (xy 43.18051 -184.651445) (xy 43.181016 -184.71007) (xy 43.180861 -184.740833)
			(xy 43.178574 -184.802316) (xy 43.176444 -184.833006) (xy 43.175682 -184.842404) (xy 43.170622 -184.900806)
			(xy 43.153396 -185.016771) (xy 43.12813 -185.131253) (xy 43.094949 -185.243697) (xy 43.054014 -185.353555)
			(xy 43.005523 -185.460294) (xy 42.949712 -185.563395) (xy 42.886853 -185.662356) (xy 42.817252 -185.756696)
			(xy 42.741246 -185.845958) (xy 42.659204 -185.929706) (xy 42.571527 -186.007535) (xy 42.503292 -186.06008)
			(xy 43.327831 -186.06008) (xy 43.331866 -185.984376) (xy 43.343925 -185.909531) (xy 43.363871 -185.83639)
			(xy 43.391478 -185.765785) (xy 43.426434 -185.698514) (xy 43.468342 -185.635339) (xy 43.516728 -185.576977)
			(xy 43.571044 -185.524089) (xy 43.630673 -185.477274) (xy 43.694941 -185.437062) (xy 43.763118 -185.40391)
			(xy 43.834434 -185.378192) (xy 43.908079 -185.3602) (xy 43.983219 -185.350138) (xy 44.059003 -185.348119)
			(xy 44.134573 -185.354168) (xy 44.209071 -185.368215) (xy 44.281654 -185.390101) (xy 44.3515 -185.419578)
			(xy 44.417817 -185.456313) (xy 44.479853 -185.499888) (xy 44.536906 -185.54981) (xy 44.58833 -185.605514)
			(xy 44.633541 -185.666369) (xy 44.672028 -185.731684) (xy 44.703354 -185.80072) (xy 44.727164 -185.872695)
			(xy 44.743189 -185.946793) (xy 44.751248 -186.022174) (xy 44.751752 -186.06008) (xy 45.867831 -186.06008)
			(xy 45.871866 -185.984376) (xy 45.883925 -185.909531) (xy 45.903871 -185.83639) (xy 45.931478 -185.765785)
			(xy 45.966434 -185.698514) (xy 46.008342 -185.635339) (xy 46.056728 -185.576977) (xy 46.111044 -185.524089)
			(xy 46.170673 -185.477274) (xy 46.234941 -185.437062) (xy 46.303118 -185.40391) (xy 46.374434 -185.378192)
			(xy 46.448079 -185.3602) (xy 46.523219 -185.350138) (xy 46.599003 -185.348119) (xy 46.674573 -185.354168)
			(xy 46.749071 -185.368215) (xy 46.821654 -185.390101) (xy 46.8915 -185.419578) (xy 46.957817 -185.456313)
			(xy 47.019853 -185.499888) (xy 47.076906 -185.54981) (xy 47.12833 -185.605514) (xy 47.173541 -185.666369)
			(xy 47.212028 -185.731684) (xy 47.243354 -185.80072) (xy 47.267164 -185.872695) (xy 47.283189 -185.946793)
			(xy 47.291248 -186.022174) (xy 47.291752 -186.06008) (xy 48.407831 -186.06008) (xy 48.411866 -185.984376)
			(xy 48.423925 -185.909531) (xy 48.443871 -185.83639) (xy 48.471478 -185.765785) (xy 48.506434 -185.698514)
			(xy 48.548342 -185.635339) (xy 48.596728 -185.576977) (xy 48.651044 -185.524089) (xy 48.710673 -185.477274)
			(xy 48.774941 -185.437062) (xy 48.843118 -185.40391) (xy 48.914434 -185.378192) (xy 48.988079 -185.3602)
			(xy 49.063219 -185.350138) (xy 49.139003 -185.348119) (xy 49.214573 -185.354168) (xy 49.289071 -185.368215)
			(xy 49.361654 -185.390101) (xy 49.4315 -185.419578) (xy 49.497817 -185.456313) (xy 49.559853 -185.499888)
			(xy 49.616906 -185.54981) (xy 49.66833 -185.605514) (xy 49.713541 -185.666369) (xy 49.752028 -185.731684)
			(xy 49.783354 -185.80072) (xy 49.807164 -185.872695) (xy 49.823189 -185.946793) (xy 49.831248 -186.022174)
			(xy 49.831752 -186.06008) (xy 50.947831 -186.06008) (xy 50.951866 -185.984376) (xy 50.963925 -185.909531)
			(xy 50.983871 -185.83639) (xy 51.011478 -185.765785) (xy 51.046434 -185.698514) (xy 51.088342 -185.635339)
			(xy 51.136728 -185.576977) (xy 51.191044 -185.524089) (xy 51.250673 -185.477274) (xy 51.314941 -185.437062)
			(xy 51.383118 -185.40391) (xy 51.454434 -185.378192) (xy 51.528079 -185.3602) (xy 51.603219 -185.350138)
			(xy 51.679003 -185.348119) (xy 51.754573 -185.354168) (xy 51.829071 -185.368215) (xy 51.901654 -185.390101)
			(xy 51.9715 -185.419578) (xy 52.037817 -185.456313) (xy 52.099853 -185.499888) (xy 52.156906 -185.54981)
			(xy 52.20833 -185.605514) (xy 52.253541 -185.666369) (xy 52.292028 -185.731684) (xy 52.323354 -185.80072)
			(xy 52.347164 -185.872695) (xy 52.363189 -185.946793) (xy 52.371248 -186.022174) (xy 52.371752 -186.06008)
			(xy 53.487831 -186.06008) (xy 53.491866 -185.984376) (xy 53.503925 -185.909531) (xy 53.523871 -185.83639)
			(xy 53.551478 -185.765785) (xy 53.586434 -185.698514) (xy 53.628342 -185.635339) (xy 53.676728 -185.576977)
			(xy 53.731044 -185.524089) (xy 53.790673 -185.477274) (xy 53.854941 -185.437062) (xy 53.923118 -185.40391)
			(xy 53.994434 -185.378192) (xy 54.068079 -185.3602) (xy 54.143219 -185.350138) (xy 54.219003 -185.348119)
			(xy 54.294573 -185.354168) (xy 54.369071 -185.368215) (xy 54.441654 -185.390101) (xy 54.5115 -185.419578)
			(xy 54.577817 -185.456313) (xy 54.639853 -185.499888) (xy 54.696906 -185.54981) (xy 54.74833 -185.605514)
			(xy 54.793541 -185.666369) (xy 54.832028 -185.731684) (xy 54.863354 -185.80072) (xy 54.887164 -185.872695)
			(xy 54.903189 -185.946793) (xy 54.911248 -186.022174) (xy 54.911752 -186.06008) (xy 56.027831 -186.06008)
			(xy 56.031866 -185.984376) (xy 56.043925 -185.909531) (xy 56.063871 -185.83639) (xy 56.091478 -185.765785)
			(xy 56.126434 -185.698514) (xy 56.168342 -185.635339) (xy 56.216728 -185.576977) (xy 56.271044 -185.524089)
			(xy 56.330673 -185.477274) (xy 56.394941 -185.437062) (xy 56.463118 -185.40391) (xy 56.534434 -185.378192)
			(xy 56.608079 -185.3602) (xy 56.683219 -185.350138) (xy 56.759003 -185.348119) (xy 56.834573 -185.354168)
			(xy 56.909071 -185.368215) (xy 56.981654 -185.390101) (xy 57.0515 -185.419578) (xy 57.117817 -185.456313)
			(xy 57.179853 -185.499888) (xy 57.236906 -185.54981) (xy 57.28833 -185.605514) (xy 57.333541 -185.666369)
			(xy 57.372028 -185.731684) (xy 57.403354 -185.80072) (xy 57.427164 -185.872695) (xy 57.443189 -185.946793)
			(xy 57.451248 -186.022174) (xy 57.451752 -186.06008) (xy 58.567831 -186.06008) (xy 58.571866 -185.984376)
			(xy 58.583925 -185.909531) (xy 58.603871 -185.83639) (xy 58.631478 -185.765785) (xy 58.666434 -185.698514)
			(xy 58.708342 -185.635339) (xy 58.756728 -185.576977) (xy 58.811044 -185.524089) (xy 58.870673 -185.477274)
			(xy 58.934941 -185.437062) (xy 59.003118 -185.40391) (xy 59.074434 -185.378192) (xy 59.148079 -185.3602)
			(xy 59.223219 -185.350138) (xy 59.299003 -185.348119) (xy 59.374573 -185.354168) (xy 59.449071 -185.368215)
			(xy 59.521654 -185.390101) (xy 59.5915 -185.419578) (xy 59.657817 -185.456313) (xy 59.719853 -185.499888)
			(xy 59.776906 -185.54981) (xy 59.82833 -185.605514) (xy 59.873541 -185.666369) (xy 59.912028 -185.731684)
			(xy 59.943354 -185.80072) (xy 59.967164 -185.872695) (xy 59.983189 -185.946793) (xy 59.991248 -186.022174)
			(xy 59.991752 -186.06008) (xy 61.107831 -186.06008) (xy 61.111866 -185.984376) (xy 61.123925 -185.909531)
			(xy 61.143871 -185.83639) (xy 61.171478 -185.765785) (xy 61.206434 -185.698514) (xy 61.248342 -185.635339)
			(xy 61.296728 -185.576977) (xy 61.351044 -185.524089) (xy 61.410673 -185.477274) (xy 61.474941 -185.437062)
			(xy 61.543118 -185.40391) (xy 61.614434 -185.378192) (xy 61.688079 -185.3602) (xy 61.763219 -185.350138)
			(xy 61.839003 -185.348119) (xy 61.914573 -185.354168) (xy 61.989071 -185.368215) (xy 62.061654 -185.390101)
			(xy 62.1315 -185.419578) (xy 62.197817 -185.456313) (xy 62.259853 -185.499888) (xy 62.316906 -185.54981)
			(xy 62.36833 -185.605514) (xy 62.413541 -185.666369) (xy 62.452028 -185.731684) (xy 62.483354 -185.80072)
			(xy 62.507164 -185.872695) (xy 62.523189 -185.946793) (xy 62.531248 -186.022174) (xy 62.531752 -186.06008)
			(xy 62.531248 -186.097986) (xy 62.523189 -186.173367) (xy 62.507164 -186.247465) (xy 62.483354 -186.31944)
			(xy 62.452028 -186.388476) (xy 62.413541 -186.453791) (xy 62.36833 -186.514646) (xy 62.316906 -186.57035)
			(xy 62.259853 -186.620272) (xy 62.197817 -186.663847) (xy 62.1315 -186.700582) (xy 62.061654 -186.730059)
			(xy 61.989071 -186.751945) (xy 61.914573 -186.765992) (xy 61.839003 -186.772041) (xy 61.763219 -186.770022)
			(xy 61.688079 -186.75996) (xy 61.614434 -186.741968) (xy 61.543118 -186.71625) (xy 61.474941 -186.683098)
			(xy 61.410673 -186.642886) (xy 61.351044 -186.596071) (xy 61.296728 -186.543183) (xy 61.248342 -186.484821)
			(xy 61.206434 -186.421646) (xy 61.171478 -186.354375) (xy 61.143871 -186.28377) (xy 61.123925 -186.210629)
			(xy 61.111866 -186.135784) (xy 61.107831 -186.06008) (xy 59.991752 -186.06008) (xy 59.991248 -186.097986)
			(xy 59.983189 -186.173367) (xy 59.967164 -186.247465) (xy 59.943354 -186.31944) (xy 59.912028 -186.388476)
			(xy 59.873541 -186.453791) (xy 59.82833 -186.514646) (xy 59.776906 -186.57035) (xy 59.719853 -186.620272)
			(xy 59.657817 -186.663847) (xy 59.5915 -186.700582) (xy 59.521654 -186.730059) (xy 59.449071 -186.751945)
			(xy 59.374573 -186.765992) (xy 59.299003 -186.772041) (xy 59.223219 -186.770022) (xy 59.148079 -186.75996)
			(xy 59.074434 -186.741968) (xy 59.003118 -186.71625) (xy 58.934941 -186.683098) (xy 58.870673 -186.642886)
			(xy 58.811044 -186.596071) (xy 58.756728 -186.543183) (xy 58.708342 -186.484821) (xy 58.666434 -186.421646)
			(xy 58.631478 -186.354375) (xy 58.603871 -186.28377) (xy 58.583925 -186.210629) (xy 58.571866 -186.135784)
			(xy 58.567831 -186.06008) (xy 57.451752 -186.06008) (xy 57.451248 -186.097986) (xy 57.443189 -186.173367)
			(xy 57.427164 -186.247465) (xy 57.403354 -186.31944) (xy 57.372028 -186.388476) (xy 57.333541 -186.453791)
			(xy 57.28833 -186.514646) (xy 57.236906 -186.57035) (xy 57.179853 -186.620272) (xy 57.117817 -186.663847)
			(xy 57.0515 -186.700582) (xy 56.981654 -186.730059) (xy 56.909071 -186.751945) (xy 56.834573 -186.765992)
			(xy 56.759003 -186.772041) (xy 56.683219 -186.770022) (xy 56.608079 -186.75996) (xy 56.534434 -186.741968)
			(xy 56.463118 -186.71625) (xy 56.394941 -186.683098) (xy 56.330673 -186.642886) (xy 56.271044 -186.596071)
			(xy 56.216728 -186.543183) (xy 56.168342 -186.484821) (xy 56.126434 -186.421646) (xy 56.091478 -186.354375)
			(xy 56.063871 -186.28377) (xy 56.043925 -186.210629) (xy 56.031866 -186.135784) (xy 56.027831 -186.06008)
			(xy 54.911752 -186.06008) (xy 54.911248 -186.097986) (xy 54.903189 -186.173367) (xy 54.887164 -186.247465)
			(xy 54.863354 -186.31944) (xy 54.832028 -186.388476) (xy 54.793541 -186.453791) (xy 54.74833 -186.514646)
			(xy 54.696906 -186.57035) (xy 54.639853 -186.620272) (xy 54.577817 -186.663847) (xy 54.5115 -186.700582)
			(xy 54.441654 -186.730059) (xy 54.369071 -186.751945) (xy 54.294573 -186.765992) (xy 54.219003 -186.772041)
			(xy 54.143219 -186.770022) (xy 54.068079 -186.75996) (xy 53.994434 -186.741968) (xy 53.923118 -186.71625)
			(xy 53.854941 -186.683098) (xy 53.790673 -186.642886) (xy 53.731044 -186.596071) (xy 53.676728 -186.543183)
			(xy 53.628342 -186.484821) (xy 53.586434 -186.421646) (xy 53.551478 -186.354375) (xy 53.523871 -186.28377)
			(xy 53.503925 -186.210629) (xy 53.491866 -186.135784) (xy 53.487831 -186.06008) (xy 52.371752 -186.06008)
			(xy 52.371248 -186.097986) (xy 52.363189 -186.173367) (xy 52.347164 -186.247465) (xy 52.323354 -186.31944)
			(xy 52.292028 -186.388476) (xy 52.253541 -186.453791) (xy 52.20833 -186.514646) (xy 52.156906 -186.57035)
			(xy 52.099853 -186.620272) (xy 52.037817 -186.663847) (xy 51.9715 -186.700582) (xy 51.901654 -186.730059)
			(xy 51.829071 -186.751945) (xy 51.754573 -186.765992) (xy 51.679003 -186.772041) (xy 51.603219 -186.770022)
			(xy 51.528079 -186.75996) (xy 51.454434 -186.741968) (xy 51.383118 -186.71625) (xy 51.314941 -186.683098)
			(xy 51.250673 -186.642886) (xy 51.191044 -186.596071) (xy 51.136728 -186.543183) (xy 51.088342 -186.484821)
			(xy 51.046434 -186.421646) (xy 51.011478 -186.354375) (xy 50.983871 -186.28377) (xy 50.963925 -186.210629)
			(xy 50.951866 -186.135784) (xy 50.947831 -186.06008) (xy 49.831752 -186.06008) (xy 49.831248 -186.097986)
			(xy 49.823189 -186.173367) (xy 49.807164 -186.247465) (xy 49.783354 -186.31944) (xy 49.752028 -186.388476)
			(xy 49.713541 -186.453791) (xy 49.66833 -186.514646) (xy 49.616906 -186.57035) (xy 49.559853 -186.620272)
			(xy 49.497817 -186.663847) (xy 49.4315 -186.700582) (xy 49.361654 -186.730059) (xy 49.289071 -186.751945)
			(xy 49.214573 -186.765992) (xy 49.139003 -186.772041) (xy 49.063219 -186.770022) (xy 48.988079 -186.75996)
			(xy 48.914434 -186.741968) (xy 48.843118 -186.71625) (xy 48.774941 -186.683098) (xy 48.710673 -186.642886)
			(xy 48.651044 -186.596071) (xy 48.596728 -186.543183) (xy 48.548342 -186.484821) (xy 48.506434 -186.421646)
			(xy 48.471478 -186.354375) (xy 48.443871 -186.28377) (xy 48.423925 -186.210629) (xy 48.411866 -186.135784)
			(xy 48.407831 -186.06008) (xy 47.291752 -186.06008) (xy 47.291248 -186.097986) (xy 47.283189 -186.173367)
			(xy 47.267164 -186.247465) (xy 47.243354 -186.31944) (xy 47.212028 -186.388476) (xy 47.173541 -186.453791)
			(xy 47.12833 -186.514646) (xy 47.076906 -186.57035) (xy 47.019853 -186.620272) (xy 46.957817 -186.663847)
			(xy 46.8915 -186.700582) (xy 46.821654 -186.730059) (xy 46.749071 -186.751945) (xy 46.674573 -186.765992)
			(xy 46.599003 -186.772041) (xy 46.523219 -186.770022) (xy 46.448079 -186.75996) (xy 46.374434 -186.741968)
			(xy 46.303118 -186.71625) (xy 46.234941 -186.683098) (xy 46.170673 -186.642886) (xy 46.111044 -186.596071)
			(xy 46.056728 -186.543183) (xy 46.008342 -186.484821) (xy 45.966434 -186.421646) (xy 45.931478 -186.354375)
			(xy 45.903871 -186.28377) (xy 45.883925 -186.210629) (xy 45.871866 -186.135784) (xy 45.867831 -186.06008)
			(xy 44.751752 -186.06008) (xy 44.751248 -186.097986) (xy 44.743189 -186.173367) (xy 44.727164 -186.247465)
			(xy 44.703354 -186.31944) (xy 44.672028 -186.388476) (xy 44.633541 -186.453791) (xy 44.58833 -186.514646)
			(xy 44.536906 -186.57035) (xy 44.479853 -186.620272) (xy 44.417817 -186.663847) (xy 44.3515 -186.700582)
			(xy 44.281654 -186.730059) (xy 44.209071 -186.751945) (xy 44.134573 -186.765992) (xy 44.059003 -186.772041)
			(xy 43.983219 -186.770022) (xy 43.908079 -186.75996) (xy 43.834434 -186.741968) (xy 43.763118 -186.71625)
			(xy 43.694941 -186.683098) (xy 43.630673 -186.642886) (xy 43.571044 -186.596071) (xy 43.516728 -186.543183)
			(xy 43.468342 -186.484821) (xy 43.426434 -186.421646) (xy 43.391478 -186.354375) (xy 43.363871 -186.28377)
			(xy 43.343925 -186.210629) (xy 43.331866 -186.135784) (xy 43.327831 -186.06008) (xy 42.503292 -186.06008)
			(xy 42.47864 -186.079064) (xy 42.380994 -186.143948) (xy 42.279065 -186.20187) (xy 42.173347 -186.252549)
			(xy 42.064355 -186.295738) (xy 41.952619 -186.331228) (xy 41.838681 -186.358845) (xy 41.723096 -186.378457)
			(xy 41.606425 -186.389967) (xy 41.489236 -186.393319) (xy 41.372098 -186.388497) (xy 41.25558 -186.375525)
			(xy 41.14025 -186.354466) (xy 41.026668 -186.325421) (xy 40.915385 -186.288533) (xy 40.806943 -186.24398)
			(xy 40.70187 -186.19198) (xy 40.600675 -186.132784) (xy 40.50385 -186.066681) (xy 40.411868 -185.993992)
			(xy 40.325173 -185.91507) (xy 40.244189 -185.830299) (xy 40.169308 -185.740091) (xy 40.100895 -185.644885)
			(xy 40.039282 -185.545143) (xy 39.984769 -185.441351) (xy 39.937621 -185.334012) (xy 39.898066 -185.223649)
			(xy 39.866298 -185.110798) (xy 39.842471 -184.996008) (xy 39.826699 -184.879836) (xy 39.819061 -184.762848)
			(xy 39.818818 -184.704228) (xy 36.07398 -184.704228) (xy 36.071366 -184.706202) (xy 35.997482 -184.751949)
			(xy 35.919693 -184.790683) (xy 35.838661 -184.822075) (xy 35.755079 -184.845856) (xy 35.669659 -184.861824)
			(xy 35.58313 -184.869842) (xy 35.49623 -184.869842) (xy 35.409701 -184.861824) (xy 35.324281 -184.845856)
			(xy 35.240699 -184.822075) (xy 35.159667 -184.790683) (xy 35.081878 -184.751949) (xy 35.007994 -184.706202)
			(xy 34.938647 -184.653833) (xy 34.874427 -184.595289) (xy 34.815883 -184.531069) (xy 34.763514 -184.461722)
			(xy 34.717767 -184.387838) (xy 34.679033 -184.310049) (xy 34.647641 -184.229017) (xy 34.62386 -184.145435)
			(xy 34.607892 -184.060015) (xy 34.599874 -183.973486) (xy 31.399486 -183.973486) (xy 31.391468 -184.060015)
			(xy 31.3755 -184.145435) (xy 31.351719 -184.229017) (xy 31.320327 -184.310049) (xy 31.281593 -184.387838)
			(xy 31.235846 -184.461722) (xy 31.183477 -184.531069) (xy 31.124933 -184.595289) (xy 31.060713 -184.653833)
			(xy 30.991366 -184.706202) (xy 30.917482 -184.751949) (xy 30.839693 -184.790683) (xy 30.758661 -184.822075)
			(xy 30.675079 -184.845856) (xy 30.589659 -184.861824) (xy 30.50313 -184.869842) (xy 30.41623 -184.869842)
			(xy 30.329701 -184.861824) (xy 30.244281 -184.845856) (xy 30.160699 -184.822075) (xy 30.079667 -184.790683)
			(xy 30.001878 -184.751949) (xy 29.927994 -184.706202) (xy 29.858647 -184.653833) (xy 29.794427 -184.595289)
			(xy 29.735883 -184.531069) (xy 29.683514 -184.461722) (xy 29.637767 -184.387838) (xy 29.599033 -184.310049)
			(xy 29.567641 -184.229017) (xy 29.54386 -184.145435) (xy 29.527892 -184.060015) (xy 29.519874 -183.973486)
			(xy 28.461716 -183.973486) (xy 28.461716 -186.513486) (xy 29.519874 -186.513486) (xy 29.519874 -186.426586)
			(xy 29.527892 -186.340057) (xy 29.54386 -186.254637) (xy 29.567641 -186.171055) (xy 29.599033 -186.090023)
			(xy 29.637767 -186.012234) (xy 29.683514 -185.93835) (xy 29.735883 -185.869003) (xy 29.794427 -185.804783)
			(xy 29.858647 -185.746239) (xy 29.927994 -185.69387) (xy 30.001878 -185.648123) (xy 30.079667 -185.609389)
			(xy 30.160699 -185.577997) (xy 30.244281 -185.554216) (xy 30.329701 -185.538248) (xy 30.41623 -185.53023)
			(xy 30.50313 -185.53023) (xy 30.589659 -185.538248) (xy 30.675079 -185.554216) (xy 30.758661 -185.577997)
			(xy 30.839693 -185.609389) (xy 30.917482 -185.648123) (xy 30.991366 -185.69387) (xy 31.060713 -185.746239)
			(xy 31.124933 -185.804783) (xy 31.183477 -185.869003) (xy 31.235846 -185.93835) (xy 31.281593 -186.012234)
			(xy 31.320327 -186.090023) (xy 31.351719 -186.171055) (xy 31.3755 -186.254637) (xy 31.391468 -186.340057)
			(xy 31.399486 -186.426586) (xy 31.399988 -186.470036) (xy 31.399486 -186.513486) (xy 34.599874 -186.513486)
			(xy 34.599874 -186.426586) (xy 34.607892 -186.340057) (xy 34.62386 -186.254637) (xy 34.647641 -186.171055)
			(xy 34.679033 -186.090023) (xy 34.717767 -186.012234) (xy 34.763514 -185.93835) (xy 34.815883 -185.869003)
			(xy 34.874427 -185.804783) (xy 34.938647 -185.746239) (xy 35.007994 -185.69387) (xy 35.081878 -185.648123)
			(xy 35.159667 -185.609389) (xy 35.240699 -185.577997) (xy 35.324281 -185.554216) (xy 35.409701 -185.538248)
			(xy 35.49623 -185.53023) (xy 35.58313 -185.53023) (xy 35.669659 -185.538248) (xy 35.755079 -185.554216)
			(xy 35.838661 -185.577997) (xy 35.919693 -185.609389) (xy 35.997482 -185.648123) (xy 36.071366 -185.69387)
			(xy 36.140713 -185.746239) (xy 36.204933 -185.804783) (xy 36.263477 -185.869003) (xy 36.315846 -185.93835)
			(xy 36.361593 -186.012234) (xy 36.400327 -186.090023) (xy 36.431719 -186.171055) (xy 36.4555 -186.254637)
			(xy 36.471468 -186.340057) (xy 36.479486 -186.426586) (xy 36.479988 -186.470036) (xy 36.479486 -186.513486)
			(xy 36.471468 -186.600015) (xy 36.4555 -186.685435) (xy 36.431719 -186.769017) (xy 36.400327 -186.850049)
			(xy 36.361593 -186.927838) (xy 36.315846 -187.001722) (xy 36.263477 -187.071069) (xy 36.204933 -187.135289)
			(xy 36.140713 -187.193833) (xy 36.071366 -187.246202) (xy 35.997482 -187.291949) (xy 35.919693 -187.330683)
			(xy 35.838661 -187.362075) (xy 35.755079 -187.385856) (xy 35.669659 -187.401824) (xy 35.58313 -187.409842)
			(xy 35.49623 -187.409842) (xy 35.409701 -187.401824) (xy 35.324281 -187.385856) (xy 35.240699 -187.362075)
			(xy 35.159667 -187.330683) (xy 35.081878 -187.291949) (xy 35.007994 -187.246202) (xy 34.938647 -187.193833)
			(xy 34.874427 -187.135289) (xy 34.815883 -187.071069) (xy 34.763514 -187.001722) (xy 34.717767 -186.927838)
			(xy 34.679033 -186.850049) (xy 34.647641 -186.769017) (xy 34.62386 -186.685435) (xy 34.607892 -186.600015)
			(xy 34.599874 -186.513486) (xy 31.399486 -186.513486) (xy 31.391468 -186.600015) (xy 31.3755 -186.685435)
			(xy 31.351719 -186.769017) (xy 31.320327 -186.850049) (xy 31.281593 -186.927838) (xy 31.235846 -187.001722)
			(xy 31.183477 -187.071069) (xy 31.124933 -187.135289) (xy 31.060713 -187.193833) (xy 30.991366 -187.246202)
			(xy 30.917482 -187.291949) (xy 30.839693 -187.330683) (xy 30.758661 -187.362075) (xy 30.675079 -187.385856)
			(xy 30.589659 -187.401824) (xy 30.50313 -187.409842) (xy 30.41623 -187.409842) (xy 30.329701 -187.401824)
			(xy 30.244281 -187.385856) (xy 30.160699 -187.362075) (xy 30.079667 -187.330683) (xy 30.001878 -187.291949)
			(xy 29.927994 -187.246202) (xy 29.858647 -187.193833) (xy 29.794427 -187.135289) (xy 29.735883 -187.071069)
			(xy 29.683514 -187.001722) (xy 29.637767 -186.927838) (xy 29.599033 -186.850049) (xy 29.567641 -186.769017)
			(xy 29.54386 -186.685435) (xy 29.527892 -186.600015) (xy 29.519874 -186.513486) (xy 28.461716 -186.513486)
			(xy 28.461716 -189.053486) (xy 29.519874 -189.053486) (xy 29.519874 -188.966586) (xy 29.527892 -188.880057)
			(xy 29.54386 -188.794637) (xy 29.567641 -188.711055) (xy 29.599033 -188.630023) (xy 29.637767 -188.552234)
			(xy 29.683514 -188.47835) (xy 29.735883 -188.409003) (xy 29.794427 -188.344783) (xy 29.858647 -188.286239)
			(xy 29.927994 -188.23387) (xy 30.001878 -188.188123) (xy 30.079667 -188.149389) (xy 30.160699 -188.117997)
			(xy 30.244281 -188.094216) (xy 30.329701 -188.078248) (xy 30.41623 -188.07023) (xy 30.50313 -188.07023)
			(xy 30.589659 -188.078248) (xy 30.675079 -188.094216) (xy 30.758661 -188.117997) (xy 30.839693 -188.149389)
			(xy 30.917482 -188.188123) (xy 30.991366 -188.23387) (xy 31.060713 -188.286239) (xy 31.124933 -188.344783)
			(xy 31.183477 -188.409003) (xy 31.235846 -188.47835) (xy 31.281593 -188.552234) (xy 31.320327 -188.630023)
			(xy 31.351719 -188.711055) (xy 31.3755 -188.794637) (xy 31.391468 -188.880057) (xy 31.399486 -188.966586)
			(xy 31.399988 -189.010036) (xy 31.399486 -189.053486) (xy 34.599874 -189.053486) (xy 34.599874 -188.966586)
			(xy 34.607892 -188.880057) (xy 34.62386 -188.794637) (xy 34.647641 -188.711055) (xy 34.679033 -188.630023)
			(xy 34.717767 -188.552234) (xy 34.763514 -188.47835) (xy 34.815883 -188.409003) (xy 34.874427 -188.344783)
			(xy 34.938647 -188.286239) (xy 35.007994 -188.23387) (xy 35.081878 -188.188123) (xy 35.159667 -188.149389)
			(xy 35.240699 -188.117997) (xy 35.324281 -188.094216) (xy 35.409701 -188.078248) (xy 35.49623 -188.07023)
			(xy 35.58313 -188.07023) (xy 35.669659 -188.078248) (xy 35.755079 -188.094216) (xy 35.838661 -188.117997)
			(xy 35.919693 -188.149389) (xy 35.997482 -188.188123) (xy 36.071366 -188.23387) (xy 36.140713 -188.286239)
			(xy 36.204933 -188.344783) (xy 36.263477 -188.409003) (xy 36.315846 -188.47835) (xy 36.361593 -188.552234)
			(xy 36.400327 -188.630023) (xy 36.431719 -188.711055) (xy 36.4555 -188.794637) (xy 36.471468 -188.880057)
			(xy 36.479486 -188.966586) (xy 36.479988 -189.010036) (xy 36.479486 -189.053486) (xy 36.471468 -189.140015)
			(xy 36.4555 -189.225435) (xy 36.431719 -189.309017) (xy 36.400327 -189.390049) (xy 36.361593 -189.467838)
			(xy 36.315846 -189.541722) (xy 36.263477 -189.611069) (xy 36.204933 -189.675289) (xy 36.140713 -189.733833)
			(xy 36.071366 -189.786202) (xy 35.997482 -189.831949) (xy 35.919693 -189.870683) (xy 35.838661 -189.902075)
			(xy 35.755079 -189.925856) (xy 35.669659 -189.941824) (xy 35.58313 -189.949842) (xy 35.49623 -189.949842)
			(xy 35.409701 -189.941824) (xy 35.324281 -189.925856) (xy 35.240699 -189.902075) (xy 35.159667 -189.870683)
			(xy 35.081878 -189.831949) (xy 35.007994 -189.786202) (xy 34.938647 -189.733833) (xy 34.874427 -189.675289)
			(xy 34.815883 -189.611069) (xy 34.763514 -189.541722) (xy 34.717767 -189.467838) (xy 34.679033 -189.390049)
			(xy 34.647641 -189.309017) (xy 34.62386 -189.225435) (xy 34.607892 -189.140015) (xy 34.599874 -189.053486)
			(xy 31.399486 -189.053486) (xy 31.391468 -189.140015) (xy 31.3755 -189.225435) (xy 31.351719 -189.309017)
			(xy 31.320327 -189.390049) (xy 31.281593 -189.467838) (xy 31.235846 -189.541722) (xy 31.183477 -189.611069)
			(xy 31.124933 -189.675289) (xy 31.060713 -189.733833) (xy 30.991366 -189.786202) (xy 30.917482 -189.831949)
			(xy 30.839693 -189.870683) (xy 30.758661 -189.902075) (xy 30.675079 -189.925856) (xy 30.589659 -189.941824)
			(xy 30.50313 -189.949842) (xy 30.41623 -189.949842) (xy 30.329701 -189.941824) (xy 30.244281 -189.925856)
			(xy 30.160699 -189.902075) (xy 30.079667 -189.870683) (xy 30.001878 -189.831949) (xy 29.927994 -189.786202)
			(xy 29.858647 -189.733833) (xy 29.794427 -189.675289) (xy 29.735883 -189.611069) (xy 29.683514 -189.541722)
			(xy 29.637767 -189.467838) (xy 29.599033 -189.390049) (xy 29.567641 -189.309017) (xy 29.54386 -189.225435)
			(xy 29.527892 -189.140015) (xy 29.519874 -189.053486) (xy 28.461716 -189.053486) (xy 28.461716 -191.593486)
			(xy 29.519874 -191.593486) (xy 29.519874 -191.506586) (xy 29.527892 -191.420057) (xy 29.54386 -191.334637)
			(xy 29.567641 -191.251055) (xy 29.599033 -191.170023) (xy 29.637767 -191.092234) (xy 29.683514 -191.01835)
			(xy 29.735883 -190.949003) (xy 29.794427 -190.884783) (xy 29.858647 -190.826239) (xy 29.927994 -190.77387)
			(xy 30.001878 -190.728123) (xy 30.079667 -190.689389) (xy 30.160699 -190.657997) (xy 30.244281 -190.634216)
			(xy 30.329701 -190.618248) (xy 30.41623 -190.61023) (xy 30.50313 -190.61023) (xy 30.589659 -190.618248)
			(xy 30.675079 -190.634216) (xy 30.758661 -190.657997) (xy 30.839693 -190.689389) (xy 30.917482 -190.728123)
			(xy 30.991366 -190.77387) (xy 31.060713 -190.826239) (xy 31.124933 -190.884783) (xy 31.183477 -190.949003)
			(xy 31.235846 -191.01835) (xy 31.281593 -191.092234) (xy 31.320327 -191.170023) (xy 31.351719 -191.251055)
			(xy 31.3755 -191.334637) (xy 31.391468 -191.420057) (xy 31.399486 -191.506586) (xy 31.399988 -191.550036)
			(xy 31.399486 -191.593486) (xy 34.599874 -191.593486) (xy 34.599874 -191.506586) (xy 34.607892 -191.420057)
			(xy 34.62386 -191.334637) (xy 34.647641 -191.251055) (xy 34.679033 -191.170023) (xy 34.717767 -191.092234)
			(xy 34.763514 -191.01835) (xy 34.815883 -190.949003) (xy 34.874427 -190.884783) (xy 34.938647 -190.826239)
			(xy 35.007994 -190.77387) (xy 35.081878 -190.728123) (xy 35.159667 -190.689389) (xy 35.240699 -190.657997)
			(xy 35.324281 -190.634216) (xy 35.409701 -190.618248) (xy 35.49623 -190.61023) (xy 35.58313 -190.61023)
			(xy 35.669659 -190.618248) (xy 35.755079 -190.634216) (xy 35.838661 -190.657997) (xy 35.919693 -190.689389)
			(xy 35.997482 -190.728123) (xy 36.065119 -190.770002) (xy 39.396922 -190.770002) (xy 39.400993 -190.71438)
			(xy 39.413119 -190.659943) (xy 39.433042 -190.607852) (xy 39.460338 -190.559217) (xy 39.494424 -190.515074)
			(xy 39.534573 -190.476365) (xy 39.579931 -190.443914) (xy 39.629531 -190.418413) (xy 39.682315 -190.400406)
			(xy 39.737158 -190.390276) (xy 39.792892 -190.388239) (xy 39.848329 -190.394339) (xy 39.902286 -190.408445)
			(xy 39.953615 -190.430257) (xy 40.001221 -190.459311) (xy 40.044089 -190.494986) (xy 40.081306 -190.536523)
			(xy 40.112079 -190.583036) (xy 40.135751 -190.633533) (xy 40.151819 -190.68694) (xy 40.159939 -190.742116)
			(xy 40.160448 -190.770002) (xy 40.159939 -190.797888) (xy 40.151819 -190.853064) (xy 40.135751 -190.906471)
			(xy 40.112079 -190.956968) (xy 40.081306 -191.003481) (xy 40.044089 -191.045018) (xy 40.001221 -191.080693)
			(xy 39.953615 -191.109747) (xy 39.902286 -191.131559) (xy 39.848329 -191.145665) (xy 39.792892 -191.151765)
			(xy 39.737158 -191.149728) (xy 39.682315 -191.139598) (xy 39.629531 -191.121591) (xy 39.579931 -191.09609)
			(xy 39.534573 -191.063639) (xy 39.494424 -191.02493) (xy 39.460338 -190.980787) (xy 39.433042 -190.932152)
			(xy 39.413119 -190.880061) (xy 39.400993 -190.825624) (xy 39.396922 -190.770002) (xy 36.065119 -190.770002)
			(xy 36.071366 -190.77387) (xy 36.140713 -190.826239) (xy 36.204933 -190.884783) (xy 36.263477 -190.949003)
			(xy 36.315846 -191.01835) (xy 36.361593 -191.092234) (xy 36.400327 -191.170023) (xy 36.431719 -191.251055)
			(xy 36.4555 -191.334637) (xy 36.471468 -191.420057) (xy 36.479486 -191.506586) (xy 36.479988 -191.550036)
			(xy 36.479486 -191.593486) (xy 36.471468 -191.680015) (xy 36.4555 -191.765435) (xy 36.431719 -191.849017)
			(xy 36.400327 -191.930049) (xy 36.361593 -192.007838) (xy 36.315846 -192.081722) (xy 36.263477 -192.151069)
			(xy 36.204933 -192.215289) (xy 36.203848 -192.216278) (xy 40.721786 -192.216278) (xy 40.725857 -192.160656)
			(xy 40.737983 -192.106219) (xy 40.757906 -192.054128) (xy 40.785202 -192.005493) (xy 40.819288 -191.96135)
			(xy 40.859437 -191.922641) (xy 40.904795 -191.89019) (xy 40.954395 -191.864689) (xy 41.007179 -191.846682)
			(xy 41.062022 -191.836552) (xy 41.117756 -191.834515) (xy 41.173193 -191.840615) (xy 41.22715 -191.854721)
			(xy 41.278479 -191.876533) (xy 41.326085 -191.905587) (xy 41.368953 -191.941262) (xy 41.40617 -191.982799)
			(xy 41.436943 -192.029312) (xy 41.460615 -192.079809) (xy 41.476683 -192.133216) (xy 41.484803 -192.188392)
			(xy 41.485312 -192.216278) (xy 41.484803 -192.244164) (xy 41.476683 -192.29934) (xy 41.460615 -192.352747)
			(xy 41.436943 -192.403244) (xy 41.40617 -192.449757) (xy 41.368953 -192.491294) (xy 41.326085 -192.526969)
			(xy 41.278479 -192.556023) (xy 41.22715 -192.577835) (xy 41.173193 -192.591941) (xy 41.117756 -192.598041)
			(xy 41.062022 -192.596004) (xy 41.007179 -192.585874) (xy 40.954395 -192.567867) (xy 40.904795 -192.542366)
			(xy 40.859437 -192.509915) (xy 40.819288 -192.471206) (xy 40.785202 -192.427063) (xy 40.757906 -192.378428)
			(xy 40.737983 -192.326337) (xy 40.725857 -192.2719) (xy 40.721786 -192.216278) (xy 36.203848 -192.216278)
			(xy 36.140713 -192.273833) (xy 36.071366 -192.326202) (xy 35.997482 -192.371949) (xy 35.919693 -192.410683)
			(xy 35.838661 -192.442075) (xy 35.755079 -192.465856) (xy 35.669659 -192.481824) (xy 35.58313 -192.489842)
			(xy 35.49623 -192.489842) (xy 35.409701 -192.481824) (xy 35.324281 -192.465856) (xy 35.240699 -192.442075)
			(xy 35.159667 -192.410683) (xy 35.081878 -192.371949) (xy 35.007994 -192.326202) (xy 34.938647 -192.273833)
			(xy 34.874427 -192.215289) (xy 34.815883 -192.151069) (xy 34.763514 -192.081722) (xy 34.717767 -192.007838)
			(xy 34.679033 -191.930049) (xy 34.647641 -191.849017) (xy 34.62386 -191.765435) (xy 34.607892 -191.680015)
			(xy 34.599874 -191.593486) (xy 31.399486 -191.593486) (xy 31.391468 -191.680015) (xy 31.3755 -191.765435)
			(xy 31.351719 -191.849017) (xy 31.320327 -191.930049) (xy 31.281593 -192.007838) (xy 31.235846 -192.081722)
			(xy 31.183477 -192.151069) (xy 31.124933 -192.215289) (xy 31.060713 -192.273833) (xy 30.991366 -192.326202)
			(xy 30.917482 -192.371949) (xy 30.839693 -192.410683) (xy 30.758661 -192.442075) (xy 30.675079 -192.465856)
			(xy 30.589659 -192.481824) (xy 30.50313 -192.489842) (xy 30.41623 -192.489842) (xy 30.329701 -192.481824)
			(xy 30.244281 -192.465856) (xy 30.160699 -192.442075) (xy 30.079667 -192.410683) (xy 30.001878 -192.371949)
			(xy 29.927994 -192.326202) (xy 29.858647 -192.273833) (xy 29.794427 -192.215289) (xy 29.735883 -192.151069)
			(xy 29.683514 -192.081722) (xy 29.637767 -192.007838) (xy 29.599033 -191.930049) (xy 29.567641 -191.849017)
			(xy 29.54386 -191.765435) (xy 29.527892 -191.680015) (xy 29.519874 -191.593486) (xy 28.461716 -191.593486)
			(xy 28.461716 -194.133486) (xy 29.519874 -194.133486) (xy 29.519874 -194.046586) (xy 29.527892 -193.960057)
			(xy 29.54386 -193.874637) (xy 29.567641 -193.791055) (xy 29.599033 -193.710023) (xy 29.637767 -193.632234)
			(xy 29.683514 -193.55835) (xy 29.735883 -193.489003) (xy 29.794427 -193.424783) (xy 29.858647 -193.366239)
			(xy 29.927994 -193.31387) (xy 30.001878 -193.268123) (xy 30.079667 -193.229389) (xy 30.160699 -193.197997)
			(xy 30.244281 -193.174216) (xy 30.329701 -193.158248) (xy 30.41623 -193.15023) (xy 30.50313 -193.15023)
			(xy 30.589659 -193.158248) (xy 30.675079 -193.174216) (xy 30.758661 -193.197997) (xy 30.839693 -193.229389)
			(xy 30.917482 -193.268123) (xy 30.991366 -193.31387) (xy 31.060713 -193.366239) (xy 31.124933 -193.424783)
			(xy 31.183477 -193.489003) (xy 31.235846 -193.55835) (xy 31.281593 -193.632234) (xy 31.320327 -193.710023)
			(xy 31.351719 -193.791055) (xy 31.3755 -193.874637) (xy 31.391468 -193.960057) (xy 31.399486 -194.046586)
			(xy 31.399988 -194.090036) (xy 31.399486 -194.133486) (xy 34.599874 -194.133486) (xy 34.599874 -194.046586)
			(xy 34.607892 -193.960057) (xy 34.62386 -193.874637) (xy 34.647641 -193.791055) (xy 34.679033 -193.710023)
			(xy 34.717767 -193.632234) (xy 34.763514 -193.55835) (xy 34.815883 -193.489003) (xy 34.874427 -193.424783)
			(xy 34.938647 -193.366239) (xy 35.007994 -193.31387) (xy 35.081878 -193.268123) (xy 35.159667 -193.229389)
			(xy 35.240699 -193.197997) (xy 35.324281 -193.174216) (xy 35.409701 -193.158248) (xy 35.49623 -193.15023)
			(xy 35.58313 -193.15023) (xy 35.669659 -193.158248) (xy 35.755079 -193.174216) (xy 35.838661 -193.197997)
			(xy 35.919693 -193.229389) (xy 35.997482 -193.268123) (xy 36.071366 -193.31387) (xy 36.140713 -193.366239)
			(xy 36.204933 -193.424783) (xy 36.263477 -193.489003) (xy 36.315846 -193.55835) (xy 36.361593 -193.632234)
			(xy 36.400327 -193.710023) (xy 36.431719 -193.791055) (xy 36.4555 -193.874637) (xy 36.471468 -193.960057)
			(xy 36.479486 -194.046586) (xy 36.479988 -194.090036) (xy 36.479703 -194.114674) (xy 40.675558 -194.114674)
			(xy 40.679629 -194.059052) (xy 40.691755 -194.004615) (xy 40.711678 -193.952524) (xy 40.738974 -193.903889)
			(xy 40.77306 -193.859746) (xy 40.813209 -193.821037) (xy 40.858567 -193.788586) (xy 40.908167 -193.763085)
			(xy 40.960951 -193.745078) (xy 41.015794 -193.734948) (xy 41.071528 -193.732911) (xy 41.126965 -193.739011)
			(xy 41.180922 -193.753117) (xy 41.232251 -193.774929) (xy 41.279857 -193.803983) (xy 41.322725 -193.839658)
			(xy 41.359942 -193.881195) (xy 41.390715 -193.927708) (xy 41.414387 -193.978205) (xy 41.430455 -194.031612)
			(xy 41.438575 -194.086788) (xy 41.439084 -194.114674) (xy 41.438575 -194.14256) (xy 41.430455 -194.197736)
			(xy 41.414387 -194.251143) (xy 41.390715 -194.30164) (xy 41.359942 -194.348153) (xy 41.322725 -194.38969)
			(xy 41.279857 -194.425365) (xy 41.232251 -194.454419) (xy 41.180922 -194.476231) (xy 41.126965 -194.490337)
			(xy 41.071528 -194.496437) (xy 41.015794 -194.4944) (xy 40.960951 -194.48427) (xy 40.908167 -194.466263)
			(xy 40.858567 -194.440762) (xy 40.813209 -194.408311) (xy 40.77306 -194.369602) (xy 40.738974 -194.325459)
			(xy 40.711678 -194.276824) (xy 40.691755 -194.224733) (xy 40.679629 -194.170296) (xy 40.675558 -194.114674)
			(xy 36.479703 -194.114674) (xy 36.479486 -194.133486) (xy 36.471468 -194.220015) (xy 36.4555 -194.305435)
			(xy 36.431719 -194.389017) (xy 36.400327 -194.470049) (xy 36.361593 -194.547838) (xy 36.315846 -194.621722)
			(xy 36.263477 -194.691069) (xy 36.204933 -194.755289) (xy 36.140713 -194.813833) (xy 36.071366 -194.866202)
			(xy 35.997482 -194.911949) (xy 35.919693 -194.950683) (xy 35.838661 -194.982075) (xy 35.755079 -195.005856)
			(xy 35.669659 -195.021824) (xy 35.58313 -195.029842) (xy 35.49623 -195.029842) (xy 35.409701 -195.021824)
			(xy 35.324281 -195.005856) (xy 35.240699 -194.982075) (xy 35.159667 -194.950683) (xy 35.081878 -194.911949)
			(xy 35.007994 -194.866202) (xy 34.938647 -194.813833) (xy 34.874427 -194.755289) (xy 34.815883 -194.691069)
			(xy 34.763514 -194.621722) (xy 34.717767 -194.547838) (xy 34.679033 -194.470049) (xy 34.647641 -194.389017)
			(xy 34.62386 -194.305435) (xy 34.607892 -194.220015) (xy 34.599874 -194.133486) (xy 31.399486 -194.133486)
			(xy 31.391468 -194.220015) (xy 31.3755 -194.305435) (xy 31.351719 -194.389017) (xy 31.320327 -194.470049)
			(xy 31.281593 -194.547838) (xy 31.235846 -194.621722) (xy 31.183477 -194.691069) (xy 31.124933 -194.755289)
			(xy 31.060713 -194.813833) (xy 30.991366 -194.866202) (xy 30.917482 -194.911949) (xy 30.839693 -194.950683)
			(xy 30.758661 -194.982075) (xy 30.675079 -195.005856) (xy 30.589659 -195.021824) (xy 30.50313 -195.029842)
			(xy 30.41623 -195.029842) (xy 30.329701 -195.021824) (xy 30.244281 -195.005856) (xy 30.160699 -194.982075)
			(xy 30.079667 -194.950683) (xy 30.001878 -194.911949) (xy 29.927994 -194.866202) (xy 29.858647 -194.813833)
			(xy 29.794427 -194.755289) (xy 29.735883 -194.691069) (xy 29.683514 -194.621722) (xy 29.637767 -194.547838)
			(xy 29.599033 -194.470049) (xy 29.567641 -194.389017) (xy 29.54386 -194.305435) (xy 29.527892 -194.220015)
			(xy 29.519874 -194.133486) (xy 28.461716 -194.133486) (xy 28.461716 -194.723766) (xy 28.462211 -194.747063)
			(xy 28.470651 -194.792886) (xy 28.487309 -194.8364) (xy 28.511626 -194.876145) (xy 28.542785 -194.910787)
			(xy 28.579741 -194.939163) (xy 28.621254 -194.960321) (xy 28.66593 -194.97355) (xy 28.689046 -194.976496)
			(xy 28.716117 -194.979023) (xy 28.769201 -194.990773) (xy 28.820079 -195.009937) (xy 28.867723 -195.03613)
			(xy 28.911166 -195.068819) (xy 28.94953 -195.107344) (xy 28.982037 -195.150924) (xy 29.008029 -195.198677)
			(xy 29.026981 -195.249636) (xy 29.038507 -195.302768) (xy 29.042376 -195.356999) (xy 29.038508 -195.41123)
			(xy 29.026981 -195.464363) (xy 29.00803 -195.515321) (xy 28.982038 -195.563074) (xy 28.949531 -195.606654)
			(xy 28.911168 -195.645179) (xy 28.867724 -195.677869) (xy 28.820081 -195.704062) (xy 28.769202 -195.723227)
			(xy 28.716119 -195.734976) (xy 28.689046 -195.73748) (xy 28.665938 -195.740452) (xy 28.621281 -195.753712)
			(xy 28.579787 -195.774885) (xy 28.542843 -195.803261) (xy 28.511686 -195.837892) (xy 28.487358 -195.877619)
			(xy 28.470673 -195.921113) (xy 28.46219 -195.966918) (xy 28.461716 -195.99021) (xy 28.461716 -196.673486)
			(xy 29.519874 -196.673486) (xy 29.519874 -196.586586) (xy 29.527892 -196.500057) (xy 29.54386 -196.414637)
			(xy 29.567641 -196.331055) (xy 29.599033 -196.250023) (xy 29.637767 -196.172234) (xy 29.683514 -196.09835)
			(xy 29.735883 -196.029003) (xy 29.794427 -195.964783) (xy 29.858647 -195.906239) (xy 29.927994 -195.85387)
			(xy 30.001878 -195.808123) (xy 30.079667 -195.769389) (xy 30.160699 -195.737997) (xy 30.244281 -195.714216)
			(xy 30.329701 -195.698248) (xy 30.41623 -195.69023) (xy 30.50313 -195.69023) (xy 30.589659 -195.698248)
			(xy 30.675079 -195.714216) (xy 30.758661 -195.737997) (xy 30.839693 -195.769389) (xy 30.917482 -195.808123)
			(xy 30.991366 -195.85387) (xy 31.060713 -195.906239) (xy 31.124933 -195.964783) (xy 31.183477 -196.029003)
			(xy 31.235846 -196.09835) (xy 31.281593 -196.172234) (xy 31.320327 -196.250023) (xy 31.351719 -196.331055)
			(xy 31.3755 -196.414637) (xy 31.391468 -196.500057) (xy 31.399486 -196.586586) (xy 31.399988 -196.630036)
			(xy 31.399486 -196.673486) (xy 34.599874 -196.673486) (xy 34.599874 -196.586586) (xy 34.607892 -196.500057)
			(xy 34.62386 -196.414637) (xy 34.647641 -196.331055) (xy 34.679033 -196.250023) (xy 34.717767 -196.172234)
			(xy 34.763514 -196.09835) (xy 34.815883 -196.029003) (xy 34.874427 -195.964783) (xy 34.938647 -195.906239)
			(xy 35.007994 -195.85387) (xy 35.081878 -195.808123) (xy 35.159667 -195.769389) (xy 35.240699 -195.737997)
			(xy 35.324281 -195.714216) (xy 35.409701 -195.698248) (xy 35.49623 -195.69023) (xy 35.58313 -195.69023)
			(xy 35.669659 -195.698248) (xy 35.755079 -195.714216) (xy 35.838661 -195.737997) (xy 35.919693 -195.769389)
			(xy 35.997482 -195.808123) (xy 36.071366 -195.85387) (xy 36.140713 -195.906239) (xy 36.204933 -195.964783)
			(xy 36.263477 -196.029003) (xy 36.315846 -196.09835) (xy 36.361593 -196.172234) (xy 36.400327 -196.250023)
			(xy 36.431719 -196.331055) (xy 36.4555 -196.414637) (xy 36.471468 -196.500057) (xy 36.479486 -196.586586)
			(xy 36.479988 -196.630036) (xy 36.479486 -196.673486) (xy 36.471468 -196.760015) (xy 36.460439 -196.819012)
			(xy 40.545256 -196.819012) (xy 40.549327 -196.76339) (xy 40.561453 -196.708953) (xy 40.581376 -196.656862)
			(xy 40.608672 -196.608227) (xy 40.642758 -196.564084) (xy 40.682907 -196.525375) (xy 40.728265 -196.492924)
			(xy 40.777865 -196.467423) (xy 40.830649 -196.449416) (xy 40.885492 -196.439286) (xy 40.941226 -196.437249)
			(xy 40.996663 -196.443349) (xy 41.05062 -196.457455) (xy 41.101949 -196.479267) (xy 41.149555 -196.508321)
			(xy 41.192423 -196.543996) (xy 41.22964 -196.585533) (xy 41.260413 -196.632046) (xy 41.284085 -196.682543)
			(xy 41.300153 -196.73595) (xy 41.305187 -196.770159) (xy 47.903374 -196.770159) (xy 47.903374 -196.689049)
			(xy 47.911324 -196.60833) (xy 47.927147 -196.528779) (xy 47.950692 -196.451163) (xy 47.981731 -196.376227)
			(xy 48.019966 -196.304695) (xy 48.065028 -196.237255) (xy 48.116483 -196.174556) (xy 48.173836 -196.117203)
			(xy 48.236535 -196.065748) (xy 48.303975 -196.020686) (xy 48.375507 -195.982451) (xy 48.450443 -195.951412)
			(xy 48.528059 -195.927867) (xy 48.60761 -195.912044) (xy 48.688329 -195.904094) (xy 48.769439 -195.904094)
			(xy 48.850158 -195.912044) (xy 48.929709 -195.927867) (xy 49.007325 -195.951412) (xy 49.082261 -195.982451)
			(xy 49.153793 -196.020686) (xy 49.221233 -196.065748) (xy 49.283932 -196.117203) (xy 49.341285 -196.174556)
			(xy 49.39274 -196.237255) (xy 49.437802 -196.304695) (xy 49.476037 -196.376227) (xy 49.507076 -196.451163)
			(xy 49.530621 -196.528779) (xy 49.546444 -196.60833) (xy 49.554394 -196.689049) (xy 49.554892 -196.729604)
			(xy 49.554394 -196.770159) (xy 51.403494 -196.770159) (xy 51.403494 -196.689049) (xy 51.411444 -196.60833)
			(xy 51.427267 -196.528779) (xy 51.450812 -196.451163) (xy 51.481851 -196.376227) (xy 51.520086 -196.304695)
			(xy 51.565148 -196.237255) (xy 51.616603 -196.174556) (xy 51.673956 -196.117203) (xy 51.736655 -196.065748)
			(xy 51.804095 -196.020686) (xy 51.875627 -195.982451) (xy 51.950563 -195.951412) (xy 52.028179 -195.927867)
			(xy 52.10773 -195.912044) (xy 52.188449 -195.904094) (xy 52.269559 -195.904094) (xy 52.350278 -195.912044)
			(xy 52.429829 -195.927867) (xy 52.507445 -195.951412) (xy 52.582381 -195.982451) (xy 52.653913 -196.020686)
			(xy 52.721353 -196.065748) (xy 52.784052 -196.117203) (xy 52.841405 -196.174556) (xy 52.89286 -196.237255)
			(xy 52.937922 -196.304695) (xy 52.976157 -196.376227) (xy 53.007196 -196.451163) (xy 53.030741 -196.528779)
			(xy 53.046564 -196.60833) (xy 53.054514 -196.689049) (xy 53.055012 -196.729604) (xy 53.054514 -196.770159)
			(xy 53.046564 -196.850878) (xy 53.030741 -196.930429) (xy 53.007196 -197.008045) (xy 52.976157 -197.082981)
			(xy 52.937922 -197.154513) (xy 52.89286 -197.221953) (xy 52.841405 -197.284652) (xy 52.784052 -197.342005)
			(xy 52.721353 -197.39346) (xy 52.653913 -197.438522) (xy 52.582381 -197.476757) (xy 52.507445 -197.507796)
			(xy 52.429829 -197.531341) (xy 52.350278 -197.547164) (xy 52.269559 -197.555114) (xy 52.188449 -197.555114)
			(xy 52.10773 -197.547164) (xy 52.028179 -197.531341) (xy 51.950563 -197.507796) (xy 51.875627 -197.476757)
			(xy 51.804095 -197.438522) (xy 51.736655 -197.39346) (xy 51.673956 -197.342005) (xy 51.616603 -197.284652)
			(xy 51.565148 -197.221953) (xy 51.520086 -197.154513) (xy 51.481851 -197.082981) (xy 51.450812 -197.008045)
			(xy 51.427267 -196.930429) (xy 51.411444 -196.850878) (xy 51.403494 -196.770159) (xy 49.554394 -196.770159)
			(xy 49.546444 -196.850878) (xy 49.530621 -196.930429) (xy 49.507076 -197.008045) (xy 49.476037 -197.082981)
			(xy 49.437802 -197.154513) (xy 49.39274 -197.221953) (xy 49.341285 -197.284652) (xy 49.283932 -197.342005)
			(xy 49.221233 -197.39346) (xy 49.153793 -197.438522) (xy 49.082261 -197.476757) (xy 49.007325 -197.507796)
			(xy 48.929709 -197.531341) (xy 48.850158 -197.547164) (xy 48.769439 -197.555114) (xy 48.688329 -197.555114)
			(xy 48.60761 -197.547164) (xy 48.528059 -197.531341) (xy 48.450443 -197.507796) (xy 48.375507 -197.476757)
			(xy 48.303975 -197.438522) (xy 48.236535 -197.39346) (xy 48.173836 -197.342005) (xy 48.116483 -197.284652)
			(xy 48.065028 -197.221953) (xy 48.019966 -197.154513) (xy 47.981731 -197.082981) (xy 47.950692 -197.008045)
			(xy 47.927147 -196.930429) (xy 47.911324 -196.850878) (xy 47.903374 -196.770159) (xy 41.305187 -196.770159)
			(xy 41.308273 -196.791126) (xy 41.308782 -196.819012) (xy 41.308273 -196.846898) (xy 41.300153 -196.902074)
			(xy 41.284085 -196.955481) (xy 41.260413 -197.005978) (xy 41.22964 -197.052491) (xy 41.192423 -197.094028)
			(xy 41.149555 -197.129703) (xy 41.101949 -197.158757) (xy 41.05062 -197.180569) (xy 40.996663 -197.194675)
			(xy 40.941226 -197.200775) (xy 40.885492 -197.198738) (xy 40.830649 -197.188608) (xy 40.777865 -197.170601)
			(xy 40.728265 -197.1451) (xy 40.682907 -197.112649) (xy 40.642758 -197.07394) (xy 40.608672 -197.029797)
			(xy 40.581376 -196.981162) (xy 40.561453 -196.929071) (xy 40.549327 -196.874634) (xy 40.545256 -196.819012)
			(xy 36.460439 -196.819012) (xy 36.4555 -196.845435) (xy 36.431719 -196.929017) (xy 36.400327 -197.010049)
			(xy 36.361593 -197.087838) (xy 36.315846 -197.161722) (xy 36.263477 -197.231069) (xy 36.204933 -197.295289)
			(xy 36.140713 -197.353833) (xy 36.071366 -197.406202) (xy 35.997482 -197.451949) (xy 35.919693 -197.490683)
			(xy 35.838661 -197.522075) (xy 35.755079 -197.545856) (xy 35.669659 -197.561824) (xy 35.58313 -197.569842)
			(xy 35.49623 -197.569842) (xy 35.409701 -197.561824) (xy 35.324281 -197.545856) (xy 35.240699 -197.522075)
			(xy 35.159667 -197.490683) (xy 35.081878 -197.451949) (xy 35.007994 -197.406202) (xy 34.938647 -197.353833)
			(xy 34.874427 -197.295289) (xy 34.815883 -197.231069) (xy 34.763514 -197.161722) (xy 34.717767 -197.087838)
			(xy 34.679033 -197.010049) (xy 34.647641 -196.929017) (xy 34.62386 -196.845435) (xy 34.607892 -196.760015)
			(xy 34.599874 -196.673486) (xy 31.399486 -196.673486) (xy 31.391468 -196.760015) (xy 31.3755 -196.845435)
			(xy 31.351719 -196.929017) (xy 31.320327 -197.010049) (xy 31.281593 -197.087838) (xy 31.235846 -197.161722)
			(xy 31.183477 -197.231069) (xy 31.124933 -197.295289) (xy 31.060713 -197.353833) (xy 30.991366 -197.406202)
			(xy 30.917482 -197.451949) (xy 30.839693 -197.490683) (xy 30.758661 -197.522075) (xy 30.675079 -197.545856)
			(xy 30.589659 -197.561824) (xy 30.50313 -197.569842) (xy 30.41623 -197.569842) (xy 30.329701 -197.561824)
			(xy 30.244281 -197.545856) (xy 30.160699 -197.522075) (xy 30.079667 -197.490683) (xy 30.001878 -197.451949)
			(xy 29.927994 -197.406202) (xy 29.858647 -197.353833) (xy 29.794427 -197.295289) (xy 29.735883 -197.231069)
			(xy 29.683514 -197.161722) (xy 29.637767 -197.087838) (xy 29.599033 -197.010049) (xy 29.567641 -196.929017)
			(xy 29.54386 -196.845435) (xy 29.527892 -196.760015) (xy 29.519874 -196.673486) (xy 28.461716 -196.673486)
			(xy 28.461716 -199.213486) (xy 29.519874 -199.213486) (xy 29.519874 -199.126586) (xy 29.527892 -199.040057)
			(xy 29.54386 -198.954637) (xy 29.567641 -198.871055) (xy 29.599033 -198.790023) (xy 29.637767 -198.712234)
			(xy 29.683514 -198.63835) (xy 29.735883 -198.569003) (xy 29.794427 -198.504783) (xy 29.858647 -198.446239)
			(xy 29.927994 -198.39387) (xy 30.001878 -198.348123) (xy 30.079667 -198.309389) (xy 30.160699 -198.277997)
			(xy 30.244281 -198.254216) (xy 30.329701 -198.238248) (xy 30.41623 -198.23023) (xy 30.50313 -198.23023)
			(xy 30.589659 -198.238248) (xy 30.675079 -198.254216) (xy 30.758661 -198.277997) (xy 30.839693 -198.309389)
			(xy 30.917482 -198.348123) (xy 30.991366 -198.39387) (xy 31.060713 -198.446239) (xy 31.124933 -198.504783)
			(xy 31.183477 -198.569003) (xy 31.235846 -198.63835) (xy 31.281593 -198.712234) (xy 31.320327 -198.790023)
			(xy 31.351719 -198.871055) (xy 31.3755 -198.954637) (xy 31.391468 -199.040057) (xy 31.399486 -199.126586)
			(xy 31.399988 -199.170036) (xy 31.399486 -199.213486) (xy 34.599874 -199.213486) (xy 34.599874 -199.126586)
			(xy 34.607892 -199.040057) (xy 34.62386 -198.954637) (xy 34.647641 -198.871055) (xy 34.679033 -198.790023)
			(xy 34.717767 -198.712234) (xy 34.763514 -198.63835) (xy 34.815883 -198.569003) (xy 34.874427 -198.504783)
			(xy 34.938647 -198.446239) (xy 35.007994 -198.39387) (xy 35.081878 -198.348123) (xy 35.159667 -198.309389)
			(xy 35.240699 -198.277997) (xy 35.324281 -198.254216) (xy 35.409701 -198.238248) (xy 35.49623 -198.23023)
			(xy 35.58313 -198.23023) (xy 35.669659 -198.238248) (xy 35.755079 -198.254216) (xy 35.838661 -198.277997)
			(xy 35.919693 -198.309389) (xy 35.997482 -198.348123) (xy 36.031891 -198.369428) (xy 39.992806 -198.369428)
			(xy 39.996877 -198.313806) (xy 40.009003 -198.259369) (xy 40.028926 -198.207278) (xy 40.056222 -198.158643)
			(xy 40.090308 -198.1145) (xy 40.130457 -198.075791) (xy 40.175815 -198.04334) (xy 40.225415 -198.017839)
			(xy 40.278199 -197.999832) (xy 40.333042 -197.989702) (xy 40.388776 -197.987665) (xy 40.444213 -197.993765)
			(xy 40.49817 -198.007871) (xy 40.549499 -198.029683) (xy 40.597105 -198.058737) (xy 40.639973 -198.094412)
			(xy 40.67719 -198.135949) (xy 40.707963 -198.182462) (xy 40.731635 -198.232959) (xy 40.747703 -198.286366)
			(xy 40.755823 -198.341542) (xy 40.756332 -198.369428) (xy 40.755823 -198.397314) (xy 40.747703 -198.45249)
			(xy 40.731635 -198.505897) (xy 40.707963 -198.556394) (xy 40.67719 -198.602907) (xy 40.639973 -198.644444)
			(xy 40.597105 -198.680119) (xy 40.549499 -198.709173) (xy 40.49817 -198.730985) (xy 40.444213 -198.745091)
			(xy 40.388776 -198.751191) (xy 40.333042 -198.749154) (xy 40.278199 -198.739024) (xy 40.225415 -198.721017)
			(xy 40.175815 -198.695516) (xy 40.130457 -198.663065) (xy 40.090308 -198.624356) (xy 40.056222 -198.580213)
			(xy 40.028926 -198.531578) (xy 40.009003 -198.479487) (xy 39.996877 -198.42505) (xy 39.992806 -198.369428)
			(xy 36.031891 -198.369428) (xy 36.071366 -198.39387) (xy 36.140713 -198.446239) (xy 36.204933 -198.504783)
			(xy 36.263477 -198.569003) (xy 36.315846 -198.63835) (xy 36.361593 -198.712234) (xy 36.400327 -198.790023)
			(xy 36.40083 -198.791322) (xy 70.276718 -198.791322) (xy 70.280789 -198.7357) (xy 70.292915 -198.681263)
			(xy 70.312838 -198.629172) (xy 70.340134 -198.580537) (xy 70.37422 -198.536394) (xy 70.414369 -198.497685)
			(xy 70.459727 -198.465234) (xy 70.509327 -198.439733) (xy 70.562111 -198.421726) (xy 70.616954 -198.411596)
			(xy 70.672688 -198.409559) (xy 70.728125 -198.415659) (xy 70.782082 -198.429765) (xy 70.833411 -198.451577)
			(xy 70.881017 -198.480631) (xy 70.923885 -198.516306) (xy 70.961102 -198.557843) (xy 70.991875 -198.604356)
			(xy 71.015547 -198.654853) (xy 71.031615 -198.70826) (xy 71.039735 -198.763436) (xy 71.040244 -198.791322)
			(xy 71.43318 -198.791322) (xy 71.437251 -198.7357) (xy 71.449377 -198.681263) (xy 71.4693 -198.629172)
			(xy 71.496596 -198.580537) (xy 71.530682 -198.536394) (xy 71.570831 -198.497685) (xy 71.616189 -198.465234)
			(xy 71.665789 -198.439733) (xy 71.718573 -198.421726) (xy 71.773416 -198.411596) (xy 71.82915 -198.409559)
			(xy 71.884587 -198.415659) (xy 71.938544 -198.429765) (xy 71.989873 -198.451577) (xy 72.037479 -198.480631)
			(xy 72.080347 -198.516306) (xy 72.117564 -198.557843) (xy 72.148337 -198.604356) (xy 72.172009 -198.654853)
			(xy 72.188077 -198.70826) (xy 72.196197 -198.763436) (xy 72.196706 -198.791322) (xy 72.196197 -198.819208)
			(xy 72.188077 -198.874384) (xy 72.172009 -198.927791) (xy 72.148337 -198.978288) (xy 72.117564 -199.024801)
			(xy 72.080347 -199.066338) (xy 72.037479 -199.102013) (xy 71.989873 -199.131067) (xy 71.938544 -199.152879)
			(xy 71.884587 -199.166985) (xy 71.82915 -199.173085) (xy 71.773416 -199.171048) (xy 71.718573 -199.160918)
			(xy 71.665789 -199.142911) (xy 71.616189 -199.11741) (xy 71.570831 -199.084959) (xy 71.530682 -199.04625)
			(xy 71.496596 -199.002107) (xy 71.4693 -198.953472) (xy 71.449377 -198.901381) (xy 71.437251 -198.846944)
			(xy 71.43318 -198.791322) (xy 71.040244 -198.791322) (xy 71.039735 -198.819208) (xy 71.031615 -198.874384)
			(xy 71.015547 -198.927791) (xy 70.991875 -198.978288) (xy 70.961102 -199.024801) (xy 70.923885 -199.066338)
			(xy 70.881017 -199.102013) (xy 70.833411 -199.131067) (xy 70.782082 -199.152879) (xy 70.728125 -199.166985)
			(xy 70.672688 -199.173085) (xy 70.616954 -199.171048) (xy 70.562111 -199.160918) (xy 70.509327 -199.142911)
			(xy 70.459727 -199.11741) (xy 70.414369 -199.084959) (xy 70.37422 -199.04625) (xy 70.340134 -199.002107)
			(xy 70.312838 -198.953472) (xy 70.292915 -198.901381) (xy 70.280789 -198.846944) (xy 70.276718 -198.791322)
			(xy 36.40083 -198.791322) (xy 36.431719 -198.871055) (xy 36.4555 -198.954637) (xy 36.471468 -199.040057)
			(xy 36.479486 -199.126586) (xy 36.479988 -199.170036) (xy 36.479486 -199.213486) (xy 36.471468 -199.300015)
			(xy 36.4555 -199.385435) (xy 36.431719 -199.469017) (xy 36.400327 -199.550049) (xy 36.361593 -199.627838)
			(xy 36.315846 -199.701722) (xy 36.263477 -199.771069) (xy 36.204933 -199.835289) (xy 36.140713 -199.893833)
			(xy 36.071366 -199.946202) (xy 36.034352 -199.96912) (xy 40.017444 -199.96912) (xy 40.021515 -199.913498)
			(xy 40.033641 -199.859061) (xy 40.053564 -199.80697) (xy 40.08086 -199.758335) (xy 40.114946 -199.714192)
			(xy 40.155095 -199.675483) (xy 40.200453 -199.643032) (xy 40.250053 -199.617531) (xy 40.302837 -199.599524)
			(xy 40.35768 -199.589394) (xy 40.413414 -199.587357) (xy 40.468851 -199.593457) (xy 40.522808 -199.607563)
			(xy 40.574137 -199.629375) (xy 40.584783 -199.635872) (xy 68.988938 -199.635872) (xy 68.993009 -199.58025)
			(xy 69.005135 -199.525813) (xy 69.025058 -199.473722) (xy 69.052354 -199.425087) (xy 69.08644 -199.380944)
			(xy 69.126589 -199.342235) (xy 69.171947 -199.309784) (xy 69.221547 -199.284283) (xy 69.274331 -199.266276)
			(xy 69.329174 -199.256146) (xy 69.384908 -199.254109) (xy 69.440345 -199.260209) (xy 69.494302 -199.274315)
			(xy 69.545631 -199.296127) (xy 69.593237 -199.325181) (xy 69.636105 -199.360856) (xy 69.673322 -199.402393)
			(xy 69.704095 -199.448906) (xy 69.727767 -199.499403) (xy 69.743835 -199.55281) (xy 69.751955 -199.607986)
			(xy 69.752464 -199.635872) (xy 69.751955 -199.663758) (xy 69.743835 -199.718934) (xy 69.727767 -199.772341)
			(xy 69.704095 -199.822838) (xy 69.673322 -199.869351) (xy 69.636105 -199.910888) (xy 69.593237 -199.946563)
			(xy 69.545631 -199.975617) (xy 69.494302 -199.997429) (xy 69.440345 -200.011535) (xy 69.384908 -200.017635)
			(xy 69.329174 -200.015598) (xy 69.274331 -200.005468) (xy 69.221547 -199.987461) (xy 69.171947 -199.96196)
			(xy 69.126589 -199.929509) (xy 69.08644 -199.8908) (xy 69.052354 -199.846657) (xy 69.025058 -199.798022)
			(xy 69.005135 -199.745931) (xy 68.993009 -199.691494) (xy 68.988938 -199.635872) (xy 40.584783 -199.635872)
			(xy 40.621743 -199.658429) (xy 40.664611 -199.694104) (xy 40.701828 -199.735641) (xy 40.732601 -199.782154)
			(xy 40.756273 -199.832651) (xy 40.772341 -199.886058) (xy 40.780461 -199.941234) (xy 40.78097 -199.96912)
			(xy 40.780461 -199.997006) (xy 40.772341 -200.052182) (xy 40.756273 -200.105589) (xy 40.732601 -200.156086)
			(xy 40.701828 -200.202599) (xy 40.664611 -200.244136) (xy 40.621743 -200.279811) (xy 40.574137 -200.308865)
			(xy 40.522808 -200.330677) (xy 40.468851 -200.344783) (xy 40.413414 -200.350883) (xy 40.35768 -200.348846)
			(xy 40.302837 -200.338716) (xy 40.250053 -200.320709) (xy 40.200453 -200.295208) (xy 40.155095 -200.262757)
			(xy 40.114946 -200.224048) (xy 40.08086 -200.179905) (xy 40.053564 -200.13127) (xy 40.033641 -200.079179)
			(xy 40.021515 -200.024742) (xy 40.017444 -199.96912) (xy 36.034352 -199.96912) (xy 35.997482 -199.991949)
			(xy 35.919693 -200.030683) (xy 35.838661 -200.062075) (xy 35.755079 -200.085856) (xy 35.669659 -200.101824)
			(xy 35.58313 -200.109842) (xy 35.49623 -200.109842) (xy 35.409701 -200.101824) (xy 35.324281 -200.085856)
			(xy 35.240699 -200.062075) (xy 35.159667 -200.030683) (xy 35.081878 -199.991949) (xy 35.007994 -199.946202)
			(xy 34.938647 -199.893833) (xy 34.874427 -199.835289) (xy 34.815883 -199.771069) (xy 34.763514 -199.701722)
			(xy 34.717767 -199.627838) (xy 34.679033 -199.550049) (xy 34.647641 -199.469017) (xy 34.62386 -199.385435)
			(xy 34.607892 -199.300015) (xy 34.599874 -199.213486) (xy 31.399486 -199.213486) (xy 31.391468 -199.300015)
			(xy 31.3755 -199.385435) (xy 31.351719 -199.469017) (xy 31.320327 -199.550049) (xy 31.281593 -199.627838)
			(xy 31.235846 -199.701722) (xy 31.183477 -199.771069) (xy 31.124933 -199.835289) (xy 31.060713 -199.893833)
			(xy 30.991366 -199.946202) (xy 30.917482 -199.991949) (xy 30.839693 -200.030683) (xy 30.758661 -200.062075)
			(xy 30.675079 -200.085856) (xy 30.589659 -200.101824) (xy 30.50313 -200.109842) (xy 30.41623 -200.109842)
			(xy 30.329701 -200.101824) (xy 30.244281 -200.085856) (xy 30.160699 -200.062075) (xy 30.079667 -200.030683)
			(xy 30.001878 -199.991949) (xy 29.927994 -199.946202) (xy 29.858647 -199.893833) (xy 29.794427 -199.835289)
			(xy 29.735883 -199.771069) (xy 29.683514 -199.701722) (xy 29.637767 -199.627838) (xy 29.599033 -199.550049)
			(xy 29.567641 -199.469017) (xy 29.54386 -199.385435) (xy 29.527892 -199.300015) (xy 29.519874 -199.213486)
			(xy 28.461716 -199.213486) (xy 28.461716 -201.13625) (xy 28.462211 -201.15919) (xy 28.470454 -201.204324)
			(xy 28.486662 -201.247246) (xy 28.510309 -201.286563) (xy 28.540628 -201.320998) (xy 28.576634 -201.349433)
			(xy 28.617158 -201.370945) (xy 28.660885 -201.384836) (xy 28.706395 -201.390655) (xy 28.75221 -201.388212)
			(xy 28.774644 -201.383392) (xy 28.800988 -201.37636) (xy 28.855017 -201.36902) (xy 28.909541 -201.369446)
			(xy 28.963449 -201.37763) (xy 29.015643 -201.393404) (xy 29.06506 -201.416447) (xy 29.110693 -201.446291)
			(xy 29.151613 -201.482327) (xy 29.186987 -201.52382) (xy 29.216093 -201.569927) (xy 29.23834 -201.619708)
			(xy 29.253274 -201.672148) (xy 29.26059 -201.72618) (xy 29.260365 -201.753486) (xy 29.519874 -201.753486)
			(xy 29.519874 -201.666586) (xy 29.527892 -201.580057) (xy 29.54386 -201.494637) (xy 29.567641 -201.411055)
			(xy 29.599033 -201.330023) (xy 29.637767 -201.252234) (xy 29.683514 -201.17835) (xy 29.735883 -201.109003)
			(xy 29.794427 -201.044783) (xy 29.858647 -200.986239) (xy 29.927994 -200.93387) (xy 30.001878 -200.888123)
			(xy 30.079667 -200.849389) (xy 30.160699 -200.817997) (xy 30.244281 -200.794216) (xy 30.329701 -200.778248)
			(xy 30.41623 -200.77023) (xy 30.50313 -200.77023) (xy 30.589659 -200.778248) (xy 30.675079 -200.794216)
			(xy 30.758661 -200.817997) (xy 30.839693 -200.849389) (xy 30.917482 -200.888123) (xy 30.991366 -200.93387)
			(xy 31.060713 -200.986239) (xy 31.124933 -201.044783) (xy 31.183477 -201.109003) (xy 31.235846 -201.17835)
			(xy 31.281593 -201.252234) (xy 31.320327 -201.330023) (xy 31.351719 -201.411055) (xy 31.3755 -201.494637)
			(xy 31.391468 -201.580057) (xy 31.399486 -201.666586) (xy 31.399988 -201.710036) (xy 31.399486 -201.753486)
			(xy 34.599874 -201.753486) (xy 34.599874 -201.666586) (xy 34.607892 -201.580057) (xy 34.62386 -201.494637)
			(xy 34.647641 -201.411055) (xy 34.679033 -201.330023) (xy 34.717767 -201.252234) (xy 34.763514 -201.17835)
			(xy 34.815883 -201.109003) (xy 34.874427 -201.044783) (xy 34.938647 -200.986239) (xy 35.007994 -200.93387)
			(xy 35.081878 -200.888123) (xy 35.159667 -200.849389) (xy 35.240699 -200.817997) (xy 35.324281 -200.794216)
			(xy 35.409701 -200.778248) (xy 35.49623 -200.77023) (xy 35.58313 -200.77023) (xy 35.669659 -200.778248)
			(xy 35.755079 -200.794216) (xy 35.838661 -200.817997) (xy 35.919693 -200.849389) (xy 35.997482 -200.888123)
			(xy 36.071366 -200.93387) (xy 36.140713 -200.986239) (xy 36.204933 -201.044783) (xy 36.263477 -201.109003)
			(xy 36.315846 -201.17835) (xy 36.361593 -201.252234) (xy 36.400327 -201.330023) (xy 36.431719 -201.411055)
			(xy 36.4555 -201.494637) (xy 36.471468 -201.580057) (xy 36.479486 -201.666586) (xy 36.479988 -201.710036)
			(xy 36.479486 -201.753486) (xy 36.471468 -201.840015) (xy 36.4555 -201.925435) (xy 36.431719 -202.009017)
			(xy 36.400327 -202.090049) (xy 36.361593 -202.167838) (xy 36.315846 -202.241722) (xy 36.263477 -202.311069)
			(xy 36.204933 -202.375289) (xy 36.140713 -202.433833) (xy 36.071366 -202.486202) (xy 35.997482 -202.531949)
			(xy 35.919693 -202.570683) (xy 35.838661 -202.602075) (xy 35.755079 -202.625856) (xy 35.669659 -202.641824)
			(xy 35.58313 -202.649842) (xy 35.49623 -202.649842) (xy 35.409701 -202.641824) (xy 35.324281 -202.625856)
			(xy 35.240699 -202.602075) (xy 35.159667 -202.570683) (xy 35.081878 -202.531949) (xy 35.007994 -202.486202)
			(xy 34.938647 -202.433833) (xy 34.874427 -202.375289) (xy 34.815883 -202.311069) (xy 34.763514 -202.241722)
			(xy 34.717767 -202.167838) (xy 34.679033 -202.090049) (xy 34.647641 -202.009017) (xy 34.62386 -201.925435)
			(xy 34.607892 -201.840015) (xy 34.599874 -201.753486) (xy 31.399486 -201.753486) (xy 31.391468 -201.840015)
			(xy 31.3755 -201.925435) (xy 31.351719 -202.009017) (xy 31.320327 -202.090049) (xy 31.281593 -202.167838)
			(xy 31.235846 -202.241722) (xy 31.183477 -202.311069) (xy 31.124933 -202.375289) (xy 31.060713 -202.433833)
			(xy 30.991366 -202.486202) (xy 30.917482 -202.531949) (xy 30.839693 -202.570683) (xy 30.758661 -202.602075)
			(xy 30.675079 -202.625856) (xy 30.589659 -202.641824) (xy 30.50313 -202.649842) (xy 30.41623 -202.649842)
			(xy 30.329701 -202.641824) (xy 30.244281 -202.625856) (xy 30.160699 -202.602075) (xy 30.079667 -202.570683)
			(xy 30.001878 -202.531949) (xy 29.927994 -202.486202) (xy 29.858647 -202.433833) (xy 29.794427 -202.375289)
			(xy 29.735883 -202.311069) (xy 29.683514 -202.241722) (xy 29.637767 -202.167838) (xy 29.599033 -202.090049)
			(xy 29.567641 -202.009017) (xy 29.54386 -201.925435) (xy 29.527892 -201.840015) (xy 29.519874 -201.753486)
			(xy 29.260365 -201.753486) (xy 29.260141 -201.780704) (xy 29.251934 -201.834608) (xy 29.236138 -201.886795)
			(xy 29.213073 -201.936202) (xy 29.18321 -201.981823) (xy 29.147157 -202.022728) (xy 29.105648 -202.058083)
			(xy 29.059529 -202.08717) (xy 29.009739 -202.109396) (xy 28.957292 -202.124307) (xy 28.903257 -202.131601)
			(xy 28.87599 -202.13193) (xy 28.85951 -202.132312) (xy 28.827589 -202.140495) (xy 28.798838 -202.156595)
			(xy 28.775181 -202.179536) (xy 28.766262 -202.193398) (xy 28.751443 -202.217025) (xy 28.715988 -202.260074)
			(xy 28.674641 -202.297501) (xy 28.628284 -202.328507) (xy 28.577906 -202.352431) (xy 28.551378 -202.361038)
			(xy 28.5115 -202.37323) (xy 28.461716 -202.44054) (xy 28.461716 -204.293486) (xy 29.519874 -204.293486)
			(xy 29.519874 -204.206586) (xy 29.527892 -204.120057) (xy 29.54386 -204.034637) (xy 29.567641 -203.951055)
			(xy 29.599033 -203.870023) (xy 29.637767 -203.792234) (xy 29.683514 -203.71835) (xy 29.735883 -203.649003)
			(xy 29.794427 -203.584783) (xy 29.858647 -203.526239) (xy 29.927994 -203.47387) (xy 30.001878 -203.428123)
			(xy 30.079667 -203.389389) (xy 30.160699 -203.357997) (xy 30.244281 -203.334216) (xy 30.329701 -203.318248)
			(xy 30.41623 -203.31023) (xy 30.50313 -203.31023) (xy 30.589659 -203.318248) (xy 30.675079 -203.334216)
			(xy 30.758661 -203.357997) (xy 30.839693 -203.389389) (xy 30.917482 -203.428123) (xy 30.991366 -203.47387)
			(xy 31.060713 -203.526239) (xy 31.124933 -203.584783) (xy 31.183477 -203.649003) (xy 31.235846 -203.71835)
			(xy 31.281593 -203.792234) (xy 31.320327 -203.870023) (xy 31.351719 -203.951055) (xy 31.3755 -204.034637)
			(xy 31.391468 -204.120057) (xy 31.399486 -204.206586) (xy 31.399988 -204.250036) (xy 31.399486 -204.293486)
			(xy 34.599874 -204.293486) (xy 34.599874 -204.206586) (xy 34.607892 -204.120057) (xy 34.62386 -204.034637)
			(xy 34.647641 -203.951055) (xy 34.679033 -203.870023) (xy 34.717767 -203.792234) (xy 34.763514 -203.71835)
			(xy 34.815883 -203.649003) (xy 34.874427 -203.584783) (xy 34.938647 -203.526239) (xy 35.007994 -203.47387)
			(xy 35.081878 -203.428123) (xy 35.159667 -203.389389) (xy 35.240699 -203.357997) (xy 35.324281 -203.334216)
			(xy 35.409701 -203.318248) (xy 35.49623 -203.31023) (xy 35.58313 -203.31023) (xy 35.669659 -203.318248)
			(xy 35.755079 -203.334216) (xy 35.838661 -203.357997) (xy 35.919693 -203.389389) (xy 35.997482 -203.428123)
			(xy 36.071366 -203.47387) (xy 36.140713 -203.526239) (xy 36.204933 -203.584783) (xy 36.263477 -203.649003)
			(xy 36.315846 -203.71835) (xy 36.361593 -203.792234) (xy 36.400327 -203.870023) (xy 36.431719 -203.951055)
			(xy 36.4555 -204.034637) (xy 36.471468 -204.120057) (xy 36.479486 -204.206586) (xy 36.479988 -204.250036)
			(xy 36.479486 -204.293486) (xy 36.471468 -204.380015) (xy 36.4555 -204.465435) (xy 36.431719 -204.549017)
			(xy 36.400327 -204.630049) (xy 36.361593 -204.707838) (xy 36.315846 -204.781722) (xy 36.263477 -204.851069)
			(xy 36.204933 -204.915289) (xy 36.140713 -204.973833) (xy 36.071366 -205.026202) (xy 35.997482 -205.071949)
			(xy 35.919693 -205.110683) (xy 35.838661 -205.142075) (xy 35.755079 -205.165856) (xy 35.669659 -205.181824)
			(xy 35.58313 -205.189842) (xy 35.49623 -205.189842) (xy 35.409701 -205.181824) (xy 35.324281 -205.165856)
			(xy 35.240699 -205.142075) (xy 35.159667 -205.110683) (xy 35.081878 -205.071949) (xy 35.007994 -205.026202)
			(xy 34.938647 -204.973833) (xy 34.874427 -204.915289) (xy 34.815883 -204.851069) (xy 34.763514 -204.781722)
			(xy 34.717767 -204.707838) (xy 34.679033 -204.630049) (xy 34.647641 -204.549017) (xy 34.62386 -204.465435)
			(xy 34.607892 -204.380015) (xy 34.599874 -204.293486) (xy 31.399486 -204.293486) (xy 31.391468 -204.380015)
			(xy 31.3755 -204.465435) (xy 31.351719 -204.549017) (xy 31.320327 -204.630049) (xy 31.281593 -204.707838)
			(xy 31.235846 -204.781722) (xy 31.183477 -204.851069) (xy 31.124933 -204.915289) (xy 31.060713 -204.973833)
			(xy 30.991366 -205.026202) (xy 30.917482 -205.071949) (xy 30.839693 -205.110683) (xy 30.758661 -205.142075)
			(xy 30.675079 -205.165856) (xy 30.589659 -205.181824) (xy 30.50313 -205.189842) (xy 30.41623 -205.189842)
			(xy 30.329701 -205.181824) (xy 30.244281 -205.165856) (xy 30.160699 -205.142075) (xy 30.079667 -205.110683)
			(xy 30.001878 -205.071949) (xy 29.927994 -205.026202) (xy 29.858647 -204.973833) (xy 29.794427 -204.915289)
			(xy 29.735883 -204.851069) (xy 29.683514 -204.781722) (xy 29.637767 -204.707838) (xy 29.599033 -204.630049)
			(xy 29.567641 -204.549017) (xy 29.54386 -204.465435) (xy 29.527892 -204.380015) (xy 29.519874 -204.293486)
			(xy 28.461716 -204.293486) (xy 28.461716 -206.833486) (xy 29.519874 -206.833486) (xy 29.519874 -206.746586)
			(xy 29.527892 -206.660057) (xy 29.54386 -206.574637) (xy 29.567641 -206.491055) (xy 29.599033 -206.410023)
			(xy 29.637767 -206.332234) (xy 29.683514 -206.25835) (xy 29.735883 -206.189003) (xy 29.794427 -206.124783)
			(xy 29.858647 -206.066239) (xy 29.927994 -206.01387) (xy 30.001878 -205.968123) (xy 30.079667 -205.929389)
			(xy 30.160699 -205.897997) (xy 30.244281 -205.874216) (xy 30.329701 -205.858248) (xy 30.41623 -205.85023)
			(xy 30.50313 -205.85023) (xy 30.589659 -205.858248) (xy 30.675079 -205.874216) (xy 30.758661 -205.897997)
			(xy 30.839693 -205.929389) (xy 30.917482 -205.968123) (xy 30.991366 -206.01387) (xy 31.060713 -206.066239)
			(xy 31.124933 -206.124783) (xy 31.183477 -206.189003) (xy 31.235846 -206.25835) (xy 31.281593 -206.332234)
			(xy 31.320327 -206.410023) (xy 31.351719 -206.491055) (xy 31.3755 -206.574637) (xy 31.391468 -206.660057)
			(xy 31.399486 -206.746586) (xy 31.399988 -206.790036) (xy 31.399486 -206.833486) (xy 34.599874 -206.833486)
			(xy 34.599874 -206.746586) (xy 34.607892 -206.660057) (xy 34.62386 -206.574637) (xy 34.647641 -206.491055)
			(xy 34.679033 -206.410023) (xy 34.717767 -206.332234) (xy 34.763514 -206.25835) (xy 34.815883 -206.189003)
			(xy 34.874427 -206.124783) (xy 34.938647 -206.066239) (xy 35.007994 -206.01387) (xy 35.081878 -205.968123)
			(xy 35.159667 -205.929389) (xy 35.240699 -205.897997) (xy 35.324281 -205.874216) (xy 35.409701 -205.858248)
			(xy 35.49623 -205.85023) (xy 35.58313 -205.85023) (xy 35.669659 -205.858248) (xy 35.755079 -205.874216)
			(xy 35.838661 -205.897997) (xy 35.919693 -205.929389) (xy 35.997482 -205.968123) (xy 36.071366 -206.01387)
			(xy 36.140713 -206.066239) (xy 36.204933 -206.124783) (xy 36.263477 -206.189003) (xy 36.315846 -206.25835)
			(xy 36.339633 -206.296768) (xy 64.56248 -206.296768) (xy 64.566551 -206.241146) (xy 64.578677 -206.186709)
			(xy 64.5986 -206.134618) (xy 64.625896 -206.085983) (xy 64.659982 -206.04184) (xy 64.700131 -206.003131)
			(xy 64.745489 -205.97068) (xy 64.795089 -205.945179) (xy 64.847873 -205.927172) (xy 64.902716 -205.917042)
			(xy 64.95845 -205.915005) (xy 65.013887 -205.921105) (xy 65.067844 -205.935211) (xy 65.119173 -205.957023)
			(xy 65.166779 -205.986077) (xy 65.209647 -206.021752) (xy 65.246864 -206.063289) (xy 65.277637 -206.109802)
			(xy 65.301309 -206.160299) (xy 65.317377 -206.213706) (xy 65.325497 -206.268882) (xy 65.326006 -206.296768)
			(xy 68.215762 -206.296768) (xy 68.219833 -206.241146) (xy 68.231959 -206.186709) (xy 68.251882 -206.134618)
			(xy 68.279178 -206.085983) (xy 68.313264 -206.04184) (xy 68.353413 -206.003131) (xy 68.398771 -205.97068)
			(xy 68.448371 -205.945179) (xy 68.501155 -205.927172) (xy 68.555998 -205.917042) (xy 68.611732 -205.915005)
			(xy 68.667169 -205.921105) (xy 68.721126 -205.935211) (xy 68.772455 -205.957023) (xy 68.820061 -205.986077)
			(xy 68.862929 -206.021752) (xy 68.900146 -206.063289) (xy 68.930919 -206.109802) (xy 68.954591 -206.160299)
			(xy 68.970659 -206.213706) (xy 68.978779 -206.268882) (xy 68.979288 -206.296768) (xy 68.978779 -206.324654)
			(xy 68.970659 -206.37983) (xy 68.954591 -206.433237) (xy 68.930919 -206.483734) (xy 68.900146 -206.530247)
			(xy 68.862929 -206.571784) (xy 68.820061 -206.607459) (xy 68.772455 -206.636513) (xy 68.721126 -206.658325)
			(xy 68.667169 -206.672431) (xy 68.611732 -206.678531) (xy 68.555998 -206.676494) (xy 68.501155 -206.666364)
			(xy 68.448371 -206.648357) (xy 68.398771 -206.622856) (xy 68.353413 -206.590405) (xy 68.313264 -206.551696)
			(xy 68.279178 -206.507553) (xy 68.251882 -206.458918) (xy 68.231959 -206.406827) (xy 68.219833 -206.35239)
			(xy 68.215762 -206.296768) (xy 65.326006 -206.296768) (xy 65.325497 -206.324654) (xy 65.317377 -206.37983)
			(xy 65.301309 -206.433237) (xy 65.277637 -206.483734) (xy 65.246864 -206.530247) (xy 65.209647 -206.571784)
			(xy 65.166779 -206.607459) (xy 65.119173 -206.636513) (xy 65.067844 -206.658325) (xy 65.013887 -206.672431)
			(xy 64.95845 -206.678531) (xy 64.902716 -206.676494) (xy 64.847873 -206.666364) (xy 64.795089 -206.648357)
			(xy 64.745489 -206.622856) (xy 64.700131 -206.590405) (xy 64.659982 -206.551696) (xy 64.625896 -206.507553)
			(xy 64.5986 -206.458918) (xy 64.578677 -206.406827) (xy 64.566551 -206.35239) (xy 64.56248 -206.296768)
			(xy 36.339633 -206.296768) (xy 36.361593 -206.332234) (xy 36.400327 -206.410023) (xy 36.431719 -206.491055)
			(xy 36.4555 -206.574637) (xy 36.471468 -206.660057) (xy 36.479486 -206.746586) (xy 36.479988 -206.790036)
			(xy 36.479486 -206.833486) (xy 36.471468 -206.920015) (xy 36.4555 -207.005435) (xy 36.431719 -207.089017)
			(xy 36.400327 -207.170049) (xy 36.361593 -207.247838) (xy 36.315846 -207.321722) (xy 36.263477 -207.391069)
			(xy 36.204933 -207.455289) (xy 36.140713 -207.513833) (xy 36.071366 -207.566202) (xy 35.997482 -207.611949)
			(xy 35.919693 -207.650683) (xy 35.838661 -207.682075) (xy 35.755079 -207.705856) (xy 35.669659 -207.721824)
			(xy 35.58313 -207.729842) (xy 35.49623 -207.729842) (xy 35.409701 -207.721824) (xy 35.324281 -207.705856)
			(xy 35.240699 -207.682075) (xy 35.159667 -207.650683) (xy 35.081878 -207.611949) (xy 35.007994 -207.566202)
			(xy 34.938647 -207.513833) (xy 34.874427 -207.455289) (xy 34.815883 -207.391069) (xy 34.763514 -207.321722)
			(xy 34.717767 -207.247838) (xy 34.679033 -207.170049) (xy 34.647641 -207.089017) (xy 34.62386 -207.005435)
			(xy 34.607892 -206.920015) (xy 34.599874 -206.833486) (xy 31.399486 -206.833486) (xy 31.391468 -206.920015)
			(xy 31.3755 -207.005435) (xy 31.351719 -207.089017) (xy 31.320327 -207.170049) (xy 31.281593 -207.247838)
			(xy 31.235846 -207.321722) (xy 31.183477 -207.391069) (xy 31.124933 -207.455289) (xy 31.060713 -207.513833)
			(xy 30.991366 -207.566202) (xy 30.917482 -207.611949) (xy 30.839693 -207.650683) (xy 30.758661 -207.682075)
			(xy 30.675079 -207.705856) (xy 30.589659 -207.721824) (xy 30.50313 -207.729842) (xy 30.41623 -207.729842)
			(xy 30.329701 -207.721824) (xy 30.244281 -207.705856) (xy 30.160699 -207.682075) (xy 30.079667 -207.650683)
			(xy 30.001878 -207.611949) (xy 29.927994 -207.566202) (xy 29.858647 -207.513833) (xy 29.794427 -207.455289)
			(xy 29.735883 -207.391069) (xy 29.683514 -207.321722) (xy 29.637767 -207.247838) (xy 29.599033 -207.170049)
			(xy 29.567641 -207.089017) (xy 29.54386 -207.005435) (xy 29.527892 -206.920015) (xy 29.519874 -206.833486)
			(xy 28.461716 -206.833486) (xy 28.461716 -209.373486) (xy 29.519874 -209.373486) (xy 29.519874 -209.286586)
			(xy 29.527892 -209.200057) (xy 29.54386 -209.114637) (xy 29.567641 -209.031055) (xy 29.599033 -208.950023)
			(xy 29.637767 -208.872234) (xy 29.683514 -208.79835) (xy 29.735883 -208.729003) (xy 29.794427 -208.664783)
			(xy 29.858647 -208.606239) (xy 29.927994 -208.55387) (xy 30.001878 -208.508123) (xy 30.079667 -208.469389)
			(xy 30.160699 -208.437997) (xy 30.244281 -208.414216) (xy 30.329701 -208.398248) (xy 30.41623 -208.39023)
			(xy 30.50313 -208.39023) (xy 30.589659 -208.398248) (xy 30.675079 -208.414216) (xy 30.758661 -208.437997)
			(xy 30.839693 -208.469389) (xy 30.917482 -208.508123) (xy 30.991366 -208.55387) (xy 31.060713 -208.606239)
			(xy 31.124933 -208.664783) (xy 31.183477 -208.729003) (xy 31.235846 -208.79835) (xy 31.281593 -208.872234)
			(xy 31.320327 -208.950023) (xy 31.351719 -209.031055) (xy 31.3755 -209.114637) (xy 31.391468 -209.200057)
			(xy 31.399486 -209.286586) (xy 31.399988 -209.330036) (xy 31.399486 -209.373486) (xy 34.599874 -209.373486)
			(xy 34.599874 -209.286586) (xy 34.607892 -209.200057) (xy 34.62386 -209.114637) (xy 34.647641 -209.031055)
			(xy 34.679033 -208.950023) (xy 34.717767 -208.872234) (xy 34.763514 -208.79835) (xy 34.815883 -208.729003)
			(xy 34.874427 -208.664783) (xy 34.938647 -208.606239) (xy 35.007994 -208.55387) (xy 35.081878 -208.508123)
			(xy 35.159667 -208.469389) (xy 35.240699 -208.437997) (xy 35.324281 -208.414216) (xy 35.409701 -208.398248)
			(xy 35.49623 -208.39023) (xy 35.58313 -208.39023) (xy 35.669659 -208.398248) (xy 35.755079 -208.414216)
			(xy 35.838661 -208.437997) (xy 35.919693 -208.469389) (xy 35.997482 -208.508123) (xy 36.071366 -208.55387)
			(xy 36.140713 -208.606239) (xy 36.204933 -208.664783) (xy 36.263477 -208.729003) (xy 36.315846 -208.79835)
			(xy 36.361593 -208.872234) (xy 36.400327 -208.950023) (xy 36.408868 -208.97207) (xy 39.100938 -208.97207)
			(xy 39.104829 -208.917724) (xy 39.116415 -208.864486) (xy 39.13546 -208.813438) (xy 39.161576 -208.76562)
			(xy 39.194232 -208.722006) (xy 39.232762 -208.683483) (xy 39.276383 -208.650836) (xy 39.324206 -208.624729)
			(xy 39.375257 -208.605694) (xy 39.428498 -208.594119) (xy 39.482844 -208.590238) (xy 39.53719 -208.594131)
			(xy 39.590428 -208.605719) (xy 39.641475 -208.624766) (xy 39.689292 -208.650884) (xy 39.711376 -208.666842)
			(xy 39.730388 -208.680438) (xy 39.772271 -208.70117) (xy 39.817239 -208.713896) (xy 39.863776 -208.718186)
			(xy 39.910313 -208.713896) (xy 39.955281 -208.70117) (xy 39.997164 -208.680438) (xy 40.016176 -208.666842)
			(xy 40.038218 -208.650813) (xy 40.086048 -208.624682) (xy 40.13711 -208.605624) (xy 40.190365 -208.594028)
			(xy 40.244728 -208.590129) (xy 40.299093 -208.594007) (xy 40.352352 -208.605584) (xy 40.403422 -208.624622)
			(xy 40.451261 -208.650735) (xy 40.494898 -208.683391) (xy 40.533442 -208.721925) (xy 40.56611 -208.765553)
			(xy 40.592236 -208.813386) (xy 40.611288 -208.86445) (xy 40.622878 -208.917706) (xy 40.626771 -208.97207)
			(xy 40.987631 -208.97207) (xy 40.991522 -208.917723) (xy 41.003109 -208.864482) (xy 41.022154 -208.813433)
			(xy 41.048271 -208.765614) (xy 41.080928 -208.721999) (xy 41.11946 -208.683475) (xy 41.163082 -208.650828)
			(xy 41.210907 -208.624721) (xy 41.26196 -208.605686) (xy 41.315203 -208.594111) (xy 41.369551 -208.590231)
			(xy 41.423898 -208.594125) (xy 41.477138 -208.605715) (xy 41.528186 -208.624763) (xy 41.576004 -208.650883)
			(xy 41.598088 -208.666842) (xy 41.6171 -208.680438) (xy 41.658983 -208.70117) (xy 41.703951 -208.713896)
			(xy 41.750488 -208.718186) (xy 41.797025 -208.713896) (xy 41.841993 -208.70117) (xy 41.883876 -208.680438)
			(xy 41.902888 -208.666842) (xy 41.92493 -208.650814) (xy 41.972759 -208.624684) (xy 42.02382 -208.605629)
			(xy 42.077074 -208.594034) (xy 42.131435 -208.590136) (xy 42.185798 -208.594015) (xy 42.239055 -208.605592)
			(xy 42.290123 -208.624631) (xy 42.337961 -208.650743) (xy 42.381596 -208.683399) (xy 42.420139 -208.721932)
			(xy 42.452805 -208.765559) (xy 42.47893 -208.813391) (xy 42.497981 -208.864453) (xy 42.509571 -208.917708)
			(xy 42.513464 -208.97207) (xy 43.228606 -208.97207) (xy 43.232498 -208.917717) (xy 43.244086 -208.864471)
			(xy 43.263134 -208.813417) (xy 43.289255 -208.765593) (xy 43.321916 -208.721974) (xy 43.360454 -208.683448)
			(xy 43.404082 -208.650798) (xy 43.451912 -208.62469) (xy 43.502972 -208.605656) (xy 43.556221 -208.594083)
			(xy 43.610575 -208.590206) (xy 43.664928 -208.594104) (xy 43.718172 -208.605698) (xy 43.769224 -208.624753)
			(xy 43.817045 -208.650879) (xy 43.83913 -208.666842) (xy 43.858142 -208.680438) (xy 43.900025 -208.70117)
			(xy 43.944993 -208.713896) (xy 43.99153 -208.718186) (xy 44.038067 -208.713896) (xy 44.083035 -208.70117)
			(xy 44.124918 -208.680438) (xy 44.14393 -208.666842) (xy 44.165971 -208.650817) (xy 44.213797 -208.624695)
			(xy 44.264854 -208.605645) (xy 44.318103 -208.594055) (xy 44.372459 -208.590161) (xy 44.426816 -208.594043)
			(xy 44.480067 -208.605622) (xy 44.531128 -208.624661) (xy 44.57896 -208.650773) (xy 44.622589 -208.683427)
			(xy 44.661127 -208.721957) (xy 44.693789 -208.76558) (xy 44.71991 -208.813407) (xy 44.738958 -208.864465)
			(xy 44.750547 -208.917714) (xy 44.754439 -208.97207) (xy 45.132615 -208.97207) (xy 45.136507 -208.917719)
			(xy 45.148094 -208.864476) (xy 45.167142 -208.813423) (xy 45.193261 -208.765601) (xy 45.225921 -208.721984)
			(xy 45.264456 -208.683458) (xy 45.308082 -208.650809) (xy 45.35591 -208.624702) (xy 45.406968 -208.605667)
			(xy 45.460214 -208.594093) (xy 45.514566 -208.590215) (xy 45.568916 -208.594112) (xy 45.622159 -208.605705)
			(xy 45.67321 -208.624757) (xy 45.721029 -208.650881) (xy 45.743114 -208.666842) (xy 45.762126 -208.680438)
			(xy 45.804009 -208.70117) (xy 45.848977 -208.713896) (xy 45.895514 -208.718186) (xy 45.942051 -208.713896)
			(xy 45.987019 -208.70117) (xy 46.028902 -208.680438) (xy 46.047914 -208.666842) (xy 46.069955 -208.650816)
			(xy 46.117782 -208.624691) (xy 46.168841 -208.605639) (xy 46.222092 -208.594047) (xy 46.27645 -208.590152)
			(xy 46.330809 -208.594033) (xy 46.384063 -208.60561) (xy 46.435126 -208.624649) (xy 46.482961 -208.650762)
			(xy 46.526592 -208.683416) (xy 46.565132 -208.721948) (xy 46.597795 -208.765572) (xy 46.623918 -208.813401)
			(xy 46.642967 -208.86446) (xy 46.654556 -208.917712) (xy 46.658448 -208.97207) (xy 46.654564 -209.026429)
			(xy 46.642984 -209.079682) (xy 46.623942 -209.130745) (xy 46.597828 -209.178578) (xy 46.581042 -209.201004)
			(xy 64.60058 -209.201004) (xy 64.604651 -209.145382) (xy 64.616777 -209.090945) (xy 64.6367 -209.038854)
			(xy 64.663996 -208.990219) (xy 64.698082 -208.946076) (xy 64.738231 -208.907367) (xy 64.783589 -208.874916)
			(xy 64.833189 -208.849415) (xy 64.885973 -208.831408) (xy 64.940816 -208.821278) (xy 64.99655 -208.819241)
			(xy 65.051987 -208.825341) (xy 65.105944 -208.839447) (xy 65.157273 -208.861259) (xy 65.204879 -208.890313)
			(xy 65.247747 -208.925988) (xy 65.284964 -208.967525) (xy 65.315737 -209.014038) (xy 65.339409 -209.064535)
			(xy 65.355477 -209.117942) (xy 65.363597 -209.173118) (xy 65.364106 -209.201004) (xy 65.363597 -209.22889)
			(xy 65.355477 -209.284066) (xy 65.339409 -209.337473) (xy 65.315737 -209.38797) (xy 65.284964 -209.434483)
			(xy 65.247747 -209.47602) (xy 65.204879 -209.511695) (xy 65.157273 -209.540749) (xy 65.105944 -209.562561)
			(xy 65.051987 -209.576667) (xy 64.99655 -209.582767) (xy 64.940816 -209.58073) (xy 64.885973 -209.5706)
			(xy 64.833189 -209.552593) (xy 64.783589 -209.527092) (xy 64.738231 -209.494641) (xy 64.698082 -209.455932)
			(xy 64.663996 -209.411789) (xy 64.6367 -209.363154) (xy 64.616777 -209.311063) (xy 64.604651 -209.256626)
			(xy 64.60058 -209.201004) (xy 46.581042 -209.201004) (xy 46.565171 -209.222207) (xy 46.526637 -209.260745)
			(xy 46.483011 -209.293406) (xy 46.435181 -209.319526) (xy 46.38412 -209.338573) (xy 46.330869 -209.350159)
			(xy 46.27651 -209.354048) (xy 46.222151 -209.350162) (xy 46.168899 -209.338578) (xy 46.117837 -209.319534)
			(xy 46.070005 -209.293417) (xy 46.047914 -209.277458) (xy 46.028902 -209.263862) (xy 45.987019 -209.24313)
			(xy 45.942051 -209.230404) (xy 45.895514 -209.226114) (xy 45.848977 -209.230404) (xy 45.804009 -209.24313)
			(xy 45.762126 -209.263862) (xy 45.743114 -209.277458) (xy 45.720979 -209.293352) (xy 45.673155 -209.319468)
			(xy 45.622101 -209.338512) (xy 45.568857 -209.350097) (xy 45.514506 -209.353985) (xy 45.460155 -209.350098)
			(xy 45.40691 -209.338516) (xy 45.355856 -209.319473) (xy 45.308031 -209.293358) (xy 45.264411 -209.260703)
			(xy 45.225882 -209.222171) (xy 45.193229 -209.178548) (xy 45.167117 -209.130722) (xy 45.148078 -209.079667)
			(xy 45.136498 -209.026421) (xy 45.132615 -208.97207) (xy 44.754439 -208.97207) (xy 44.750555 -209.026427)
			(xy 44.738975 -209.079678) (xy 44.719935 -209.130738) (xy 44.693821 -209.17857) (xy 44.661166 -209.222198)
			(xy 44.622635 -209.260734) (xy 44.579011 -209.293395) (xy 44.531183 -209.319514) (xy 44.480125 -209.338561)
			(xy 44.426875 -209.350148) (xy 44.372519 -209.354039) (xy 44.318162 -209.350154) (xy 44.264912 -209.338572)
			(xy 44.213852 -209.31953) (xy 44.166021 -209.293415) (xy 44.14393 -209.277458) (xy 44.124918 -209.263862)
			(xy 44.083035 -209.24313) (xy 44.038067 -209.230404) (xy 43.99153 -209.226114) (xy 43.944993 -209.230404)
			(xy 43.900025 -209.24313) (xy 43.858142 -209.263862) (xy 43.83913 -209.277458) (xy 43.816994 -209.293353)
			(xy 43.76917 -209.319472) (xy 43.718114 -209.338519) (xy 43.664868 -209.350105) (xy 43.610515 -209.353994)
			(xy 43.556162 -209.350109) (xy 43.502915 -209.338527) (xy 43.451858 -209.319485) (xy 43.404031 -209.293369)
			(xy 43.360408 -209.260713) (xy 43.321877 -209.222181) (xy 43.289223 -209.178556) (xy 43.263109 -209.130729)
			(xy 43.244069 -209.079671) (xy 43.232489 -209.026424) (xy 43.228606 -208.97207) (xy 42.513464 -208.97207)
			(xy 42.50958 -209.026433) (xy 42.497998 -209.079689) (xy 42.478955 -209.130755) (xy 42.452838 -209.178591)
			(xy 42.420178 -209.222222) (xy 42.381641 -209.260762) (xy 42.338012 -209.293424) (xy 42.290178 -209.319545)
			(xy 42.239113 -209.338591) (xy 42.185857 -209.350176) (xy 42.131495 -209.354064) (xy 42.077133 -209.350175)
			(xy 42.023878 -209.338588) (xy 41.972813 -209.31954) (xy 41.92498 -209.293419) (xy 41.902888 -209.277458)
			(xy 41.883876 -209.263862) (xy 41.841993 -209.24313) (xy 41.797025 -209.230404) (xy 41.750488 -209.226114)
			(xy 41.703951 -209.230404) (xy 41.658983 -209.24313) (xy 41.6171 -209.263862) (xy 41.598088 -209.277458)
			(xy 41.575953 -209.293349) (xy 41.528132 -209.319462) (xy 41.47708 -209.338502) (xy 41.423839 -209.350083)
			(xy 41.369491 -209.353969) (xy 41.315144 -209.350081) (xy 41.261903 -209.338497) (xy 41.210853 -209.319454)
			(xy 41.163032 -209.29334) (xy 41.119415 -209.260685) (xy 41.080889 -209.222156) (xy 41.048239 -209.178535)
			(xy 41.022129 -209.130712) (xy 41.003092 -209.07966) (xy 40.991514 -209.026418) (xy 40.987631 -208.97207)
			(xy 40.626771 -208.97207) (xy 40.622887 -209.026434) (xy 40.611305 -209.079692) (xy 40.592261 -209.13076)
			(xy 40.566142 -209.178597) (xy 40.533482 -209.222229) (xy 40.494943 -209.26077) (xy 40.451312 -209.293433)
			(xy 40.403476 -209.319553) (xy 40.35241 -209.3386) (xy 40.299152 -209.350184) (xy 40.244788 -209.354071)
			(xy 40.190425 -209.350181) (xy 40.137168 -209.338593) (xy 40.086103 -209.319543) (xy 40.038268 -209.29342)
			(xy 40.016176 -209.277458) (xy 39.997164 -209.263862) (xy 39.955281 -209.24313) (xy 39.910313 -209.230404)
			(xy 39.863776 -209.226114) (xy 39.817239 -209.230404) (xy 39.772271 -209.24313) (xy 39.730388 -209.263862)
			(xy 39.711376 -209.277458) (xy 39.689242 -209.293348) (xy 39.641421 -209.319459) (xy 39.590371 -209.338498)
			(xy 39.53713 -209.350077) (xy 39.482784 -209.353962) (xy 39.428439 -209.350073) (xy 39.3752 -209.338489)
			(xy 39.324151 -209.319446) (xy 39.276332 -209.293332) (xy 39.232717 -209.260678) (xy 39.194193 -209.222149)
			(xy 39.161544 -209.178529) (xy 39.135435 -209.130708) (xy 39.116398 -209.079657) (xy 39.104821 -209.026416)
			(xy 39.100938 -208.97207) (xy 36.408868 -208.97207) (xy 36.431719 -209.031055) (xy 36.4555 -209.114637)
			(xy 36.471468 -209.200057) (xy 36.479486 -209.286586) (xy 36.479988 -209.330036) (xy 36.479486 -209.373486)
			(xy 36.471468 -209.460015) (xy 36.4555 -209.545435) (xy 36.431719 -209.629017) (xy 36.400327 -209.710049)
			(xy 36.361593 -209.787838) (xy 36.315846 -209.861722) (xy 36.263477 -209.931069) (xy 36.204933 -209.995289)
			(xy 36.140713 -210.053833) (xy 36.080034 -210.099656) (xy 72.868035 -210.099656) (xy 72.872042 -209.896906)
			(xy 72.884055 -209.694472) (xy 72.904056 -209.492671) (xy 72.932015 -209.291817) (xy 72.967886 -209.092225)
			(xy 73.011615 -208.894206) (xy 73.063133 -208.698069) (xy 73.122359 -208.504121) (xy 73.189201 -208.312663)
			(xy 73.263555 -208.123996) (xy 73.345304 -207.938414) (xy 73.434322 -207.756206) (xy 73.530468 -207.577657)
			(xy 73.633593 -207.403046) (xy 73.743536 -207.232646) (xy 73.860125 -207.066722) (xy 73.983178 -206.905533)
			(xy 74.112503 -206.749332) (xy 74.247898 -206.598362) (xy 74.389151 -206.452858) (xy 74.536043 -206.313049)
			(xy 74.688343 -206.179152) (xy 74.845814 -206.051377) (xy 75.008211 -205.929922) (xy 75.175278 -205.814978)
			(xy 75.346757 -205.706724) (xy 75.522378 -205.605329) (xy 75.701868 -205.510951) (xy 75.884946 -205.423739)
			(xy 76.071327 -205.343827) (xy 76.26072 -205.27134) (xy 76.452828 -205.206393) (xy 76.647352 -205.149085)
			(xy 76.843988 -205.099508) (xy 77.04243 -205.057737) (xy 77.242367 -205.023839) (xy 77.443486 -204.997867)
			(xy 77.645475 -204.97986) (xy 77.848018 -204.969847) (xy 78.050798 -204.967843) (xy 78.253499 -204.973853)
			(xy 78.455804 -204.987865) (xy 78.657398 -205.00986) (xy 78.857965 -205.039801) (xy 79.057193 -205.077642)
			(xy 79.254771 -205.123325) (xy 79.450389 -205.176778) (xy 79.643743 -205.237917) (xy 79.834531 -205.306648)
			(xy 80.022454 -205.382862) (xy 80.20722 -205.466441) (xy 80.388539 -205.557254) (xy 80.56613 -205.655159)
			(xy 80.739713 -205.760004) (xy 80.909019 -205.871625) (xy 81.073784 -205.989847) (xy 81.233749 -206.114487)
			(xy 81.388665 -206.245348) (xy 81.53829 -206.382228) (xy 81.68239 -206.524912) (xy 81.820742 -206.673178)
			(xy 81.953127 -206.826794) (xy 82.079341 -206.985519) (xy 82.199185 -207.149108) (xy 82.312473 -207.317303)
			(xy 82.419028 -207.489842) (xy 82.518683 -207.666457) (xy 82.611283 -207.84687) (xy 82.696683 -208.030801)
			(xy 82.77475 -208.217962) (xy 82.845362 -208.408062) (xy 82.908408 -208.600802) (xy 82.963791 -208.795883)
			(xy 83.011423 -208.993) (xy 83.051231 -209.191844) (xy 83.083153 -209.392106) (xy 83.107137 -209.593472)
			(xy 83.123148 -209.795629) (xy 83.131159 -209.998261) (xy 83.13166 -210.099656) (xy 83.131159 -210.201051)
			(xy 83.123148 -210.403683) (xy 83.107137 -210.60584) (xy 83.083153 -210.807206) (xy 83.051231 -211.007468)
			(xy 83.011423 -211.206312) (xy 82.963791 -211.403429) (xy 82.908408 -211.59851) (xy 82.845362 -211.79125)
			(xy 82.77475 -211.98135) (xy 82.696683 -212.168511) (xy 82.611283 -212.352442) (xy 82.518683 -212.532855)
			(xy 82.419028 -212.70947) (xy 82.312473 -212.882009) (xy 82.199185 -213.050204) (xy 82.079341 -213.213793)
			(xy 81.953127 -213.372518) (xy 81.820742 -213.526134) (xy 81.68239 -213.6744) (xy 81.53829 -213.817084)
			(xy 81.388665 -213.953964) (xy 81.233749 -214.084825) (xy 81.073784 -214.209465) (xy 80.909019 -214.327687)
			(xy 80.739713 -214.439308) (xy 80.56613 -214.544153) (xy 80.388539 -214.642058) (xy 80.20722 -214.732871)
			(xy 80.022454 -214.81645) (xy 79.834531 -214.892664) (xy 79.643743 -214.961395) (xy 79.450389 -215.022534)
			(xy 79.254771 -215.075987) (xy 79.057193 -215.12167) (xy 78.857965 -215.159511) (xy 78.657398 -215.189452)
			(xy 78.455804 -215.211447) (xy 78.253499 -215.225459) (xy 78.050798 -215.231469) (xy 77.848018 -215.229465)
			(xy 77.645475 -215.219452) (xy 77.443486 -215.201445) (xy 77.242367 -215.175473) (xy 77.04243 -215.141575)
			(xy 76.843988 -215.099804) (xy 76.647352 -215.050227) (xy 76.452828 -214.992919) (xy 76.26072 -214.927972)
			(xy 76.071327 -214.855485) (xy 75.884946 -214.775573) (xy 75.701868 -214.688361) (xy 75.522378 -214.593983)
			(xy 75.346757 -214.492588) (xy 75.175278 -214.384334) (xy 75.008211 -214.26939) (xy 74.845814 -214.147935)
			(xy 74.688343 -214.02016) (xy 74.536043 -213.886263) (xy 74.389151 -213.746454) (xy 74.247898 -213.60095)
			(xy 74.112503 -213.44998) (xy 73.983178 -213.293779) (xy 73.860125 -213.13259) (xy 73.743536 -212.966666)
			(xy 73.633593 -212.796266) (xy 73.530468 -212.621655) (xy 73.434322 -212.443106) (xy 73.345304 -212.260898)
			(xy 73.263555 -212.075316) (xy 73.189201 -211.886649) (xy 73.122359 -211.695191) (xy 73.063133 -211.501243)
			(xy 73.011615 -211.305106) (xy 72.967886 -211.107087) (xy 72.932015 -210.907495) (xy 72.904056 -210.706641)
			(xy 72.884055 -210.50484) (xy 72.872042 -210.302406) (xy 72.868035 -210.099656) (xy 36.080034 -210.099656)
			(xy 36.071366 -210.106202) (xy 35.997482 -210.151949) (xy 35.919693 -210.190683) (xy 35.838661 -210.222075)
			(xy 35.755079 -210.245856) (xy 35.669659 -210.261824) (xy 35.58313 -210.269842) (xy 35.49623 -210.269842)
			(xy 35.409701 -210.261824) (xy 35.324281 -210.245856) (xy 35.240699 -210.222075) (xy 35.159667 -210.190683)
			(xy 35.081878 -210.151949) (xy 35.007994 -210.106202) (xy 34.938647 -210.053833) (xy 34.874427 -209.995289)
			(xy 34.815883 -209.931069) (xy 34.763514 -209.861722) (xy 34.717767 -209.787838) (xy 34.679033 -209.710049)
			(xy 34.647641 -209.629017) (xy 34.62386 -209.545435) (xy 34.607892 -209.460015) (xy 34.599874 -209.373486)
			(xy 31.399486 -209.373486) (xy 31.391468 -209.460015) (xy 31.3755 -209.545435) (xy 31.351719 -209.629017)
			(xy 31.320327 -209.710049) (xy 31.281593 -209.787838) (xy 31.235846 -209.861722) (xy 31.183477 -209.931069)
			(xy 31.124933 -209.995289) (xy 31.060713 -210.053833) (xy 30.991366 -210.106202) (xy 30.917482 -210.151949)
			(xy 30.839693 -210.190683) (xy 30.758661 -210.222075) (xy 30.675079 -210.245856) (xy 30.589659 -210.261824)
			(xy 30.50313 -210.269842) (xy 30.41623 -210.269842) (xy 30.329701 -210.261824) (xy 30.244281 -210.245856)
			(xy 30.160699 -210.222075) (xy 30.079667 -210.190683) (xy 30.001878 -210.151949) (xy 29.927994 -210.106202)
			(xy 29.858647 -210.053833) (xy 29.794427 -209.995289) (xy 29.735883 -209.931069) (xy 29.683514 -209.861722)
			(xy 29.637767 -209.787838) (xy 29.599033 -209.710049) (xy 29.567641 -209.629017) (xy 29.54386 -209.545435)
			(xy 29.527892 -209.460015) (xy 29.519874 -209.373486) (xy 28.461716 -209.373486) (xy 28.461716 -210.873108)
			(xy 39.100887 -210.873108) (xy 39.104773 -210.818755) (xy 39.116355 -210.765508) (xy 39.135398 -210.714452)
			(xy 39.161512 -210.666625) (xy 39.194168 -210.623001) (xy 39.2327 -210.58447) (xy 39.276323 -210.551814)
			(xy 39.324149 -210.525699) (xy 39.375206 -210.506656) (xy 39.428453 -210.495073) (xy 39.482806 -210.491187)
			(xy 39.537159 -210.495075) (xy 39.590406 -210.506659) (xy 39.641462 -210.525704) (xy 39.689287 -210.55182)
			(xy 39.711376 -210.567778) (xy 39.730388 -210.581374) (xy 39.772271 -210.602106) (xy 39.817239 -210.614832)
			(xy 39.863776 -210.619122) (xy 39.910313 -210.614832) (xy 39.955281 -210.602106) (xy 39.997164 -210.581374)
			(xy 40.016176 -210.567778) (xy 40.038278 -210.551835) (xy 40.086104 -210.525712) (xy 40.137162 -210.506662)
			(xy 40.19041 -210.495073) (xy 40.244767 -210.49118) (xy 40.299124 -210.495063) (xy 40.352375 -210.506643)
			(xy 40.403435 -210.525685) (xy 40.451266 -210.551799) (xy 40.494893 -210.584455) (xy 40.533429 -210.622988)
			(xy 40.566088 -210.666613) (xy 40.592205 -210.714442) (xy 40.61125 -210.765502) (xy 40.622833 -210.818752)
			(xy 40.62672 -210.873108) (xy 40.987579 -210.873108) (xy 40.991466 -210.818753) (xy 41.003049 -210.765505)
			(xy 41.022092 -210.714447) (xy 41.048208 -210.666619) (xy 41.080865 -210.622994) (xy 41.119398 -210.584462)
			(xy 41.163022 -210.551805) (xy 41.210851 -210.52569) (xy 41.261909 -210.506647) (xy 41.315158 -210.495065)
			(xy 41.369513 -210.491179) (xy 41.423868 -210.495069) (xy 41.477115 -210.506655) (xy 41.528172 -210.525701)
			(xy 41.575999 -210.551819) (xy 41.598088 -210.567778) (xy 41.6171 -210.581374) (xy 41.658983 -210.602106)
			(xy 41.703951 -210.614832) (xy 41.750488 -210.619122) (xy 41.797025 -210.614832) (xy 41.841993 -210.602106)
			(xy 41.883876 -210.581374) (xy 41.902888 -210.567778) (xy 41.92499 -210.551836) (xy 41.972815 -210.525715)
			(xy 42.023871 -210.506667) (xy 42.077119 -210.495079) (xy 42.131474 -210.491187) (xy 42.185829 -210.495071)
			(xy 42.239078 -210.506652) (xy 42.290137 -210.525693) (xy 42.337966 -210.551807) (xy 42.381591 -210.584463)
			(xy 42.420125 -210.622995) (xy 42.452783 -210.666619) (xy 42.478899 -210.714447) (xy 42.497943 -210.765505)
			(xy 42.509526 -210.818753) (xy 42.513413 -210.873108) (xy 43.228554 -210.873108) (xy 43.232441 -210.818748)
			(xy 43.244026 -210.765494) (xy 43.263072 -210.71443) (xy 43.289191 -210.666598) (xy 43.321853 -210.62297)
			(xy 43.360391 -210.584434) (xy 43.404022 -210.551776) (xy 43.451856 -210.52566) (xy 43.502921 -210.506618)
			(xy 43.556176 -210.495037) (xy 43.610537 -210.491154) (xy 43.664897 -210.495048) (xy 43.71815 -210.506638)
			(xy 43.769211 -210.52569) (xy 43.81704 -210.551816) (xy 43.83913 -210.567778) (xy 43.858142 -210.581374)
			(xy 43.900025 -210.602106) (xy 43.944993 -210.614832) (xy 43.99153 -210.619122) (xy 44.038067 -210.614832)
			(xy 44.083035 -210.602106) (xy 44.124918 -210.581374) (xy 44.14393 -210.567778) (xy 44.166031 -210.551839)
			(xy 44.213853 -210.525725) (xy 44.264906 -210.506683) (xy 44.318148 -210.4951) (xy 44.372497 -210.491213)
			(xy 44.426847 -210.4951) (xy 44.48009 -210.506682) (xy 44.531142 -210.525723) (xy 44.578965 -210.551837)
			(xy 44.622585 -210.58449) (xy 44.661113 -210.62302) (xy 44.693766 -210.66664) (xy 44.719879 -210.714463)
			(xy 44.73892 -210.765516) (xy 44.750501 -210.818759) (xy 44.754387 -210.873108) (xy 45.132564 -210.873108)
			(xy 45.136451 -210.81875) (xy 45.148034 -210.765498) (xy 45.167079 -210.714437) (xy 45.193197 -210.666606)
			(xy 45.225857 -210.622979) (xy 45.264394 -210.584445) (xy 45.308022 -210.551787) (xy 45.355854 -210.525671)
			(xy 45.406916 -210.506629) (xy 45.460169 -210.495048) (xy 45.514528 -210.491164) (xy 45.568886 -210.495056)
			(xy 45.622137 -210.506645) (xy 45.673196 -210.525694) (xy 45.721024 -210.551817) (xy 45.743114 -210.567778)
			(xy 45.762126 -210.581374) (xy 45.804009 -210.602106) (xy 45.848977 -210.614832) (xy 45.895514 -210.619122)
			(xy 45.942051 -210.614832) (xy 45.987019 -210.602106) (xy 46.028902 -210.581374) (xy 46.047914 -210.567778)
			(xy 46.070015 -210.551838) (xy 46.117839 -210.525721) (xy 46.168892 -210.506677) (xy 46.222137 -210.495092)
			(xy 46.276488 -210.491203) (xy 46.33084 -210.495089) (xy 46.384085 -210.50667) (xy 46.43514 -210.525712)
			(xy 46.482965 -210.551825) (xy 46.526587 -210.58448) (xy 46.565118 -210.62301) (xy 46.597773 -210.666632)
			(xy 46.623887 -210.714457) (xy 46.642929 -210.765512) (xy 46.654511 -210.818757) (xy 46.658397 -210.873108)
			(xy 46.654508 -210.92746) (xy 46.642924 -210.980704) (xy 46.62388 -211.031758) (xy 46.597764 -211.079582)
			(xy 46.565107 -211.123203) (xy 46.526575 -211.161731) (xy 46.482951 -211.194384) (xy 46.435125 -211.220495)
			(xy 46.384069 -211.239534) (xy 46.330823 -211.251114) (xy 46.276472 -211.254997) (xy 46.22212 -211.251105)
			(xy 46.168876 -211.239518) (xy 46.117823 -211.220472) (xy 46.070001 -211.194353) (xy 46.047914 -211.178394)
			(xy 46.028902 -211.164798) (xy 45.987019 -211.144066) (xy 45.942051 -211.13134) (xy 45.895514 -211.12705)
			(xy 45.848977 -211.13134) (xy 45.804009 -211.144066) (xy 45.762126 -211.164798) (xy 45.743114 -211.178394)
			(xy 45.721039 -211.194374) (xy 45.673211 -211.220499) (xy 45.622153 -211.239551) (xy 45.568902 -211.251142)
			(xy 45.514544 -211.255036) (xy 45.460186 -211.251154) (xy 45.406932 -211.239576) (xy 45.355869 -211.220536)
			(xy 45.308036 -211.194422) (xy 45.264406 -211.161766) (xy 45.225868 -211.123234) (xy 45.193207 -211.079608)
			(xy 45.167086 -211.031779) (xy 45.148039 -210.980718) (xy 45.136453 -210.927467) (xy 45.132564 -210.873108)
			(xy 44.754387 -210.873108) (xy 44.750499 -210.927458) (xy 44.738915 -210.9807) (xy 44.719872 -211.031752)
			(xy 44.693757 -211.079574) (xy 44.661102 -211.123193) (xy 44.622572 -211.161721) (xy 44.578951 -211.194372)
			(xy 44.531127 -211.220484) (xy 44.480073 -211.239523) (xy 44.42683 -211.251103) (xy 44.372481 -211.254987)
			(xy 44.318132 -211.251097) (xy 44.264889 -211.239512) (xy 44.213838 -211.220468) (xy 44.166016 -211.194351)
			(xy 44.14393 -211.178394) (xy 44.124918 -211.164798) (xy 44.083035 -211.144066) (xy 44.038067 -211.13134)
			(xy 43.99153 -211.12705) (xy 43.944993 -211.13134) (xy 43.900025 -211.144066) (xy 43.858142 -211.164798)
			(xy 43.83913 -211.178394) (xy 43.817054 -211.194375) (xy 43.769226 -211.220503) (xy 43.718166 -211.239557)
			(xy 43.664914 -211.25115) (xy 43.610554 -211.255046) (xy 43.556192 -211.251165) (xy 43.502937 -211.239587)
			(xy 43.451872 -211.220547) (xy 43.404036 -211.194433) (xy 43.360404 -211.161777) (xy 43.321864 -211.123243)
			(xy 43.2892 -211.079616) (xy 43.263079 -211.031785) (xy 43.24403 -210.980722) (xy 43.232444 -210.927469)
			(xy 43.228554 -210.873108) (xy 42.513413 -210.873108) (xy 42.509524 -210.927463) (xy 42.497938 -210.980711)
			(xy 42.478892 -211.031768) (xy 42.452774 -211.079595) (xy 42.420114 -211.123218) (xy 42.381579 -211.161748)
			(xy 42.337952 -211.194402) (xy 42.290121 -211.220514) (xy 42.239062 -211.239553) (xy 42.185812 -211.251131)
			(xy 42.131457 -211.255013) (xy 42.077102 -211.251119) (xy 42.023855 -211.239528) (xy 41.9728 -211.220478)
			(xy 41.924975 -211.194355) (xy 41.902888 -211.178394) (xy 41.883876 -211.164798) (xy 41.841993 -211.144066)
			(xy 41.797025 -211.13134) (xy 41.750488 -211.12705) (xy 41.703951 -211.13134) (xy 41.658983 -211.144066)
			(xy 41.6171 -211.164798) (xy 41.598088 -211.178394) (xy 41.576013 -211.194372) (xy 41.528188 -211.220492)
			(xy 41.477132 -211.239541) (xy 41.423884 -211.251129) (xy 41.36953 -211.255021) (xy 41.315174 -211.251137)
			(xy 41.261925 -211.239557) (xy 41.210866 -211.220517) (xy 41.163037 -211.194404) (xy 41.11941 -211.161749)
			(xy 41.080876 -211.123218) (xy 41.048217 -211.079595) (xy 41.022099 -211.031768) (xy 41.003053 -210.980711)
			(xy 40.991468 -210.927463) (xy 40.987579 -210.873108) (xy 40.62672 -210.873108) (xy 40.622831 -210.927465)
			(xy 40.611245 -210.980715) (xy 40.592198 -211.031773) (xy 40.566079 -211.079601) (xy 40.533418 -211.123225)
			(xy 40.494881 -211.161756) (xy 40.451252 -211.19441) (xy 40.40342 -211.220522) (xy 40.352358 -211.239561)
			(xy 40.299107 -211.251139) (xy 40.24475 -211.25502) (xy 40.190394 -211.251125) (xy 40.137145 -211.239533)
			(xy 40.086089 -211.220481) (xy 40.038264 -211.194356) (xy 40.016176 -211.178394) (xy 39.997164 -211.164798)
			(xy 39.955281 -211.144066) (xy 39.910313 -211.13134) (xy 39.863776 -211.12705) (xy 39.817239 -211.13134)
			(xy 39.772271 -211.144066) (xy 39.730388 -211.164798) (xy 39.711376 -211.178394) (xy 39.689302 -211.194371)
			(xy 39.641477 -211.220489) (xy 39.590422 -211.239536) (xy 39.537176 -211.251123) (xy 39.482823 -211.255013)
			(xy 39.428469 -211.251129) (xy 39.375222 -211.239549) (xy 39.324165 -211.220508) (xy 39.276337 -211.194395)
			(xy 39.232712 -211.161741) (xy 39.194179 -211.123211) (xy 39.161521 -211.079589) (xy 39.135405 -211.031764)
			(xy 39.11636 -210.980708) (xy 39.104775 -210.927462) (xy 39.100887 -210.873108) (xy 28.461716 -210.873108)
			(xy 28.461716 -211.913486) (xy 29.519874 -211.913486) (xy 29.519874 -211.826586) (xy 29.527892 -211.740057)
			(xy 29.54386 -211.654637) (xy 29.567641 -211.571055) (xy 29.599033 -211.490023) (xy 29.637767 -211.412234)
			(xy 29.683514 -211.33835) (xy 29.735883 -211.269003) (xy 29.794427 -211.204783) (xy 29.858647 -211.146239)
			(xy 29.927994 -211.09387) (xy 30.001878 -211.048123) (xy 30.079667 -211.009389) (xy 30.160699 -210.977997)
			(xy 30.244281 -210.954216) (xy 30.329701 -210.938248) (xy 30.41623 -210.93023) (xy 30.50313 -210.93023)
			(xy 30.589659 -210.938248) (xy 30.675079 -210.954216) (xy 30.758661 -210.977997) (xy 30.839693 -211.009389)
			(xy 30.917482 -211.048123) (xy 30.991366 -211.09387) (xy 31.060713 -211.146239) (xy 31.124933 -211.204783)
			(xy 31.183477 -211.269003) (xy 31.235846 -211.33835) (xy 31.281593 -211.412234) (xy 31.320327 -211.490023)
			(xy 31.351719 -211.571055) (xy 31.3755 -211.654637) (xy 31.391468 -211.740057) (xy 31.399486 -211.826586)
			(xy 31.399988 -211.870036) (xy 31.399486 -211.913486) (xy 34.599874 -211.913486) (xy 34.599874 -211.826586)
			(xy 34.607892 -211.740057) (xy 34.62386 -211.654637) (xy 34.647641 -211.571055) (xy 34.679033 -211.490023)
			(xy 34.717767 -211.412234) (xy 34.763514 -211.33835) (xy 34.815883 -211.269003) (xy 34.874427 -211.204783)
			(xy 34.938647 -211.146239) (xy 35.007994 -211.09387) (xy 35.081878 -211.048123) (xy 35.159667 -211.009389)
			(xy 35.240699 -210.977997) (xy 35.324281 -210.954216) (xy 35.409701 -210.938248) (xy 35.49623 -210.93023)
			(xy 35.58313 -210.93023) (xy 35.669659 -210.938248) (xy 35.755079 -210.954216) (xy 35.838661 -210.977997)
			(xy 35.919693 -211.009389) (xy 35.997482 -211.048123) (xy 36.071366 -211.09387) (xy 36.140713 -211.146239)
			(xy 36.204933 -211.204783) (xy 36.263477 -211.269003) (xy 36.315846 -211.33835) (xy 36.361593 -211.412234)
			(xy 36.400327 -211.490023) (xy 36.431719 -211.571055) (xy 36.4555 -211.654637) (xy 36.471468 -211.740057)
			(xy 36.479486 -211.826586) (xy 36.479988 -211.870036) (xy 36.479486 -211.913486) (xy 36.471468 -212.000015)
			(xy 36.4555 -212.085435) (xy 36.431719 -212.169017) (xy 36.400327 -212.250049) (xy 36.361593 -212.327838)
			(xy 36.315846 -212.401722) (xy 36.263477 -212.471069) (xy 36.204933 -212.535289) (xy 36.190781 -212.54819)
			(xy 39.100911 -212.54819) (xy 39.104799 -212.493841) (xy 39.116383 -212.440598) (xy 39.135427 -212.389545)
			(xy 39.161542 -212.341723) (xy 39.194198 -212.298103) (xy 39.232729 -212.259576) (xy 39.276351 -212.226924)
			(xy 39.324176 -212.200813) (xy 39.37523 -212.181774) (xy 39.428474 -212.170195) (xy 39.482824 -212.166311)
			(xy 39.537174 -212.170201) (xy 39.590416 -212.181787) (xy 39.641468 -212.200833) (xy 39.68929 -212.22695)
			(xy 39.711376 -212.242908) (xy 39.730388 -212.256504) (xy 39.772271 -212.277236) (xy 39.817239 -212.289962)
			(xy 39.863776 -212.294252) (xy 39.910313 -212.289962) (xy 39.955281 -212.277236) (xy 39.997164 -212.256504)
			(xy 40.016176 -212.242908) (xy 40.03825 -212.226924) (xy 40.086078 -212.200798) (xy 40.137138 -212.181744)
			(xy 40.190389 -212.170152) (xy 40.244749 -212.166256) (xy 40.299109 -212.170137) (xy 40.352364 -212.181715)
			(xy 40.403429 -212.200755) (xy 40.451264 -212.226869) (xy 40.494895 -212.259525) (xy 40.533435 -212.298058)
			(xy 40.566098 -212.341685) (xy 40.59222 -212.389516) (xy 40.611267 -212.440578) (xy 40.622854 -212.49383)
			(xy 40.626744 -212.54819) (xy 40.987603 -212.54819) (xy 40.991492 -212.493839) (xy 41.003077 -212.440594)
			(xy 41.022121 -212.38954) (xy 41.048238 -212.341717) (xy 41.080894 -212.298096) (xy 41.119427 -212.259568)
			(xy 41.163051 -212.226916) (xy 41.210877 -212.200804) (xy 41.261933 -212.181765) (xy 41.315179 -212.170187)
			(xy 41.369531 -212.166303) (xy 41.423882 -212.170195) (xy 41.477126 -212.181783) (xy 41.528179 -212.20083)
			(xy 41.576001 -212.226949) (xy 41.598088 -212.242908) (xy 41.6171 -212.256504) (xy 41.658983 -212.277236)
			(xy 41.703951 -212.289962) (xy 41.750488 -212.294252) (xy 41.797025 -212.289962) (xy 41.841993 -212.277236)
			(xy 41.883876 -212.256504) (xy 41.902888 -212.242908) (xy 41.924961 -212.226925) (xy 41.972789 -212.200801)
			(xy 42.023847 -212.181749) (xy 42.077098 -212.170158) (xy 42.131456 -212.166263) (xy 42.185814 -212.170145)
			(xy 42.239067 -212.181724) (xy 42.29013 -212.200764) (xy 42.337964 -212.226877) (xy 42.381594 -212.259533)
			(xy 42.420132 -212.298066) (xy 42.452793 -212.341691) (xy 42.478914 -212.38952) (xy 42.497961 -212.440581)
			(xy 42.509547 -212.493832) (xy 42.513437 -212.54819) (xy 43.228578 -212.54819) (xy 43.232468 -212.493833)
			(xy 43.244054 -212.440583) (xy 43.263101 -212.389524) (xy 43.289221 -212.341696) (xy 43.321883 -212.298072)
			(xy 43.36042 -212.25954) (xy 43.40405 -212.226886) (xy 43.451883 -212.200774) (xy 43.502945 -212.181736)
			(xy 43.556197 -212.170159) (xy 43.610555 -212.166278) (xy 43.664911 -212.170174) (xy 43.71816 -212.181767)
			(xy 43.769217 -212.20082) (xy 43.817042 -212.226945) (xy 43.83913 -212.242908) (xy 43.858142 -212.256504)
			(xy 43.900025 -212.277236) (xy 43.944993 -212.289962) (xy 43.99153 -212.294252) (xy 44.038067 -212.289962)
			(xy 44.083035 -212.277236) (xy 44.124918 -212.256504) (xy 44.14393 -212.242908) (xy 44.166002 -212.226929)
			(xy 44.213827 -212.200811) (xy 44.264881 -212.181765) (xy 44.318127 -212.170179) (xy 44.372479 -212.166289)
			(xy 44.426832 -212.170173) (xy 44.480079 -212.181754) (xy 44.531136 -212.200794) (xy 44.578963 -212.226907)
			(xy 44.622587 -212.25956) (xy 44.66112 -212.29809) (xy 44.693777 -212.341712) (xy 44.719894 -212.389537)
			(xy 44.738938 -212.440592) (xy 44.750523 -212.493838) (xy 44.754411 -212.54819) (xy 45.132588 -212.54819)
			(xy 45.136477 -212.493835) (xy 45.148063 -212.440587) (xy 45.167109 -212.38953) (xy 45.193227 -212.341704)
			(xy 45.225887 -212.298081) (xy 45.264423 -212.259551) (xy 45.30805 -212.226898) (xy 45.355881 -212.200786)
			(xy 45.40694 -212.181747) (xy 45.46019 -212.170169) (xy 45.514546 -212.166288) (xy 45.5689 -212.170182)
			(xy 45.622147 -212.181773) (xy 45.673202 -212.200824) (xy 45.721027 -212.226947) (xy 45.743114 -212.242908)
			(xy 45.762126 -212.256504) (xy 45.804009 -212.277236) (xy 45.848977 -212.289962) (xy 45.895514 -212.294252)
			(xy 45.942051 -212.289962) (xy 45.987019 -212.277236) (xy 46.028902 -212.256504) (xy 46.047914 -212.242908)
			(xy 46.069987 -212.226928) (xy 46.117812 -212.200807) (xy 46.168868 -212.181759) (xy 46.222116 -212.170171)
			(xy 46.27647 -212.166279) (xy 46.330825 -212.170163) (xy 46.384075 -212.181742) (xy 46.435134 -212.200782)
			(xy 46.482963 -212.226896) (xy 46.526589 -212.25955) (xy 46.565124 -212.298081) (xy 46.597783 -212.341704)
			(xy 46.623901 -212.389531) (xy 46.642947 -212.440588) (xy 46.654532 -212.493836) (xy 46.658421 -212.54819)
			(xy 46.654535 -212.602545) (xy 46.642952 -212.655794) (xy 46.623909 -212.706852) (xy 46.597794 -212.75468)
			(xy 46.565137 -212.798305) (xy 46.526604 -212.836837) (xy 46.482979 -212.869494) (xy 46.435151 -212.89561)
			(xy 46.384093 -212.914652) (xy 46.330844 -212.926235) (xy 46.27649 -212.930121) (xy 46.222135 -212.926232)
			(xy 46.168887 -212.914646) (xy 46.11783 -212.895601) (xy 46.070003 -212.869483) (xy 46.047914 -212.853524)
			(xy 46.028902 -212.839928) (xy 45.987019 -212.819196) (xy 45.942051 -212.80647) (xy 45.895514 -212.80218)
			(xy 45.848977 -212.80647) (xy 45.804009 -212.819196) (xy 45.762126 -212.839928) (xy 45.743114 -212.853524)
			(xy 45.72101 -212.869464) (xy 45.673185 -212.895584) (xy 45.622129 -212.914633) (xy 45.568881 -212.926221)
			(xy 45.514526 -212.930112) (xy 45.460171 -212.926228) (xy 45.406922 -212.914648) (xy 45.355863 -212.895606)
			(xy 45.308034 -212.869492) (xy 45.264408 -212.836836) (xy 45.225875 -212.798304) (xy 45.193217 -212.75468)
			(xy 45.167101 -212.706852) (xy 45.148057 -212.655794) (xy 45.136474 -212.602545) (xy 45.132588 -212.54819)
			(xy 44.754411 -212.54819) (xy 44.750525 -212.602543) (xy 44.738943 -212.65579) (xy 44.719902 -212.706846)
			(xy 44.693787 -212.754672) (xy 44.661132 -212.798295) (xy 44.622601 -212.836827) (xy 44.578979 -212.869483)
			(xy 44.531153 -212.895598) (xy 44.480097 -212.914641) (xy 44.426851 -212.926224) (xy 44.372499 -212.930111)
			(xy 44.318146 -212.926224) (xy 44.2649 -212.91464) (xy 44.213844 -212.895597) (xy 44.166019 -212.869481)
			(xy 44.14393 -212.853524) (xy 44.124918 -212.839928) (xy 44.083035 -212.819196) (xy 44.038067 -212.80647)
			(xy 43.99153 -212.80218) (xy 43.944993 -212.80647) (xy 43.900025 -212.819196) (xy 43.858142 -212.839928)
			(xy 43.83913 -212.853524) (xy 43.817026 -212.869465) (xy 43.769199 -212.895588) (xy 43.718142 -212.914639)
			(xy 43.664892 -212.926229) (xy 43.610536 -212.930122) (xy 43.556178 -212.926239) (xy 43.502926 -212.914659)
			(xy 43.451865 -212.895618) (xy 43.404034 -212.869503) (xy 43.360406 -212.836847) (xy 43.32187 -212.798314)
			(xy 43.289211 -212.754688) (xy 43.263093 -212.706858) (xy 43.244048 -212.655798) (xy 43.232465 -212.602548)
			(xy 43.228578 -212.54819) (xy 42.513437 -212.54819) (xy 42.50955 -212.602549) (xy 42.497966 -212.655801)
			(xy 42.478922 -212.706862) (xy 42.452804 -212.754693) (xy 42.420144 -212.79832) (xy 42.381608 -212.836855)
			(xy 42.33798 -212.869512) (xy 42.290148 -212.895628) (xy 42.239086 -212.914671) (xy 42.185833 -212.926252)
			(xy 42.131475 -212.930137) (xy 42.077117 -212.926245) (xy 42.023866 -212.914657) (xy 41.972806 -212.895607)
			(xy 41.924978 -212.869485) (xy 41.902888 -212.853524) (xy 41.883876 -212.839928) (xy 41.841993 -212.819196)
			(xy 41.797025 -212.80647) (xy 41.750488 -212.80218) (xy 41.703951 -212.80647) (xy 41.658983 -212.819196)
			(xy 41.6171 -212.839928) (xy 41.598088 -212.853524) (xy 41.575985 -212.869461) (xy 41.528161 -212.895578)
			(xy 41.477108 -212.914623) (xy 41.423863 -212.926207) (xy 41.369512 -212.930097) (xy 41.31516 -212.926211)
			(xy 41.261915 -212.914629) (xy 41.21086 -212.895588) (xy 41.163034 -212.869474) (xy 41.119412 -212.836819)
			(xy 41.080882 -212.798289) (xy 41.048227 -212.754667) (xy 41.022113 -212.706842) (xy 41.003071 -212.655787)
			(xy 40.99149 -212.602542) (xy 40.987603 -212.54819) (xy 40.626744 -212.54819) (xy 40.622857 -212.602551)
			(xy 40.611273 -212.655804) (xy 40.592227 -212.706867) (xy 40.566108 -212.754699) (xy 40.533448 -212.798327)
			(xy 40.49491 -212.836862) (xy 40.45128 -212.869521) (xy 40.403446 -212.895637) (xy 40.352382 -212.914679)
			(xy 40.299128 -212.92626) (xy 40.244768 -212.930144) (xy 40.190408 -212.926251) (xy 40.137156 -212.914661)
			(xy 40.086095 -212.89561) (xy 40.038266 -212.869486) (xy 40.016176 -212.853524) (xy 39.997164 -212.839928)
			(xy 39.955281 -212.819196) (xy 39.910313 -212.80647) (xy 39.863776 -212.80218) (xy 39.817239 -212.80647)
			(xy 39.772271 -212.819196) (xy 39.730388 -212.839928) (xy 39.711376 -212.853524) (xy 39.689273 -212.86946)
			(xy 39.64145 -212.895575) (xy 39.590398 -212.914618) (xy 39.537155 -212.926201) (xy 39.482805 -212.930089)
			(xy 39.428455 -212.926203) (xy 39.375211 -212.914621) (xy 39.324158 -212.895579) (xy 39.276335 -212.869466)
			(xy 39.232714 -212.836812) (xy 39.194185 -212.798282) (xy 39.161532 -212.754661) (xy 39.135419 -212.706837)
			(xy 39.116378 -212.655784) (xy 39.104797 -212.60254) (xy 39.100911 -212.54819) (xy 36.190781 -212.54819)
			(xy 36.140713 -212.593833) (xy 36.071366 -212.646202) (xy 35.997482 -212.691949) (xy 35.919693 -212.730683)
			(xy 35.838661 -212.762075) (xy 35.755079 -212.785856) (xy 35.669659 -212.801824) (xy 35.58313 -212.809842)
			(xy 35.49623 -212.809842) (xy 35.409701 -212.801824) (xy 35.324281 -212.785856) (xy 35.240699 -212.762075)
			(xy 35.159667 -212.730683) (xy 35.081878 -212.691949) (xy 35.007994 -212.646202) (xy 34.938647 -212.593833)
			(xy 34.874427 -212.535289) (xy 34.815883 -212.471069) (xy 34.763514 -212.401722) (xy 34.717767 -212.327838)
			(xy 34.679033 -212.250049) (xy 34.647641 -212.169017) (xy 34.62386 -212.085435) (xy 34.607892 -212.000015)
			(xy 34.599874 -211.913486) (xy 31.399486 -211.913486) (xy 31.391468 -212.000015) (xy 31.3755 -212.085435)
			(xy 31.351719 -212.169017) (xy 31.320327 -212.250049) (xy 31.281593 -212.327838) (xy 31.235846 -212.401722)
			(xy 31.183477 -212.471069) (xy 31.124933 -212.535289) (xy 31.060713 -212.593833) (xy 30.991366 -212.646202)
			(xy 30.917482 -212.691949) (xy 30.839693 -212.730683) (xy 30.758661 -212.762075) (xy 30.675079 -212.785856)
			(xy 30.589659 -212.801824) (xy 30.50313 -212.809842) (xy 30.41623 -212.809842) (xy 30.329701 -212.801824)
			(xy 30.244281 -212.785856) (xy 30.160699 -212.762075) (xy 30.079667 -212.730683) (xy 30.001878 -212.691949)
			(xy 29.927994 -212.646202) (xy 29.858647 -212.593833) (xy 29.794427 -212.535289) (xy 29.735883 -212.471069)
			(xy 29.683514 -212.401722) (xy 29.637767 -212.327838) (xy 29.599033 -212.250049) (xy 29.567641 -212.169017)
			(xy 29.54386 -212.085435) (xy 29.527892 -212.000015) (xy 29.519874 -211.913486) (xy 28.461716 -211.913486)
			(xy 28.461716 -214.453486) (xy 29.519874 -214.453486) (xy 29.519874 -214.366586) (xy 29.527892 -214.280057)
			(xy 29.54386 -214.194637) (xy 29.567641 -214.111055) (xy 29.599033 -214.030023) (xy 29.637767 -213.952234)
			(xy 29.683514 -213.87835) (xy 29.735883 -213.809003) (xy 29.794427 -213.744783) (xy 29.858647 -213.686239)
			(xy 29.927994 -213.63387) (xy 30.001878 -213.588123) (xy 30.079667 -213.549389) (xy 30.160699 -213.517997)
			(xy 30.244281 -213.494216) (xy 30.329701 -213.478248) (xy 30.41623 -213.47023) (xy 30.50313 -213.47023)
			(xy 30.589659 -213.478248) (xy 30.675079 -213.494216) (xy 30.758661 -213.517997) (xy 30.839693 -213.549389)
			(xy 30.917482 -213.588123) (xy 30.991366 -213.63387) (xy 31.060713 -213.686239) (xy 31.124933 -213.744783)
			(xy 31.183477 -213.809003) (xy 31.235846 -213.87835) (xy 31.281593 -213.952234) (xy 31.320327 -214.030023)
			(xy 31.351719 -214.111055) (xy 31.3755 -214.194637) (xy 31.391468 -214.280057) (xy 31.399486 -214.366586)
			(xy 31.399988 -214.410036) (xy 31.399486 -214.453486) (xy 34.599874 -214.453486) (xy 34.599874 -214.366586)
			(xy 34.607892 -214.280057) (xy 34.62386 -214.194637) (xy 34.647641 -214.111055) (xy 34.679033 -214.030023)
			(xy 34.717767 -213.952234) (xy 34.763514 -213.87835) (xy 34.815883 -213.809003) (xy 34.874427 -213.744783)
			(xy 34.938647 -213.686239) (xy 35.007994 -213.63387) (xy 35.081878 -213.588123) (xy 35.159667 -213.549389)
			(xy 35.240699 -213.517997) (xy 35.324281 -213.494216) (xy 35.409701 -213.478248) (xy 35.49623 -213.47023)
			(xy 35.58313 -213.47023) (xy 35.669659 -213.478248) (xy 35.755079 -213.494216) (xy 35.838661 -213.517997)
			(xy 35.919693 -213.549389) (xy 35.997482 -213.588123) (xy 36.071366 -213.63387) (xy 36.140713 -213.686239)
			(xy 36.204933 -213.744783) (xy 36.263477 -213.809003) (xy 36.315846 -213.87835) (xy 36.361593 -213.952234)
			(xy 36.400327 -214.030023) (xy 36.431719 -214.111055) (xy 36.4555 -214.194637) (xy 36.471468 -214.280057)
			(xy 36.479486 -214.366586) (xy 36.479988 -214.410036) (xy 36.479486 -214.453486) (xy 36.471468 -214.540015)
			(xy 36.467843 -214.559407) (xy 39.057349 -214.559407) (xy 39.061236 -214.505045) (xy 39.072821 -214.45179)
			(xy 39.091868 -214.400725) (xy 39.117988 -214.352892) (xy 39.150651 -214.309263) (xy 39.189191 -214.270727)
			(xy 39.232823 -214.238068) (xy 39.28066 -214.211952) (xy 39.331726 -214.19291) (xy 39.384982 -214.181331)
			(xy 39.439345 -214.177449) (xy 39.493706 -214.181343) (xy 39.54696 -214.192936) (xy 39.598022 -214.211989)
			(xy 39.645852 -214.238117) (xy 39.667942 -214.25408) (xy 39.686954 -214.267676) (xy 39.728837 -214.288408)
			(xy 39.773805 -214.301134) (xy 39.820342 -214.305424) (xy 39.866879 -214.301134) (xy 39.911847 -214.288408)
			(xy 39.95373 -214.267676) (xy 39.972742 -214.25408) (xy 39.99484 -214.23814) (xy 40.042662 -214.212027)
			(xy 40.093714 -214.192987) (xy 40.146955 -214.181405) (xy 40.201303 -214.177518) (xy 40.255651 -214.181406)
			(xy 40.308892 -214.192988) (xy 40.359943 -214.21203) (xy 40.407765 -214.238143) (xy 40.451383 -214.270796)
			(xy 40.48991 -214.309325) (xy 40.522562 -214.352944) (xy 40.548674 -214.400766) (xy 40.567715 -214.451818)
			(xy 40.579296 -214.505059) (xy 40.583182 -214.559407) (xy 40.944201 -214.559407) (xy 40.948088 -214.505057)
			(xy 40.959669 -214.451813) (xy 40.97871 -214.40076) (xy 41.004823 -214.352936) (xy 41.037476 -214.309314)
			(xy 41.076005 -214.270784) (xy 41.119625 -214.23813) (xy 41.167448 -214.212015) (xy 41.218501 -214.192973)
			(xy 41.271745 -214.181389) (xy 41.326095 -214.177501) (xy 41.380445 -214.181388) (xy 41.433688 -214.19297)
			(xy 41.484742 -214.212011) (xy 41.532566 -214.238124) (xy 41.554654 -214.25408) (xy 41.573666 -214.267676)
			(xy 41.615549 -214.288408) (xy 41.660517 -214.301134) (xy 41.707054 -214.305424) (xy 41.753591 -214.301134)
			(xy 41.798559 -214.288408) (xy 41.840442 -214.267676) (xy 41.859454 -214.25408) (xy 41.881555 -214.238132)
			(xy 41.929382 -214.212006) (xy 41.980442 -214.192953) (xy 42.033694 -214.18136) (xy 42.088053 -214.177466)
			(xy 42.142413 -214.181347) (xy 42.195668 -214.192926) (xy 42.246732 -214.211967) (xy 42.294566 -214.238082)
			(xy 42.338197 -214.270739) (xy 42.376735 -214.309273) (xy 42.409397 -214.3529) (xy 42.435517 -214.400732)
			(xy 42.454563 -214.451794) (xy 42.466147 -214.505047) (xy 42.470034 -214.559407) (xy 43.185176 -214.559407)
			(xy 43.189063 -214.505051) (xy 43.200646 -214.451802) (xy 43.21969 -214.400743) (xy 43.245806 -214.352915)
			(xy 43.278464 -214.30929) (xy 43.316998 -214.270757) (xy 43.360624 -214.2381) (xy 43.408454 -214.211985)
			(xy 43.459513 -214.192943) (xy 43.512763 -214.181361) (xy 43.567119 -214.177476) (xy 43.621474 -214.181367)
			(xy 43.674723 -214.192953) (xy 43.72578 -214.212001) (xy 43.773607 -214.23812) (xy 43.795696 -214.25408)
			(xy 43.814708 -214.267676) (xy 43.856591 -214.288408) (xy 43.901559 -214.301134) (xy 43.948096 -214.305424)
			(xy 43.994633 -214.301134) (xy 44.039601 -214.288408) (xy 44.081484 -214.267676) (xy 44.100496 -214.25408)
			(xy 44.122596 -214.238136) (xy 44.170421 -214.212016) (xy 44.221476 -214.192969) (xy 44.274723 -214.181382)
			(xy 44.329077 -214.177491) (xy 44.383431 -214.181375) (xy 44.436679 -214.192956) (xy 44.487737 -214.211997)
			(xy 44.535566 -214.238111) (xy 44.57919 -214.270766) (xy 44.617723 -214.309298) (xy 44.65038 -214.352921)
			(xy 44.676496 -214.400748) (xy 44.69554 -214.451805) (xy 44.707123 -214.505053) (xy 44.711009 -214.559407)
			(xy 45.089186 -214.559407) (xy 45.093072 -214.505054) (xy 45.104655 -214.451806) (xy 45.123698 -214.40075)
			(xy 45.149813 -214.352923) (xy 45.182469 -214.309299) (xy 45.221001 -214.270767) (xy 45.264624 -214.238112)
			(xy 45.312452 -214.211997) (xy 45.363509 -214.192954) (xy 45.416756 -214.181372) (xy 45.471109 -214.177486)
			(xy 45.525463 -214.181375) (xy 45.57871 -214.19296) (xy 45.629766 -214.212004) (xy 45.677591 -214.238122)
			(xy 45.69968 -214.25408) (xy 45.718692 -214.267676) (xy 45.760575 -214.288408) (xy 45.805543 -214.301134)
			(xy 45.85208 -214.305424) (xy 45.898617 -214.301134) (xy 45.943585 -214.288408) (xy 45.985468 -214.267676)
			(xy 46.00448 -214.25408) (xy 46.02658 -214.238135) (xy 46.074406 -214.212012) (xy 46.125463 -214.192963)
			(xy 46.178712 -214.181374) (xy 46.233068 -214.177481) (xy 46.287424 -214.181364) (xy 46.340675 -214.192944)
			(xy 46.391735 -214.211985) (xy 46.439566 -214.2381) (xy 46.483193 -214.270756) (xy 46.521728 -214.309288)
			(xy 46.554387 -214.352913) (xy 46.580504 -214.400742) (xy 46.599549 -214.451801) (xy 46.611132 -214.505051)
			(xy 46.615019 -214.559407) (xy 46.61113 -214.613763) (xy 46.599544 -214.667013) (xy 46.580498 -214.718071)
			(xy 46.554379 -214.765899) (xy 46.521719 -214.809523) (xy 46.483182 -214.848054) (xy 46.439554 -214.880708)
			(xy 46.391722 -214.906821) (xy 46.340661 -214.92586) (xy 46.28741 -214.937438) (xy 46.233053 -214.941319)
			(xy 46.178698 -214.937424) (xy 46.125449 -214.925833) (xy 46.074393 -214.906782) (xy 46.026568 -214.880658)
			(xy 46.00448 -214.864696) (xy 45.985468 -214.8511) (xy 45.943585 -214.830368) (xy 45.898617 -214.817642)
			(xy 45.85208 -214.813352) (xy 45.805543 -214.817642) (xy 45.760575 -214.830368) (xy 45.718692 -214.8511)
			(xy 45.69968 -214.864696) (xy 45.677604 -214.88067) (xy 45.629779 -214.90679) (xy 45.578723 -214.925836)
			(xy 45.525477 -214.937423) (xy 45.471124 -214.941314) (xy 45.41677 -214.93743) (xy 45.363522 -214.92585)
			(xy 45.312465 -214.906809) (xy 45.264637 -214.880696) (xy 45.221012 -214.848042) (xy 45.182478 -214.809512)
			(xy 45.149821 -214.76589) (xy 45.123704 -214.718064) (xy 45.104659 -214.667007) (xy 45.093074 -214.613761)
			(xy 45.089186 -214.559407) (xy 44.711009 -214.559407) (xy 44.707121 -214.613761) (xy 44.695536 -214.667008)
			(xy 44.676491 -214.718065) (xy 44.650373 -214.765891) (xy 44.617714 -214.809513) (xy 44.579179 -214.848043)
			(xy 44.535553 -214.880697) (xy 44.487724 -214.906809) (xy 44.436666 -214.925848) (xy 44.383417 -214.937427)
			(xy 44.329062 -214.941309) (xy 44.274709 -214.937416) (xy 44.221462 -214.925827) (xy 44.170407 -214.906778)
			(xy 44.122583 -214.880656) (xy 44.100496 -214.864696) (xy 44.081484 -214.8511) (xy 44.039601 -214.830368)
			(xy 43.994633 -214.817642) (xy 43.948096 -214.813352) (xy 43.901559 -214.817642) (xy 43.856591 -214.830368)
			(xy 43.814708 -214.8511) (xy 43.795696 -214.864696) (xy 43.773619 -214.880672) (xy 43.725793 -214.906793)
			(xy 43.674736 -214.925843) (xy 43.621488 -214.937431) (xy 43.567133 -214.941324) (xy 43.512777 -214.937441)
			(xy 43.459527 -214.925861) (xy 43.408467 -214.906821) (xy 43.360636 -214.880707) (xy 43.317009 -214.848053)
			(xy 43.278474 -214.809521) (xy 43.245814 -214.765897) (xy 43.219696 -214.71807) (xy 43.20065 -214.667012)
			(xy 43.189065 -214.613763) (xy 43.185176 -214.559407) (xy 42.470034 -214.559407) (xy 42.466145 -214.613767)
			(xy 42.454559 -214.66702) (xy 42.435511 -214.718081) (xy 42.409389 -214.765912) (xy 42.376726 -214.809538)
			(xy 42.338186 -214.848071) (xy 42.294554 -214.880726) (xy 42.246719 -214.906839) (xy 42.195654 -214.925878)
			(xy 42.142399 -214.937455) (xy 42.088039 -214.941334) (xy 42.033679 -214.937437) (xy 41.980428 -214.925843)
			(xy 41.929369 -214.906788) (xy 41.881542 -214.88066) (xy 41.859454 -214.864696) (xy 41.840442 -214.8511)
			(xy 41.798559 -214.830368) (xy 41.753591 -214.817642) (xy 41.707054 -214.813352) (xy 41.660517 -214.817642)
			(xy 41.615549 -214.830368) (xy 41.573666 -214.8511) (xy 41.554654 -214.864696) (xy 41.532578 -214.880668)
			(xy 41.484755 -214.906783) (xy 41.433702 -214.925826) (xy 41.380459 -214.93741) (xy 41.326109 -214.941299)
			(xy 41.271759 -214.937413) (xy 41.218515 -214.925831) (xy 41.167461 -214.906791) (xy 41.119637 -214.880678)
			(xy 41.076016 -214.848025) (xy 41.037486 -214.809496) (xy 41.004831 -214.765877) (xy 40.978716 -214.718053)
			(xy 40.959673 -214.667) (xy 40.94809 -214.613757) (xy 40.944201 -214.559407) (xy 40.583182 -214.559407)
			(xy 40.579294 -214.613755) (xy 40.567711 -214.666996) (xy 40.548668 -214.718047) (xy 40.522555 -214.765868)
			(xy 40.489901 -214.809486) (xy 40.451372 -214.848013) (xy 40.407753 -214.880665) (xy 40.35993 -214.906776)
			(xy 40.308878 -214.925816) (xy 40.255637 -214.937396) (xy 40.201289 -214.941282) (xy 40.146941 -214.937393)
			(xy 40.0937 -214.925809) (xy 40.042649 -214.906767) (xy 39.994828 -214.880652) (xy 39.972742 -214.864696)
			(xy 39.95373 -214.8511) (xy 39.911847 -214.830368) (xy 39.866879 -214.817642) (xy 39.820342 -214.813352)
			(xy 39.773805 -214.817642) (xy 39.728837 -214.830368) (xy 39.686954 -214.8511) (xy 39.667942 -214.864696)
			(xy 39.645864 -214.880676) (xy 39.598035 -214.906805) (xy 39.546974 -214.92586) (xy 39.493721 -214.937454)
			(xy 39.439359 -214.941351) (xy 39.384997 -214.937471) (xy 39.33174 -214.925894) (xy 39.280673 -214.906854)
			(xy 39.232835 -214.88074) (xy 39.189202 -214.848083) (xy 39.150661 -214.809548) (xy 39.117996 -214.76592)
			(xy 39.091874 -214.718088) (xy 39.072825 -214.667024) (xy 39.061238 -214.613769) (xy 39.057349 -214.559407)
			(xy 36.467843 -214.559407) (xy 36.4555 -214.625435) (xy 36.431719 -214.709017) (xy 36.400327 -214.790049)
			(xy 36.361593 -214.867838) (xy 36.315846 -214.941722) (xy 36.263477 -215.011069) (xy 36.204933 -215.075289)
			(xy 36.140713 -215.133833) (xy 36.071366 -215.186202) (xy 36.003996 -215.227916) (xy 66.719956 -215.227916)
			(xy 66.724027 -215.172294) (xy 66.736153 -215.117857) (xy 66.756076 -215.065766) (xy 66.783372 -215.017131)
			(xy 66.817458 -214.972988) (xy 66.857607 -214.934279) (xy 66.902965 -214.901828) (xy 66.952565 -214.876327)
			(xy 67.005349 -214.85832) (xy 67.060192 -214.84819) (xy 67.115926 -214.846153) (xy 67.171363 -214.852253)
			(xy 67.22532 -214.866359) (xy 67.276649 -214.888171) (xy 67.324255 -214.917225) (xy 67.367123 -214.9529)
			(xy 67.40434 -214.994437) (xy 67.435113 -215.04095) (xy 67.458785 -215.091447) (xy 67.474853 -215.144854)
			(xy 67.482973 -215.20003) (xy 67.483482 -215.227916) (xy 67.482973 -215.255802) (xy 67.482068 -215.261952)
			(xy 67.864226 -215.261952) (xy 67.868297 -215.20633) (xy 67.880423 -215.151893) (xy 67.900346 -215.099802)
			(xy 67.927642 -215.051167) (xy 67.961728 -215.007024) (xy 68.001877 -214.968315) (xy 68.047235 -214.935864)
			(xy 68.096835 -214.910363) (xy 68.149619 -214.892356) (xy 68.204462 -214.882226) (xy 68.260196 -214.880189)
			(xy 68.315633 -214.886289) (xy 68.36959 -214.900395) (xy 68.420919 -214.922207) (xy 68.468525 -214.951261)
			(xy 68.511393 -214.986936) (xy 68.54861 -215.028473) (xy 68.579383 -215.074986) (xy 68.603055 -215.125483)
			(xy 68.619123 -215.17889) (xy 68.621964 -215.198198) (xy 69.037452 -215.198198) (xy 69.041523 -215.142576)
			(xy 69.053649 -215.088139) (xy 69.073572 -215.036048) (xy 69.100868 -214.987413) (xy 69.134954 -214.94327)
			(xy 69.175103 -214.904561) (xy 69.220461 -214.87211) (xy 69.270061 -214.846609) (xy 69.322845 -214.828602)
			(xy 69.377688 -214.818472) (xy 69.433422 -214.816435) (xy 69.488859 -214.822535) (xy 69.542816 -214.836641)
			(xy 69.594145 -214.858453) (xy 69.641751 -214.887507) (xy 69.684619 -214.923182) (xy 69.721836 -214.964719)
			(xy 69.752609 -215.011232) (xy 69.776281 -215.061729) (xy 69.792349 -215.115136) (xy 69.800469 -215.170312)
			(xy 69.800978 -215.198198) (xy 70.176134 -215.198198) (xy 70.180205 -215.142576) (xy 70.192331 -215.088139)
			(xy 70.212254 -215.036048) (xy 70.23955 -214.987413) (xy 70.273636 -214.94327) (xy 70.313785 -214.904561)
			(xy 70.359143 -214.87211) (xy 70.408743 -214.846609) (xy 70.461527 -214.828602) (xy 70.51637 -214.818472)
			(xy 70.572104 -214.816435) (xy 70.627541 -214.822535) (xy 70.681498 -214.836641) (xy 70.732827 -214.858453)
			(xy 70.780433 -214.887507) (xy 70.823301 -214.923182) (xy 70.860518 -214.964719) (xy 70.891291 -215.011232)
			(xy 70.914963 -215.061729) (xy 70.931031 -215.115136) (xy 70.939151 -215.170312) (xy 70.93966 -215.198198)
			(xy 70.939151 -215.226084) (xy 70.931031 -215.28126) (xy 70.914963 -215.334667) (xy 70.891291 -215.385164)
			(xy 70.860518 -215.431677) (xy 70.823301 -215.473214) (xy 70.780433 -215.508889) (xy 70.732827 -215.537943)
			(xy 70.681498 -215.559755) (xy 70.627541 -215.573861) (xy 70.572104 -215.579961) (xy 70.51637 -215.577924)
			(xy 70.461527 -215.567794) (xy 70.408743 -215.549787) (xy 70.359143 -215.524286) (xy 70.313785 -215.491835)
			(xy 70.273636 -215.453126) (xy 70.23955 -215.408983) (xy 70.212254 -215.360348) (xy 70.192331 -215.308257)
			(xy 70.180205 -215.25382) (xy 70.176134 -215.198198) (xy 69.800978 -215.198198) (xy 69.800469 -215.226084)
			(xy 69.792349 -215.28126) (xy 69.776281 -215.334667) (xy 69.752609 -215.385164) (xy 69.721836 -215.431677)
			(xy 69.684619 -215.473214) (xy 69.641751 -215.508889) (xy 69.594145 -215.537943) (xy 69.542816 -215.559755)
			(xy 69.488859 -215.573861) (xy 69.433422 -215.579961) (xy 69.377688 -215.577924) (xy 69.322845 -215.567794)
			(xy 69.270061 -215.549787) (xy 69.220461 -215.524286) (xy 69.175103 -215.491835) (xy 69.134954 -215.453126)
			(xy 69.100868 -215.408983) (xy 69.073572 -215.360348) (xy 69.053649 -215.308257) (xy 69.041523 -215.25382)
			(xy 69.037452 -215.198198) (xy 68.621964 -215.198198) (xy 68.627243 -215.234066) (xy 68.627752 -215.261952)
			(xy 68.627243 -215.289838) (xy 68.619123 -215.345014) (xy 68.603055 -215.398421) (xy 68.579383 -215.448918)
			(xy 68.54861 -215.495431) (xy 68.511393 -215.536968) (xy 68.468525 -215.572643) (xy 68.420919 -215.601697)
			(xy 68.36959 -215.623509) (xy 68.315633 -215.637615) (xy 68.260196 -215.643715) (xy 68.204462 -215.641678)
			(xy 68.149619 -215.631548) (xy 68.096835 -215.613541) (xy 68.047235 -215.58804) (xy 68.001877 -215.555589)
			(xy 67.961728 -215.51688) (xy 67.927642 -215.472737) (xy 67.900346 -215.424102) (xy 67.880423 -215.372011)
			(xy 67.868297 -215.317574) (xy 67.864226 -215.261952) (xy 67.482068 -215.261952) (xy 67.474853 -215.310978)
			(xy 67.458785 -215.364385) (xy 67.435113 -215.414882) (xy 67.40434 -215.461395) (xy 67.367123 -215.502932)
			(xy 67.324255 -215.538607) (xy 67.276649 -215.567661) (xy 67.22532 -215.589473) (xy 67.171363 -215.603579)
			(xy 67.115926 -215.609679) (xy 67.060192 -215.607642) (xy 67.005349 -215.597512) (xy 66.952565 -215.579505)
			(xy 66.902965 -215.554004) (xy 66.857607 -215.521553) (xy 66.817458 -215.482844) (xy 66.783372 -215.438701)
			(xy 66.756076 -215.390066) (xy 66.736153 -215.337975) (xy 66.724027 -215.283538) (xy 66.719956 -215.227916)
			(xy 36.003996 -215.227916) (xy 35.997482 -215.231949) (xy 35.919693 -215.270683) (xy 35.838661 -215.302075)
			(xy 35.755079 -215.325856) (xy 35.669659 -215.341824) (xy 35.58313 -215.349842) (xy 35.49623 -215.349842)
			(xy 35.409701 -215.341824) (xy 35.324281 -215.325856) (xy 35.240699 -215.302075) (xy 35.159667 -215.270683)
			(xy 35.081878 -215.231949) (xy 35.007994 -215.186202) (xy 34.938647 -215.133833) (xy 34.874427 -215.075289)
			(xy 34.815883 -215.011069) (xy 34.763514 -214.941722) (xy 34.717767 -214.867838) (xy 34.679033 -214.790049)
			(xy 34.647641 -214.709017) (xy 34.62386 -214.625435) (xy 34.607892 -214.540015) (xy 34.599874 -214.453486)
			(xy 31.399486 -214.453486) (xy 31.391468 -214.540015) (xy 31.3755 -214.625435) (xy 31.351719 -214.709017)
			(xy 31.320327 -214.790049) (xy 31.281593 -214.867838) (xy 31.235846 -214.941722) (xy 31.183477 -215.011069)
			(xy 31.124933 -215.075289) (xy 31.060713 -215.133833) (xy 30.991366 -215.186202) (xy 30.917482 -215.231949)
			(xy 30.839693 -215.270683) (xy 30.758661 -215.302075) (xy 30.675079 -215.325856) (xy 30.589659 -215.341824)
			(xy 30.50313 -215.349842) (xy 30.41623 -215.349842) (xy 30.329701 -215.341824) (xy 30.244281 -215.325856)
			(xy 30.160699 -215.302075) (xy 30.079667 -215.270683) (xy 30.001878 -215.231949) (xy 29.927994 -215.186202)
			(xy 29.858647 -215.133833) (xy 29.794427 -215.075289) (xy 29.735883 -215.011069) (xy 29.683514 -214.941722)
			(xy 29.637767 -214.867838) (xy 29.599033 -214.790049) (xy 29.567641 -214.709017) (xy 29.54386 -214.625435)
			(xy 29.527892 -214.540015) (xy 29.519874 -214.453486) (xy 28.461716 -214.453486) (xy 28.461716 -215.70696)
			(xy 28.863288 -215.70696) (xy 28.867359 -215.651338) (xy 28.879485 -215.596901) (xy 28.899408 -215.54481)
			(xy 28.926704 -215.496175) (xy 28.96079 -215.452032) (xy 29.000939 -215.413323) (xy 29.046297 -215.380872)
			(xy 29.095897 -215.355371) (xy 29.148681 -215.337364) (xy 29.203524 -215.327234) (xy 29.259258 -215.325197)
			(xy 29.314695 -215.331297) (xy 29.368652 -215.345403) (xy 29.419981 -215.367215) (xy 29.467587 -215.396269)
			(xy 29.510455 -215.431944) (xy 29.547672 -215.473481) (xy 29.578445 -215.519994) (xy 29.602117 -215.570491)
			(xy 29.618185 -215.623898) (xy 29.626305 -215.679074) (xy 29.626814 -215.70696) (xy 29.626305 -215.734846)
			(xy 29.618185 -215.790022) (xy 29.602117 -215.843429) (xy 29.578445 -215.893926) (xy 29.547672 -215.940439)
			(xy 29.510455 -215.981976) (xy 29.467587 -216.017651) (xy 29.419981 -216.046705) (xy 29.368652 -216.068517)
			(xy 29.314695 -216.082623) (xy 29.259258 -216.088723) (xy 29.203524 -216.086686) (xy 29.148681 -216.076556)
			(xy 29.095897 -216.058549) (xy 29.046297 -216.033048) (xy 29.000939 -216.000597) (xy 28.96079 -215.961888)
			(xy 28.926704 -215.917745) (xy 28.899408 -215.86911) (xy 28.879485 -215.817019) (xy 28.867359 -215.762582)
			(xy 28.863288 -215.70696) (xy 28.461716 -215.70696) (xy 28.461716 -216.993486) (xy 29.519874 -216.993486)
			(xy 29.519874 -216.906586) (xy 29.527892 -216.820057) (xy 29.54386 -216.734637) (xy 29.567641 -216.651055)
			(xy 29.599033 -216.570023) (xy 29.637767 -216.492234) (xy 29.683514 -216.41835) (xy 29.735883 -216.349003)
			(xy 29.794427 -216.284783) (xy 29.858647 -216.226239) (xy 29.927994 -216.17387) (xy 30.001878 -216.128123)
			(xy 30.079667 -216.089389) (xy 30.160699 -216.057997) (xy 30.244281 -216.034216) (xy 30.329701 -216.018248)
			(xy 30.41623 -216.01023) (xy 30.50313 -216.01023) (xy 30.589659 -216.018248) (xy 30.675079 -216.034216)
			(xy 30.758661 -216.057997) (xy 30.839693 -216.089389) (xy 30.917482 -216.128123) (xy 30.991366 -216.17387)
			(xy 31.060713 -216.226239) (xy 31.124933 -216.284783) (xy 31.183477 -216.349003) (xy 31.235846 -216.41835)
			(xy 31.281593 -216.492234) (xy 31.320327 -216.570023) (xy 31.351719 -216.651055) (xy 31.3755 -216.734637)
			(xy 31.391468 -216.820057) (xy 31.399486 -216.906586) (xy 31.399988 -216.950036) (xy 31.399486 -216.993486)
			(xy 34.599874 -216.993486) (xy 34.599874 -216.906586) (xy 34.607892 -216.820057) (xy 34.62386 -216.734637)
			(xy 34.647641 -216.651055) (xy 34.679033 -216.570023) (xy 34.717767 -216.492234) (xy 34.763514 -216.41835)
			(xy 34.815883 -216.349003) (xy 34.874427 -216.284783) (xy 34.938647 -216.226239) (xy 35.007994 -216.17387)
			(xy 35.081878 -216.128123) (xy 35.159667 -216.089389) (xy 35.240699 -216.057997) (xy 35.324281 -216.034216)
			(xy 35.409701 -216.018248) (xy 35.49623 -216.01023) (xy 35.58313 -216.01023) (xy 35.669659 -216.018248)
			(xy 35.755079 -216.034216) (xy 35.838661 -216.057997) (xy 35.919693 -216.089389) (xy 35.997482 -216.128123)
			(xy 36.071366 -216.17387) (xy 36.140713 -216.226239) (xy 36.204933 -216.284783) (xy 36.263477 -216.349003)
			(xy 36.315846 -216.41835) (xy 36.335377 -216.449894) (xy 39.057366 -216.449894) (xy 39.061255 -216.395535)
			(xy 39.072842 -216.342282) (xy 39.091889 -216.291221) (xy 39.11801 -216.24339) (xy 39.150673 -216.199764)
			(xy 39.189213 -216.161231) (xy 39.232844 -216.128576) (xy 39.280679 -216.102463) (xy 39.331743 -216.083424)
			(xy 39.384998 -216.071846) (xy 39.439358 -216.067966) (xy 39.493717 -216.071863) (xy 39.546968 -216.083456)
			(xy 39.598027 -216.102511) (xy 39.645854 -216.128638) (xy 39.667942 -216.144602) (xy 39.686954 -216.158198)
			(xy 39.728837 -216.17893) (xy 39.773805 -216.191656) (xy 39.820342 -216.195946) (xy 39.866879 -216.191656)
			(xy 39.911847 -216.17893) (xy 39.95373 -216.158198) (xy 39.972742 -216.144602) (xy 39.99482 -216.128632)
			(xy 40.042643 -216.102517) (xy 40.093696 -216.083473) (xy 40.14694 -216.071889) (xy 40.20129 -216.068001)
			(xy 40.25564 -216.071886) (xy 40.308884 -216.083468) (xy 40.359939 -216.102508) (xy 40.407763 -216.128621)
			(xy 40.451385 -216.161274) (xy 40.489915 -216.199803) (xy 40.52257 -216.243423) (xy 40.548685 -216.291247)
			(xy 40.567728 -216.3423) (xy 40.579311 -216.395544) (xy 40.583199 -216.449894) (xy 40.944219 -216.449894)
			(xy 40.948107 -216.395547) (xy 40.95969 -216.342306) (xy 40.978732 -216.291255) (xy 41.004845 -216.243434)
			(xy 41.037498 -216.199816) (xy 41.076026 -216.161289) (xy 41.119646 -216.128637) (xy 41.167468 -216.102526)
			(xy 41.218519 -216.083486) (xy 41.27176 -216.071905) (xy 41.326108 -216.068019) (xy 41.380455 -216.071907)
			(xy 41.433696 -216.08349) (xy 41.484747 -216.102532) (xy 41.532568 -216.128646) (xy 41.554654 -216.144602)
			(xy 41.573666 -216.158198) (xy 41.615549 -216.17893) (xy 41.660517 -216.191656) (xy 41.707054 -216.195946)
			(xy 41.753591 -216.191656) (xy 41.798559 -216.17893) (xy 41.840442 -216.158198) (xy 41.859454 -216.144602)
			(xy 41.881534 -216.128625) (xy 41.929363 -216.102495) (xy 41.980424 -216.083439) (xy 42.033678 -216.071845)
			(xy 42.08804 -216.067948) (xy 42.142403 -216.071828) (xy 42.19566 -216.083405) (xy 42.246727 -216.102445)
			(xy 42.294565 -216.12856) (xy 42.338199 -216.161217) (xy 42.37674 -216.199751) (xy 42.409405 -216.243379)
			(xy 42.435527 -216.291212) (xy 42.454576 -216.342276) (xy 42.466163 -216.395532) (xy 42.470052 -216.449894)
			(xy 43.185194 -216.449894) (xy 43.189082 -216.395541) (xy 43.200667 -216.342294) (xy 43.219711 -216.291239)
			(xy 43.245828 -216.243413) (xy 43.278486 -216.199791) (xy 43.31702 -216.161261) (xy 43.360645 -216.128608)
			(xy 43.408473 -216.102496) (xy 43.459531 -216.083456) (xy 43.512778 -216.071877) (xy 43.567132 -216.067994)
			(xy 43.621485 -216.071886) (xy 43.67473 -216.083474) (xy 43.725785 -216.102522) (xy 43.773609 -216.128642)
			(xy 43.795696 -216.144602) (xy 43.814708 -216.158198) (xy 43.856591 -216.17893) (xy 43.901559 -216.191656)
			(xy 43.948096 -216.195946) (xy 43.994633 -216.191656) (xy 44.039601 -216.17893) (xy 44.081484 -216.158198)
			(xy 44.100496 -216.144602) (xy 44.122575 -216.128628) (xy 44.170401 -216.102506) (xy 44.221459 -216.083456)
			(xy 44.274707 -216.071866) (xy 44.329064 -216.067973) (xy 44.383421 -216.071856) (xy 44.436672 -216.083435)
			(xy 44.487733 -216.102475) (xy 44.535564 -216.128589) (xy 44.579192 -216.161244) (xy 44.617728 -216.199776)
			(xy 44.650388 -216.2434) (xy 44.676507 -216.291229) (xy 44.695553 -216.342288) (xy 44.707138 -216.395537)
			(xy 44.711027 -216.449894) (xy 45.089203 -216.449894) (xy 45.093092 -216.395543) (xy 45.104676 -216.342299)
			(xy 45.123719 -216.291245) (xy 45.149835 -216.243421) (xy 45.182491 -216.199801) (xy 45.221022 -216.161272)
			(xy 45.264645 -216.128619) (xy 45.312471 -216.102507) (xy 45.363526 -216.083467) (xy 45.416771 -216.071888)
			(xy 45.471123 -216.068003) (xy 45.525473 -216.071894) (xy 45.578717 -216.08348) (xy 45.62977 -216.102526)
			(xy 45.677593 -216.128644) (xy 45.69968 -216.144602) (xy 45.718692 -216.158198) (xy 45.760575 -216.17893)
			(xy 45.805543 -216.191656) (xy 45.85208 -216.195946) (xy 45.898617 -216.191656) (xy 45.943585 -216.17893)
			(xy 45.985468 -216.158198) (xy 46.00448 -216.144602) (xy 46.026559 -216.128627) (xy 46.074387 -216.102502)
			(xy 46.125446 -216.083449) (xy 46.178696 -216.071858) (xy 46.233055 -216.067963) (xy 46.287414 -216.071845)
			(xy 46.340667 -216.083424) (xy 46.391731 -216.102464) (xy 46.439564 -216.128578) (xy 46.483194 -216.161234)
			(xy 46.521733 -216.199767) (xy 46.554394 -216.243392) (xy 46.580515 -216.291223) (xy 46.599562 -216.342283)
			(xy 46.611148 -216.395535) (xy 46.615037 -216.449894) (xy 46.611149 -216.504253) (xy 46.599565 -216.557505)
			(xy 46.58052 -216.608566) (xy 46.554401 -216.656397) (xy 46.521741 -216.700024) (xy 46.483204 -216.738559)
			(xy 46.439574 -216.771216) (xy 46.391742 -216.797331) (xy 46.340679 -216.816373) (xy 46.287426 -216.827953)
			(xy 46.233067 -216.831837) (xy 46.178708 -216.827944) (xy 46.125457 -216.816354) (xy 46.074398 -216.797303)
			(xy 46.026569 -216.77118) (xy 46.00448 -216.755218) (xy 45.985468 -216.741622) (xy 45.943585 -216.72089)
			(xy 45.898617 -216.708164) (xy 45.85208 -216.703874) (xy 45.805543 -216.708164) (xy 45.760575 -216.72089)
			(xy 45.718692 -216.741622) (xy 45.69968 -216.755218) (xy 45.677583 -216.771163) (xy 45.629759 -216.797279)
			(xy 45.578706 -216.816323) (xy 45.525462 -216.827908) (xy 45.471111 -216.831797) (xy 45.41676 -216.827911)
			(xy 45.363515 -216.816329) (xy 45.31246 -216.797288) (xy 45.264635 -216.771174) (xy 45.221013 -216.73852)
			(xy 45.182483 -216.69999) (xy 45.149828 -216.656369) (xy 45.123714 -216.608544) (xy 45.104672 -216.55749)
			(xy 45.09309 -216.504245) (xy 45.089203 -216.449894) (xy 44.711027 -216.449894) (xy 44.70714 -216.504251)
			(xy 44.695556 -216.557501) (xy 44.676512 -216.60856) (xy 44.650395 -216.65639) (xy 44.617736 -216.700015)
			(xy 44.579201 -216.738548) (xy 44.535574 -216.771205) (xy 44.487744 -216.79732) (xy 44.436683 -216.816361)
			(xy 44.383433 -216.827943) (xy 44.329076 -216.831827) (xy 44.274719 -216.827936) (xy 44.22147 -216.816348)
			(xy 44.170412 -216.797299) (xy 44.122585 -216.771178) (xy 44.100496 -216.755218) (xy 44.081484 -216.741622)
			(xy 44.039601 -216.72089) (xy 43.994633 -216.708164) (xy 43.948096 -216.703874) (xy 43.901559 -216.708164)
			(xy 43.856591 -216.72089) (xy 43.814708 -216.741622) (xy 43.795696 -216.755218) (xy 43.773599 -216.771164)
			(xy 43.725774 -216.797283) (xy 43.674719 -216.816329) (xy 43.621473 -216.827916) (xy 43.56712 -216.831806)
			(xy 43.512766 -216.827921) (xy 43.459519 -216.81634) (xy 43.408462 -216.797299) (xy 43.360635 -216.771185)
			(xy 43.317011 -216.738531) (xy 43.278478 -216.7) (xy 43.245822 -216.656377) (xy 43.219706 -216.60855)
			(xy 43.200663 -216.557494) (xy 43.189081 -216.504247) (xy 43.185194 -216.449894) (xy 42.470052 -216.449894)
			(xy 42.466165 -216.504256) (xy 42.454579 -216.557512) (xy 42.435532 -216.608577) (xy 42.409411 -216.65641)
			(xy 42.376748 -216.70004) (xy 42.338208 -216.738576) (xy 42.294575 -216.771234) (xy 42.246738 -216.79735)
			(xy 42.195672 -216.816391) (xy 42.142415 -216.827971) (xy 42.088052 -216.831852) (xy 42.03369 -216.827957)
			(xy 41.980436 -216.816364) (xy 41.929374 -216.79731) (xy 41.881544 -216.771182) (xy 41.859454 -216.755218)
			(xy 41.840442 -216.741622) (xy 41.798559 -216.72089) (xy 41.753591 -216.708164) (xy 41.707054 -216.703874)
			(xy 41.660517 -216.708164) (xy 41.615549 -216.72089) (xy 41.573666 -216.741622) (xy 41.554654 -216.755218)
			(xy 41.532558 -216.771161) (xy 41.484736 -216.797273) (xy 41.433685 -216.816313) (xy 41.380443 -216.827895)
			(xy 41.326096 -216.831781) (xy 41.271748 -216.827893) (xy 41.218507 -216.816311) (xy 41.167457 -216.797269)
			(xy 41.119636 -216.771156) (xy 41.076017 -216.738503) (xy 41.03749 -216.699975) (xy 41.004838 -216.656356)
			(xy 40.978727 -216.608534) (xy 40.959686 -216.557483) (xy 40.948105 -216.504242) (xy 40.944219 -216.449894)
			(xy 40.583199 -216.449894) (xy 40.579313 -216.504244) (xy 40.567731 -216.557488) (xy 40.54869 -216.608542)
			(xy 40.522577 -216.656367) (xy 40.489923 -216.699988) (xy 40.451394 -216.738518) (xy 40.407773 -216.771172)
			(xy 40.359949 -216.797287) (xy 40.308896 -216.816329) (xy 40.255652 -216.827912) (xy 40.201302 -216.831799)
			(xy 40.146952 -216.827912) (xy 40.093708 -216.81633) (xy 40.042654 -216.797288) (xy 39.99483 -216.771174)
			(xy 39.972742 -216.755218) (xy 39.95373 -216.741622) (xy 39.911847 -216.72089) (xy 39.866879 -216.708164)
			(xy 39.820342 -216.703874) (xy 39.773805 -216.708164) (xy 39.728837 -216.72089) (xy 39.686954 -216.741622)
			(xy 39.667942 -216.755218) (xy 39.645843 -216.771168) (xy 39.598016 -216.797294) (xy 39.546956 -216.816347)
			(xy 39.493705 -216.827939) (xy 39.439346 -216.831834) (xy 39.384986 -216.827952) (xy 39.331732 -216.816373)
			(xy 39.280668 -216.797332) (xy 39.232834 -216.771218) (xy 39.189203 -216.738561) (xy 39.150665 -216.700027)
			(xy 39.118004 -216.6564) (xy 39.091884 -216.608568) (xy 39.072838 -216.557506) (xy 39.061254 -216.504254)
			(xy 39.057366 -216.449894) (xy 36.335377 -216.449894) (xy 36.361593 -216.492234) (xy 36.400327 -216.570023)
			(xy 36.431719 -216.651055) (xy 36.4555 -216.734637) (xy 36.471468 -216.820057) (xy 36.479486 -216.906586)
			(xy 36.479988 -216.950036) (xy 36.479486 -216.993486) (xy 36.471468 -217.080015) (xy 36.4555 -217.165435)
			(xy 36.431719 -217.249017) (xy 36.400327 -217.330049) (xy 36.361593 -217.407838) (xy 36.315846 -217.481722)
			(xy 36.282007 -217.526531) (xy 47.842414 -217.526531) (xy 47.842414 -217.445421) (xy 47.850364 -217.364702)
			(xy 47.866187 -217.285151) (xy 47.889732 -217.207535) (xy 47.920771 -217.132599) (xy 47.959006 -217.061067)
			(xy 48.004068 -216.993627) (xy 48.055523 -216.930928) (xy 48.112876 -216.873575) (xy 48.175575 -216.82212)
			(xy 48.243015 -216.777058) (xy 48.314547 -216.738823) (xy 48.389483 -216.707784) (xy 48.467099 -216.684239)
			(xy 48.54665 -216.668416) (xy 48.627369 -216.660466) (xy 48.708479 -216.660466) (xy 48.789198 -216.668416)
			(xy 48.868749 -216.684239) (xy 48.946365 -216.707784) (xy 49.021301 -216.738823) (xy 49.092833 -216.777058)
			(xy 49.160273 -216.82212) (xy 49.222972 -216.873575) (xy 49.280325 -216.930928) (xy 49.33178 -216.993627)
			(xy 49.376842 -217.061067) (xy 49.415077 -217.132599) (xy 49.446116 -217.207535) (xy 49.469661 -217.285151)
			(xy 49.485484 -217.364702) (xy 49.493434 -217.445421) (xy 49.493932 -217.485976) (xy 49.493434 -217.526531)
			(xy 51.342534 -217.526531) (xy 51.342534 -217.445421) (xy 51.350484 -217.364702) (xy 51.366307 -217.285151)
			(xy 51.389852 -217.207535) (xy 51.420891 -217.132599) (xy 51.459126 -217.061067) (xy 51.504188 -216.993627)
			(xy 51.555643 -216.930928) (xy 51.612996 -216.873575) (xy 51.675695 -216.82212) (xy 51.743135 -216.777058)
			(xy 51.814667 -216.738823) (xy 51.889603 -216.707784) (xy 51.967219 -216.684239) (xy 52.04677 -216.668416)
			(xy 52.127489 -216.660466) (xy 52.208599 -216.660466) (xy 52.289318 -216.668416) (xy 52.368869 -216.684239)
			(xy 52.446485 -216.707784) (xy 52.521421 -216.738823) (xy 52.592953 -216.777058) (xy 52.660393 -216.82212)
			(xy 52.723092 -216.873575) (xy 52.780445 -216.930928) (xy 52.8319 -216.993627) (xy 52.876962 -217.061067)
			(xy 52.915197 -217.132599) (xy 52.946236 -217.207535) (xy 52.969781 -217.285151) (xy 52.985604 -217.364702)
			(xy 52.993554 -217.445421) (xy 52.994052 -217.485976) (xy 52.993554 -217.526531) (xy 52.985604 -217.60725)
			(xy 52.969781 -217.686801) (xy 52.946236 -217.764417) (xy 52.915197 -217.839353) (xy 52.876962 -217.910885)
			(xy 52.8319 -217.978325) (xy 52.780445 -218.041024) (xy 52.723092 -218.098377) (xy 52.660393 -218.149832)
			(xy 52.592953 -218.194894) (xy 52.521421 -218.233129) (xy 52.446485 -218.264168) (xy 52.368869 -218.287713)
			(xy 52.289318 -218.303536) (xy 52.208599 -218.311486) (xy 52.127489 -218.311486) (xy 52.04677 -218.303536)
			(xy 51.967219 -218.287713) (xy 51.889603 -218.264168) (xy 51.814667 -218.233129) (xy 51.743135 -218.194894)
			(xy 51.675695 -218.149832) (xy 51.612996 -218.098377) (xy 51.555643 -218.041024) (xy 51.504188 -217.978325)
			(xy 51.459126 -217.910885) (xy 51.420891 -217.839353) (xy 51.389852 -217.764417) (xy 51.366307 -217.686801)
			(xy 51.350484 -217.60725) (xy 51.342534 -217.526531) (xy 49.493434 -217.526531) (xy 49.485484 -217.60725)
			(xy 49.469661 -217.686801) (xy 49.446116 -217.764417) (xy 49.415077 -217.839353) (xy 49.376842 -217.910885)
			(xy 49.33178 -217.978325) (xy 49.280325 -218.041024) (xy 49.222972 -218.098377) (xy 49.160273 -218.149832)
			(xy 49.092833 -218.194894) (xy 49.021301 -218.233129) (xy 48.946365 -218.264168) (xy 48.868749 -218.287713)
			(xy 48.789198 -218.303536) (xy 48.708479 -218.311486) (xy 48.627369 -218.311486) (xy 48.54665 -218.303536)
			(xy 48.467099 -218.287713) (xy 48.389483 -218.264168) (xy 48.314547 -218.233129) (xy 48.243015 -218.194894)
			(xy 48.175575 -218.149832) (xy 48.112876 -218.098377) (xy 48.055523 -218.041024) (xy 48.004068 -217.978325)
			(xy 47.959006 -217.910885) (xy 47.920771 -217.839353) (xy 47.889732 -217.764417) (xy 47.866187 -217.686801)
			(xy 47.850364 -217.60725) (xy 47.842414 -217.526531) (xy 36.282007 -217.526531) (xy 36.263477 -217.551069)
			(xy 36.204933 -217.615289) (xy 36.140713 -217.673833) (xy 36.071366 -217.726202) (xy 35.997482 -217.771949)
			(xy 35.919693 -217.810683) (xy 35.838661 -217.842075) (xy 35.755079 -217.865856) (xy 35.669659 -217.881824)
			(xy 35.58313 -217.889842) (xy 35.49623 -217.889842) (xy 35.409701 -217.881824) (xy 35.324281 -217.865856)
			(xy 35.240699 -217.842075) (xy 35.159667 -217.810683) (xy 35.081878 -217.771949) (xy 35.007994 -217.726202)
			(xy 34.938647 -217.673833) (xy 34.874427 -217.615289) (xy 34.815883 -217.551069) (xy 34.763514 -217.481722)
			(xy 34.717767 -217.407838) (xy 34.679033 -217.330049) (xy 34.647641 -217.249017) (xy 34.62386 -217.165435)
			(xy 34.607892 -217.080015) (xy 34.599874 -216.993486) (xy 31.399486 -216.993486) (xy 31.391468 -217.080015)
			(xy 31.3755 -217.165435) (xy 31.351719 -217.249017) (xy 31.320327 -217.330049) (xy 31.281593 -217.407838)
			(xy 31.235846 -217.481722) (xy 31.183477 -217.551069) (xy 31.124933 -217.615289) (xy 31.060713 -217.673833)
			(xy 30.991366 -217.726202) (xy 30.917482 -217.771949) (xy 30.839693 -217.810683) (xy 30.758661 -217.842075)
			(xy 30.675079 -217.865856) (xy 30.589659 -217.881824) (xy 30.50313 -217.889842) (xy 30.41623 -217.889842)
			(xy 30.329701 -217.881824) (xy 30.244281 -217.865856) (xy 30.160699 -217.842075) (xy 30.079667 -217.810683)
			(xy 30.001878 -217.771949) (xy 29.927994 -217.726202) (xy 29.858647 -217.673833) (xy 29.794427 -217.615289)
			(xy 29.735883 -217.551069) (xy 29.683514 -217.481722) (xy 29.637767 -217.407838) (xy 29.599033 -217.330049)
			(xy 29.567641 -217.249017) (xy 29.54386 -217.165435) (xy 29.527892 -217.080015) (xy 29.519874 -216.993486)
			(xy 28.461716 -216.993486) (xy 28.461716 -218.491128) (xy 39.057321 -218.491128) (xy 39.061206 -218.436761)
			(xy 39.072789 -218.383502) (xy 39.091835 -218.332433) (xy 39.117955 -218.284594) (xy 39.150617 -218.24096)
			(xy 39.189158 -218.202419) (xy 39.232791 -218.169756) (xy 39.28063 -218.143636) (xy 39.331698 -218.12459)
			(xy 39.384958 -218.113007) (xy 39.439324 -218.109121) (xy 39.49369 -218.113014) (xy 39.546948 -218.124604)
			(xy 39.598015 -218.143656) (xy 39.64585 -218.169783) (xy 39.667942 -218.185746) (xy 39.686954 -218.199342)
			(xy 39.728837 -218.220074) (xy 39.773805 -218.2328) (xy 39.820342 -218.23709) (xy 39.866879 -218.2328)
			(xy 39.911847 -218.220074) (xy 39.95373 -218.199342) (xy 39.972742 -218.185746) (xy 39.994872 -218.169852)
			(xy 40.042692 -218.143744) (xy 40.093741 -218.124707) (xy 40.146979 -218.113129) (xy 40.201323 -218.109245)
			(xy 40.255667 -218.113136) (xy 40.308904 -218.12472) (xy 40.35995 -218.143763) (xy 40.407767 -218.169877)
			(xy 40.451381 -218.20253) (xy 40.489903 -218.241058) (xy 40.522551 -218.284676) (xy 40.548658 -218.332496)
			(xy 40.567694 -218.383545) (xy 40.579272 -218.436783) (xy 40.583155 -218.491128) (xy 40.944174 -218.491128)
			(xy 40.948058 -218.436773) (xy 40.959637 -218.383525) (xy 40.978677 -218.332467) (xy 41.004789 -218.284638)
			(xy 41.037442 -218.241012) (xy 41.075972 -218.202477) (xy 41.119593 -218.169818) (xy 41.167418 -218.143699)
			(xy 41.218474 -218.124652) (xy 41.271721 -218.113065) (xy 41.326074 -218.109174) (xy 41.380428 -218.113058)
			(xy 41.433677 -218.124638) (xy 41.484735 -218.143678) (xy 41.532564 -218.16979) (xy 41.554654 -218.185746)
			(xy 41.573666 -218.199342) (xy 41.615549 -218.220074) (xy 41.660517 -218.2328) (xy 41.707054 -218.23709)
			(xy 41.753591 -218.2328) (xy 41.798559 -218.220074) (xy 41.840442 -218.199342) (xy 41.859454 -218.185746)
			(xy 41.881586 -218.169844) (xy 41.929412 -218.143722) (xy 41.980469 -218.124673) (xy 42.033718 -218.113084)
			(xy 42.088073 -218.109193) (xy 42.14243 -218.113077) (xy 42.19568 -218.124658) (xy 42.246739 -218.1437)
			(xy 42.294569 -218.169815) (xy 42.338195 -218.202472) (xy 42.376728 -218.241006) (xy 42.409385 -218.284632)
			(xy 42.4355 -218.332462) (xy 42.454542 -218.383521) (xy 42.466123 -218.436771) (xy 42.470007 -218.491128)
			(xy 43.185149 -218.491128) (xy 43.189033 -218.436768) (xy 43.200614 -218.383514) (xy 43.219657 -218.332451)
			(xy 43.245773 -218.284617) (xy 43.27843 -218.240987) (xy 43.316965 -218.20245) (xy 43.360592 -218.169788)
			(xy 43.408424 -218.143669) (xy 43.459486 -218.124623) (xy 43.512739 -218.113037) (xy 43.567098 -218.109149)
			(xy 43.621458 -218.113037) (xy 43.674711 -218.124622) (xy 43.725773 -218.143667) (xy 43.773605 -218.169786)
			(xy 43.795696 -218.185746) (xy 43.814708 -218.199342) (xy 43.856591 -218.220074) (xy 43.901559 -218.2328)
			(xy 43.948096 -218.23709) (xy 43.994633 -218.2328) (xy 44.039601 -218.220074) (xy 44.081484 -218.199342)
			(xy 44.100496 -218.185746) (xy 44.122627 -218.169848) (xy 44.17045 -218.143732) (xy 44.221503 -218.124689)
			(xy 44.274747 -218.113106) (xy 44.329097 -218.109218) (xy 44.383448 -218.113105) (xy 44.436691 -218.124688)
			(xy 44.487745 -218.14373) (xy 44.535568 -218.169845) (xy 44.579188 -218.2025) (xy 44.617716 -218.241031)
			(xy 44.650369 -218.284653) (xy 44.67648 -218.332478) (xy 44.695519 -218.383533) (xy 44.707099 -218.436777)
			(xy 44.710982 -218.491128) (xy 45.089159 -218.491128) (xy 45.093043 -218.43677) (xy 45.104623 -218.383518)
			(xy 45.123664 -218.332457) (xy 45.149779 -218.284625) (xy 45.182435 -218.240997) (xy 45.220968 -218.20246)
			(xy 45.264593 -218.1698) (xy 45.312422 -218.14368) (xy 45.363481 -218.124634) (xy 45.416732 -218.113048)
			(xy 45.471089 -218.109159) (xy 45.525447 -218.113045) (xy 45.578698 -218.124628) (xy 45.629758 -218.143671)
			(xy 45.677589 -218.169788) (xy 45.69968 -218.185746) (xy 45.718692 -218.199342) (xy 45.760575 -218.220074)
			(xy 45.805543 -218.2328) (xy 45.85208 -218.23709) (xy 45.898617 -218.2328) (xy 45.943585 -218.220074)
			(xy 45.985468 -218.199342) (xy 46.00448 -218.185746) (xy 46.026612 -218.169846) (xy 46.074436 -218.143728)
			(xy 46.12549 -218.124683) (xy 46.178736 -218.113098) (xy 46.233088 -218.109208) (xy 46.287441 -218.113094)
			(xy 46.340687 -218.124676) (xy 46.391743 -218.143719) (xy 46.439568 -218.169834) (xy 46.48319 -218.20249)
			(xy 46.521721 -218.241021) (xy 46.554375 -218.284645) (xy 46.580488 -218.332472) (xy 46.599528 -218.383528)
			(xy 46.611108 -218.436775) (xy 46.614992 -218.491128) (xy 46.6111 -218.54548) (xy 46.599513 -218.598725)
			(xy 46.580465 -218.649778) (xy 46.554345 -218.697602) (xy 46.521685 -218.74122) (xy 46.483149 -218.779747)
			(xy 46.439522 -218.812396) (xy 46.391692 -218.838504) (xy 46.340634 -218.857539) (xy 46.287386 -218.869114)
			(xy 46.233033 -218.872992) (xy 46.178681 -218.869095) (xy 46.125437 -218.857501) (xy 46.074386 -218.838449)
			(xy 46.026565 -218.812324) (xy 46.00448 -218.796362) (xy 45.985468 -218.782766) (xy 45.943585 -218.762034)
			(xy 45.898617 -218.749308) (xy 45.85208 -218.745018) (xy 45.805543 -218.749308) (xy 45.760575 -218.762034)
			(xy 45.718692 -218.782766) (xy 45.69968 -218.796362) (xy 45.677635 -218.812382) (xy 45.629809 -218.838506)
			(xy 45.578751 -218.857557) (xy 45.525501 -218.869147) (xy 45.471144 -218.873041) (xy 45.416786 -218.86916)
			(xy 45.363534 -218.857582) (xy 45.312472 -218.838543) (xy 45.264639 -218.81243) (xy 45.221009 -218.779776)
			(xy 45.182471 -218.741245) (xy 45.149809 -218.697621) (xy 45.123687 -218.649793) (xy 45.104639 -218.598735)
			(xy 45.09305 -218.545485) (xy 45.089159 -218.491128) (xy 44.710982 -218.491128) (xy 44.707091 -218.545478)
			(xy 44.695504 -218.59872) (xy 44.676457 -218.649772) (xy 44.650339 -218.697594) (xy 44.61768 -218.741211)
			(xy 44.579146 -218.779736) (xy 44.535522 -218.812385) (xy 44.487694 -218.838493) (xy 44.436638 -218.857528)
			(xy 44.383393 -218.869103) (xy 44.329042 -218.872982) (xy 44.274692 -218.869086) (xy 44.221451 -218.857495)
			(xy 44.1704 -218.838445) (xy 44.122581 -218.812322) (xy 44.100496 -218.796362) (xy 44.081484 -218.782766)
			(xy 44.039601 -218.762034) (xy 43.994633 -218.749308) (xy 43.948096 -218.745018) (xy 43.901559 -218.749308)
			(xy 43.856591 -218.762034) (xy 43.814708 -218.782766) (xy 43.795696 -218.796362) (xy 43.773651 -218.812384)
			(xy 43.725823 -218.83851) (xy 43.674764 -218.857563) (xy 43.621512 -218.869155) (xy 43.567153 -218.873051)
			(xy 43.512793 -218.86917) (xy 43.459539 -218.857593) (xy 43.408474 -218.838554) (xy 43.360639 -218.812441)
			(xy 43.317007 -218.779787) (xy 43.278466 -218.741254) (xy 43.245802 -218.697629) (xy 43.21968 -218.6498)
			(xy 43.20063 -218.598739) (xy 43.189041 -218.545487) (xy 43.185149 -218.491128) (xy 42.470007 -218.491128)
			(xy 42.466115 -218.545483) (xy 42.454527 -218.598732) (xy 42.435477 -218.649789) (xy 42.409355 -218.697614)
			(xy 42.376692 -218.741236) (xy 42.338153 -218.779764) (xy 42.294522 -218.812414) (xy 42.246689 -218.838523)
			(xy 42.195627 -218.857558) (xy 42.142375 -218.869131) (xy 42.088018 -218.873007) (xy 42.033663 -218.869108)
			(xy 41.980416 -218.857512) (xy 41.929362 -218.838455) (xy 41.88154 -218.812326) (xy 41.859454 -218.796362)
			(xy 41.840442 -218.782766) (xy 41.798559 -218.762034) (xy 41.753591 -218.749308) (xy 41.707054 -218.745018)
			(xy 41.660517 -218.749308) (xy 41.615549 -218.762034) (xy 41.573666 -218.782766) (xy 41.554654 -218.796362)
			(xy 41.53261 -218.81238) (xy 41.484785 -218.838499) (xy 41.43373 -218.857547) (xy 41.380483 -218.869134)
			(xy 41.326129 -218.873026) (xy 41.271775 -218.869142) (xy 41.218527 -218.857563) (xy 41.167469 -218.838524)
			(xy 41.11964 -218.812412) (xy 41.076013 -218.779759) (xy 41.037478 -218.74123) (xy 41.004819 -218.697608)
			(xy 40.9787 -218.649783) (xy 40.959653 -218.598728) (xy 40.948066 -218.545481) (xy 40.944174 -218.491128)
			(xy 40.583155 -218.491128) (xy 40.579264 -218.545471) (xy 40.567679 -218.598708) (xy 40.548635 -218.649754)
			(xy 40.522521 -218.697571) (xy 40.489867 -218.741184) (xy 40.451339 -218.779706) (xy 40.407721 -218.812353)
			(xy 40.3599 -218.83846) (xy 40.308851 -218.857495) (xy 40.255613 -218.869072) (xy 40.201268 -218.872955)
			(xy 40.146925 -218.869063) (xy 40.093688 -218.857478) (xy 40.042642 -218.838433) (xy 39.994826 -218.812318)
			(xy 39.972742 -218.796362) (xy 39.95373 -218.782766) (xy 39.911847 -218.762034) (xy 39.866879 -218.749308)
			(xy 39.820342 -218.745018) (xy 39.773805 -218.749308) (xy 39.728837 -218.762034) (xy 39.686954 -218.782766)
			(xy 39.667942 -218.796362) (xy 39.645896 -218.812388) (xy 39.598065 -218.838521) (xy 39.547001 -218.857581)
			(xy 39.493745 -218.869179) (xy 39.43938 -218.873079) (xy 39.385013 -218.869201) (xy 39.331751 -218.857625)
			(xy 39.28068 -218.838587) (xy 39.232838 -218.812474) (xy 39.1892 -218.779817) (xy 39.150653 -218.741281)
			(xy 39.117984 -218.697652) (xy 39.091857 -218.649818) (xy 39.072805 -218.598751) (xy 39.061214 -218.545493)
			(xy 39.057321 -218.491128) (xy 28.461716 -218.491128) (xy 28.461716 -219.533486) (xy 29.519874 -219.533486)
			(xy 29.519874 -219.446586) (xy 29.527892 -219.360057) (xy 29.54386 -219.274637) (xy 29.567641 -219.191055)
			(xy 29.599033 -219.110023) (xy 29.637767 -219.032234) (xy 29.683514 -218.95835) (xy 29.735883 -218.889003)
			(xy 29.794427 -218.824783) (xy 29.858647 -218.766239) (xy 29.927994 -218.71387) (xy 30.001878 -218.668123)
			(xy 30.079667 -218.629389) (xy 30.160699 -218.597997) (xy 30.244281 -218.574216) (xy 30.329701 -218.558248)
			(xy 30.41623 -218.55023) (xy 30.50313 -218.55023) (xy 30.589659 -218.558248) (xy 30.675079 -218.574216)
			(xy 30.758661 -218.597997) (xy 30.839693 -218.629389) (xy 30.917482 -218.668123) (xy 30.991366 -218.71387)
			(xy 31.060713 -218.766239) (xy 31.124933 -218.824783) (xy 31.183477 -218.889003) (xy 31.235846 -218.95835)
			(xy 31.281593 -219.032234) (xy 31.320327 -219.110023) (xy 31.351719 -219.191055) (xy 31.3755 -219.274637)
			(xy 31.391468 -219.360057) (xy 31.399486 -219.446586) (xy 31.399988 -219.490036) (xy 31.399486 -219.533486)
			(xy 34.599874 -219.533486) (xy 34.599874 -219.446586) (xy 34.607892 -219.360057) (xy 34.62386 -219.274637)
			(xy 34.647641 -219.191055) (xy 34.679033 -219.110023) (xy 34.717767 -219.032234) (xy 34.763514 -218.95835)
			(xy 34.815883 -218.889003) (xy 34.874427 -218.824783) (xy 34.938647 -218.766239) (xy 35.007994 -218.71387)
			(xy 35.081878 -218.668123) (xy 35.159667 -218.629389) (xy 35.240699 -218.597997) (xy 35.324281 -218.574216)
			(xy 35.409701 -218.558248) (xy 35.49623 -218.55023) (xy 35.58313 -218.55023) (xy 35.669659 -218.558248)
			(xy 35.755079 -218.574216) (xy 35.838661 -218.597997) (xy 35.919693 -218.629389) (xy 35.997482 -218.668123)
			(xy 36.071366 -218.71387) (xy 36.140713 -218.766239) (xy 36.204933 -218.824783) (xy 36.263477 -218.889003)
			(xy 36.315846 -218.95835) (xy 36.361593 -219.032234) (xy 36.400327 -219.110023) (xy 36.431719 -219.191055)
			(xy 36.4555 -219.274637) (xy 36.471468 -219.360057) (xy 36.479486 -219.446586) (xy 36.479988 -219.490036)
			(xy 36.479486 -219.533486) (xy 36.471468 -219.620015) (xy 36.4555 -219.705435) (xy 36.431719 -219.789017)
			(xy 36.400327 -219.870049) (xy 36.361593 -219.947838) (xy 36.315846 -220.021722) (xy 36.263477 -220.091069)
			(xy 36.204933 -220.155289) (xy 36.140713 -220.213833) (xy 36.071366 -220.266202) (xy 35.997482 -220.311949)
			(xy 35.919693 -220.350683) (xy 35.838661 -220.382075) (xy 35.772455 -220.400912) (xy 39.057342 -220.400912)
			(xy 39.061229 -220.346549) (xy 39.072814 -220.293293) (xy 39.09186 -220.242227) (xy 39.11798 -220.194392)
			(xy 39.150643 -220.150762) (xy 39.189183 -220.112225) (xy 39.232816 -220.079565) (xy 39.280652 -220.053448)
			(xy 39.331719 -220.034406) (xy 39.384977 -220.022825) (xy 39.43934 -220.018942) (xy 39.493702 -220.022836)
			(xy 39.546957 -220.034428) (xy 39.59802 -220.053482) (xy 39.645851 -220.079609) (xy 39.667942 -220.095572)
			(xy 39.686954 -220.109168) (xy 39.728837 -220.1299) (xy 39.773805 -220.142626) (xy 39.820342 -220.146916)
			(xy 39.866879 -220.142626) (xy 39.911847 -220.1299) (xy 39.95373 -220.109168) (xy 39.972742 -220.095572)
			(xy 39.994848 -220.079643) (xy 40.042669 -220.053531) (xy 40.09372 -220.034491) (xy 40.146961 -220.022911)
			(xy 40.201308 -220.019025) (xy 40.255655 -220.022913) (xy 40.308895 -220.034496) (xy 40.359945 -220.053538)
			(xy 40.407765 -220.079651) (xy 40.451383 -220.112304) (xy 40.489909 -220.150832) (xy 40.52256 -220.194451)
			(xy 40.548671 -220.242273) (xy 40.56771 -220.293324) (xy 40.57929 -220.346565) (xy 40.583175 -220.400912)
			(xy 40.944195 -220.400912) (xy 40.948081 -220.346561) (xy 40.959662 -220.293316) (xy 40.978702 -220.242261)
			(xy 41.004815 -220.194436) (xy 41.037468 -220.150814) (xy 41.075997 -220.112283) (xy 41.119617 -220.079627)
			(xy 41.167441 -220.053511) (xy 41.218495 -220.034468) (xy 41.271739 -220.022884) (xy 41.32609 -220.018995)
			(xy 41.380441 -220.022881) (xy 41.433686 -220.034462) (xy 41.48474 -220.053503) (xy 41.532565 -220.079616)
			(xy 41.554654 -220.095572) (xy 41.573666 -220.109168) (xy 41.615549 -220.1299) (xy 41.660517 -220.142626)
			(xy 41.707054 -220.146916) (xy 41.753591 -220.142626) (xy 41.798559 -220.1299) (xy 41.840442 -220.109168)
			(xy 41.859454 -220.095572) (xy 41.881562 -220.079635) (xy 41.92939 -220.05351) (xy 41.980448 -220.034457)
			(xy 42.033699 -220.022866) (xy 42.088058 -220.018972) (xy 42.142417 -220.022854) (xy 42.195671 -220.034434)
			(xy 42.246734 -220.053475) (xy 42.294567 -220.079589) (xy 42.338196 -220.112247) (xy 42.376734 -220.150781)
			(xy 42.409394 -220.194408) (xy 42.435513 -220.242239) (xy 42.454558 -220.2933) (xy 42.466142 -220.346553)
			(xy 42.470028 -220.400912) (xy 43.18517 -220.400912) (xy 43.189056 -220.346555) (xy 43.200639 -220.293305)
			(xy 43.219682 -220.242245) (xy 43.245799 -220.194415) (xy 43.278456 -220.150789) (xy 43.316991 -220.112255)
			(xy 43.360617 -220.079598) (xy 43.408447 -220.053481) (xy 43.459507 -220.034438) (xy 43.512757 -220.022856)
			(xy 43.567114 -220.01897) (xy 43.62147 -220.02286) (xy 43.67472 -220.034446) (xy 43.725778 -220.053493)
			(xy 43.773606 -220.079612) (xy 43.795696 -220.095572) (xy 43.814708 -220.109168) (xy 43.856591 -220.1299)
			(xy 43.901559 -220.142626) (xy 43.948096 -220.146916) (xy 43.994633 -220.142626) (xy 44.039601 -220.1299)
			(xy 44.081484 -220.109168) (xy 44.100496 -220.095572) (xy 44.122603 -220.079639) (xy 44.170428 -220.05352)
			(xy 44.221483 -220.034474) (xy 44.274729 -220.022887) (xy 44.329082 -220.018997) (xy 44.383435 -220.022882)
			(xy 44.436682 -220.034463) (xy 44.487739 -220.053505) (xy 44.535566 -220.079619) (xy 44.57919 -220.112274)
			(xy 44.617722 -220.150805) (xy 44.650378 -220.194429) (xy 44.676493 -220.242255) (xy 44.695535 -220.293312)
			(xy 44.707117 -220.346559) (xy 44.711003 -220.400912) (xy 45.089179 -220.400912) (xy 45.093065 -220.346557)
			(xy 45.104647 -220.293309) (xy 45.12369 -220.242251) (xy 45.149805 -220.194423) (xy 45.182461 -220.150799)
			(xy 45.220993 -220.112266) (xy 45.264617 -220.079609) (xy 45.312445 -220.053493) (xy 45.363502 -220.034449)
			(xy 45.41675 -220.022866) (xy 45.471105 -220.018979) (xy 45.525459 -220.022868) (xy 45.578707 -220.034452)
			(xy 45.629764 -220.053497) (xy 45.677591 -220.079614) (xy 45.69968 -220.095572) (xy 45.718692 -220.109168)
			(xy 45.760575 -220.1299) (xy 45.805543 -220.142626) (xy 45.85208 -220.146916) (xy 45.898617 -220.142626)
			(xy 45.943585 -220.1299) (xy 45.985468 -220.109168) (xy 46.00448 -220.095572) (xy 46.026587 -220.079637)
			(xy 46.074413 -220.053516) (xy 46.12547 -220.034467) (xy 46.178718 -220.022879) (xy 46.233073 -220.018988)
			(xy 46.287428 -220.022871) (xy 46.340678 -220.034452) (xy 46.391737 -220.053493) (xy 46.439566 -220.079608)
			(xy 46.483192 -220.112264) (xy 46.521726 -220.150796) (xy 46.554384 -220.194421) (xy 46.5805 -220.242249)
			(xy 46.599544 -220.293307) (xy 46.611126 -220.346557) (xy 46.615013 -220.400912) (xy 46.611123 -220.455267)
			(xy 46.599537 -220.508516) (xy 46.58049 -220.559573) (xy 46.554371 -220.6074) (xy 46.521711 -220.651022)
			(xy 46.483174 -220.689552) (xy 46.439546 -220.722205) (xy 46.391715 -220.748317) (xy 46.340655 -220.767355)
			(xy 46.287404 -220.778932) (xy 46.233049 -220.782812) (xy 46.178694 -220.778917) (xy 46.125447 -220.767326)
			(xy 46.074391 -220.748274) (xy 46.026567 -220.72215) (xy 46.00448 -220.706188) (xy 45.985468 -220.692592)
			(xy 45.943585 -220.67186) (xy 45.898617 -220.659134) (xy 45.85208 -220.654844) (xy 45.805543 -220.659134)
			(xy 45.760575 -220.67186) (xy 45.718692 -220.692592) (xy 45.69968 -220.706188) (xy 45.677611 -220.722173)
			(xy 45.629786 -220.748293) (xy 45.57873 -220.767341) (xy 45.525483 -220.778929) (xy 45.471129 -220.782821)
			(xy 45.416774 -220.778937) (xy 45.363525 -220.767357) (xy 45.312466 -220.748317) (xy 45.264637 -220.722204)
			(xy 45.221011 -220.68955) (xy 45.182477 -220.65102) (xy 45.149818 -220.607397) (xy 45.1237 -220.559571)
			(xy 45.104654 -220.508514) (xy 45.093069 -220.455266) (xy 45.089179 -220.400912) (xy 44.711003 -220.400912)
			(xy 44.707114 -220.455265) (xy 44.695528 -220.508511) (xy 44.676483 -220.559567) (xy 44.650365 -220.607392)
			(xy 44.617706 -220.651013) (xy 44.579172 -220.689542) (xy 44.535546 -220.722194) (xy 44.487717 -220.748305)
			(xy 44.436659 -220.767344) (xy 44.383411 -220.778921) (xy 44.329058 -220.782803) (xy 44.274705 -220.778909)
			(xy 44.22146 -220.76732) (xy 44.170406 -220.74827) (xy 44.122583 -220.722148) (xy 44.100496 -220.706188)
			(xy 44.081484 -220.692592) (xy 44.039601 -220.67186) (xy 43.994633 -220.659134) (xy 43.948096 -220.654844)
			(xy 43.901559 -220.659134) (xy 43.856591 -220.67186) (xy 43.814708 -220.692592) (xy 43.795696 -220.706188)
			(xy 43.773627 -220.722175) (xy 43.7258 -220.748297) (xy 43.674743 -220.767347) (xy 43.621494 -220.778937)
			(xy 43.567138 -220.78283) (xy 43.512781 -220.778948) (xy 43.45953 -220.767369) (xy 43.408468 -220.748329)
			(xy 43.360637 -220.722215) (xy 43.317009 -220.689561) (xy 43.278472 -220.651029) (xy 43.245811 -220.607405)
			(xy 43.219692 -220.559577) (xy 43.200645 -220.508518) (xy 43.189059 -220.455269) (xy 43.18517 -220.400912)
			(xy 42.470028 -220.400912) (xy 42.466138 -220.455271) (xy 42.454551 -220.508523) (xy 42.435503 -220.559583)
			(xy 42.409381 -220.607413) (xy 42.376718 -220.651037) (xy 42.338178 -220.689569) (xy 42.294547 -220.722223)
			(xy 42.246712 -220.748335) (xy 42.195648 -220.767373) (xy 42.142393 -220.778949) (xy 42.088034 -220.782828)
			(xy 42.033676 -220.77893) (xy 41.980425 -220.767336) (xy 41.929368 -220.74828) (xy 41.881542 -220.722152)
			(xy 41.859454 -220.706188) (xy 41.840442 -220.692592) (xy 41.798559 -220.67186) (xy 41.753591 -220.659134)
			(xy 41.707054 -220.654844) (xy 41.660517 -220.659134) (xy 41.615549 -220.67186) (xy 41.573666 -220.692592)
			(xy 41.554654 -220.706188) (xy 41.532586 -220.722171) (xy 41.484762 -220.748287) (xy 41.433709 -220.767331)
			(xy 41.380465 -220.778916) (xy 41.326114 -220.782805) (xy 41.271763 -220.77892) (xy 41.218518 -220.767339)
			(xy 41.167463 -220.748299) (xy 41.119638 -220.722186) (xy 41.076015 -220.689533) (xy 41.037484 -220.651004)
			(xy 41.004828 -220.607384) (xy 40.978712 -220.55956) (xy 40.959668 -220.508507) (xy 40.948084 -220.455263)
			(xy 40.944195 -220.400912) (xy 40.583175 -220.400912) (xy 40.579287 -220.455259) (xy 40.567703 -220.508499)
			(xy 40.548661 -220.559549) (xy 40.522547 -220.607369) (xy 40.489893 -220.650986) (xy 40.451364 -220.689511)
			(xy 40.407745 -220.722162) (xy 40.359923 -220.748272) (xy 40.308872 -220.767311) (xy 40.255631 -220.778891)
			(xy 40.201284 -220.782775) (xy 40.146937 -220.778886) (xy 40.093697 -220.767302) (xy 40.042648 -220.748259)
			(xy 39.994828 -220.722144) (xy 39.972742 -220.706188) (xy 39.95373 -220.692592) (xy 39.911847 -220.67186)
			(xy 39.866879 -220.659134) (xy 39.820342 -220.654844) (xy 39.773805 -220.659134) (xy 39.728837 -220.67186)
			(xy 39.686954 -220.692592) (xy 39.667942 -220.706188) (xy 39.645872 -220.722178) (xy 39.598042 -220.748308)
			(xy 39.54698 -220.767365) (xy 39.493726 -220.77896) (xy 39.439364 -220.782858) (xy 39.385 -220.778978)
			(xy 39.331742 -220.767401) (xy 39.280674 -220.748362) (xy 39.232836 -220.722248) (xy 39.189201 -220.689591)
			(xy 39.150659 -220.651056) (xy 39.117993 -220.607428) (xy 39.09187 -220.559595) (xy 39.07282 -220.508531)
			(xy 39.061232 -220.455275) (xy 39.057342 -220.400912) (xy 35.772455 -220.400912) (xy 35.755079 -220.405856)
			(xy 35.669659 -220.421824) (xy 35.58313 -220.429842) (xy 35.49623 -220.429842) (xy 35.409701 -220.421824)
			(xy 35.324281 -220.405856) (xy 35.240699 -220.382075) (xy 35.159667 -220.350683) (xy 35.081878 -220.311949)
			(xy 35.007994 -220.266202) (xy 34.938647 -220.213833) (xy 34.874427 -220.155289) (xy 34.815883 -220.091069)
			(xy 34.763514 -220.021722) (xy 34.717767 -219.947838) (xy 34.679033 -219.870049) (xy 34.647641 -219.789017)
			(xy 34.62386 -219.705435) (xy 34.607892 -219.620015) (xy 34.599874 -219.533486) (xy 31.399486 -219.533486)
			(xy 31.391468 -219.620015) (xy 31.3755 -219.705435) (xy 31.351719 -219.789017) (xy 31.320327 -219.870049)
			(xy 31.281593 -219.947838) (xy 31.235846 -220.021722) (xy 31.183477 -220.091069) (xy 31.124933 -220.155289)
			(xy 31.060713 -220.213833) (xy 30.991366 -220.266202) (xy 30.917482 -220.311949) (xy 30.839693 -220.350683)
			(xy 30.758661 -220.382075) (xy 30.675079 -220.405856) (xy 30.589659 -220.421824) (xy 30.50313 -220.429842)
			(xy 30.41623 -220.429842) (xy 30.329701 -220.421824) (xy 30.244281 -220.405856) (xy 30.160699 -220.382075)
			(xy 30.079667 -220.350683) (xy 30.001878 -220.311949) (xy 29.927994 -220.266202) (xy 29.858647 -220.213833)
			(xy 29.794427 -220.155289) (xy 29.735883 -220.091069) (xy 29.683514 -220.021722) (xy 29.637767 -219.947838)
			(xy 29.599033 -219.870049) (xy 29.567641 -219.789017) (xy 29.54386 -219.705435) (xy 29.527892 -219.620015)
			(xy 29.519874 -219.533486) (xy 28.461716 -219.533486) (xy 28.461716 -222.073486) (xy 29.519874 -222.073486)
			(xy 29.519874 -221.986586) (xy 29.527892 -221.900057) (xy 29.54386 -221.814637) (xy 29.567641 -221.731055)
			(xy 29.599033 -221.650023) (xy 29.637767 -221.572234) (xy 29.683514 -221.49835) (xy 29.735883 -221.429003)
			(xy 29.794427 -221.364783) (xy 29.858647 -221.306239) (xy 29.927994 -221.25387) (xy 30.001878 -221.208123)
			(xy 30.079667 -221.169389) (xy 30.160699 -221.137997) (xy 30.244281 -221.114216) (xy 30.329701 -221.098248)
			(xy 30.41623 -221.09023) (xy 30.50313 -221.09023) (xy 30.589659 -221.098248) (xy 30.675079 -221.114216)
			(xy 30.758661 -221.137997) (xy 30.839693 -221.169389) (xy 30.917482 -221.208123) (xy 30.991366 -221.25387)
			(xy 31.060713 -221.306239) (xy 31.124933 -221.364783) (xy 31.183477 -221.429003) (xy 31.235846 -221.49835)
			(xy 31.281593 -221.572234) (xy 31.320327 -221.650023) (xy 31.351719 -221.731055) (xy 31.3755 -221.814637)
			(xy 31.391468 -221.900057) (xy 31.399486 -221.986586) (xy 31.399988 -222.030036) (xy 31.399486 -222.073486)
			(xy 34.599874 -222.073486) (xy 34.599874 -221.986586) (xy 34.607892 -221.900057) (xy 34.62386 -221.814637)
			(xy 34.647641 -221.731055) (xy 34.679033 -221.650023) (xy 34.717767 -221.572234) (xy 34.763514 -221.49835)
			(xy 34.815883 -221.429003) (xy 34.874427 -221.364783) (xy 34.938647 -221.306239) (xy 35.007994 -221.25387)
			(xy 35.081878 -221.208123) (xy 35.159667 -221.169389) (xy 35.240699 -221.137997) (xy 35.324281 -221.114216)
			(xy 35.409701 -221.098248) (xy 35.49623 -221.09023) (xy 35.58313 -221.09023) (xy 35.669659 -221.098248)
			(xy 35.755079 -221.114216) (xy 35.838661 -221.137997) (xy 35.919693 -221.169389) (xy 35.997482 -221.208123)
			(xy 36.071366 -221.25387) (xy 36.140713 -221.306239) (xy 36.204933 -221.364783) (xy 36.263477 -221.429003)
			(xy 36.315846 -221.49835) (xy 36.361593 -221.572234) (xy 36.400327 -221.650023) (xy 36.431719 -221.731055)
			(xy 36.4555 -221.814637) (xy 36.471468 -221.900057) (xy 36.479486 -221.986586) (xy 36.479988 -222.030036)
			(xy 36.479486 -222.073486) (xy 36.471468 -222.160015) (xy 36.4555 -222.245435) (xy 36.431719 -222.329017)
			(xy 36.400327 -222.410049) (xy 36.361593 -222.487838) (xy 36.315846 -222.561722) (xy 36.263477 -222.631069)
			(xy 36.204933 -222.695289) (xy 36.140713 -222.753833) (xy 36.071366 -222.806202) (xy 35.997482 -222.851949)
			(xy 35.919693 -222.890683) (xy 35.838661 -222.922075) (xy 35.755079 -222.945856) (xy 35.669659 -222.961824)
			(xy 35.58313 -222.969842) (xy 35.49623 -222.969842) (xy 35.409701 -222.961824) (xy 35.324281 -222.945856)
			(xy 35.240699 -222.922075) (xy 35.159667 -222.890683) (xy 35.081878 -222.851949) (xy 35.007994 -222.806202)
			(xy 34.938647 -222.753833) (xy 34.874427 -222.695289) (xy 34.815883 -222.631069) (xy 34.763514 -222.561722)
			(xy 34.717767 -222.487838) (xy 34.679033 -222.410049) (xy 34.647641 -222.329017) (xy 34.62386 -222.245435)
			(xy 34.607892 -222.160015) (xy 34.599874 -222.073486) (xy 31.399486 -222.073486) (xy 31.391468 -222.160015)
			(xy 31.3755 -222.245435) (xy 31.351719 -222.329017) (xy 31.320327 -222.410049) (xy 31.281593 -222.487838)
			(xy 31.235846 -222.561722) (xy 31.183477 -222.631069) (xy 31.124933 -222.695289) (xy 31.060713 -222.753833)
			(xy 30.991366 -222.806202) (xy 30.917482 -222.851949) (xy 30.839693 -222.890683) (xy 30.758661 -222.922075)
			(xy 30.675079 -222.945856) (xy 30.589659 -222.961824) (xy 30.50313 -222.969842) (xy 30.41623 -222.969842)
			(xy 30.329701 -222.961824) (xy 30.244281 -222.945856) (xy 30.160699 -222.922075) (xy 30.079667 -222.890683)
			(xy 30.001878 -222.851949) (xy 29.927994 -222.806202) (xy 29.858647 -222.753833) (xy 29.794427 -222.695289)
			(xy 29.735883 -222.631069) (xy 29.683514 -222.561722) (xy 29.637767 -222.487838) (xy 29.599033 -222.410049)
			(xy 29.567641 -222.329017) (xy 29.54386 -222.245435) (xy 29.527892 -222.160015) (xy 29.519874 -222.073486)
			(xy 28.461716 -222.073486) (xy 28.461716 -224.613486) (xy 29.519874 -224.613486) (xy 29.519874 -224.526586)
			(xy 29.527892 -224.440057) (xy 29.54386 -224.354637) (xy 29.567641 -224.271055) (xy 29.599033 -224.190023)
			(xy 29.637767 -224.112234) (xy 29.683514 -224.03835) (xy 29.735883 -223.969003) (xy 29.794427 -223.904783)
			(xy 29.858647 -223.846239) (xy 29.927994 -223.79387) (xy 30.001878 -223.748123) (xy 30.079667 -223.709389)
			(xy 30.160699 -223.677997) (xy 30.244281 -223.654216) (xy 30.329701 -223.638248) (xy 30.41623 -223.63023)
			(xy 30.50313 -223.63023) (xy 30.589659 -223.638248) (xy 30.675079 -223.654216) (xy 30.758661 -223.677997)
			(xy 30.839693 -223.709389) (xy 30.917482 -223.748123) (xy 30.991366 -223.79387) (xy 31.060713 -223.846239)
			(xy 31.124933 -223.904783) (xy 31.183477 -223.969003) (xy 31.235846 -224.03835) (xy 31.281593 -224.112234)
			(xy 31.320327 -224.190023) (xy 31.351719 -224.271055) (xy 31.3755 -224.354637) (xy 31.391468 -224.440057)
			(xy 31.399486 -224.526586) (xy 31.399988 -224.570036) (xy 31.399486 -224.613486) (xy 34.599874 -224.613486)
			(xy 34.599874 -224.526586) (xy 34.607892 -224.440057) (xy 34.62386 -224.354637) (xy 34.647641 -224.271055)
			(xy 34.679033 -224.190023) (xy 34.717767 -224.112234) (xy 34.763514 -224.03835) (xy 34.815883 -223.969003)
			(xy 34.874427 -223.904783) (xy 34.938647 -223.846239) (xy 35.007994 -223.79387) (xy 35.081878 -223.748123)
			(xy 35.159667 -223.709389) (xy 35.240699 -223.677997) (xy 35.324281 -223.654216) (xy 35.409701 -223.638248)
			(xy 35.49623 -223.63023) (xy 35.58313 -223.63023) (xy 35.669659 -223.638248) (xy 35.755079 -223.654216)
			(xy 35.838661 -223.677997) (xy 35.919693 -223.709389) (xy 35.997482 -223.748123) (xy 36.071366 -223.79387)
			(xy 36.140713 -223.846239) (xy 36.204933 -223.904783) (xy 36.263477 -223.969003) (xy 36.315846 -224.03835)
			(xy 36.361593 -224.112234) (xy 36.400327 -224.190023) (xy 36.431719 -224.271055) (xy 36.4555 -224.354637)
			(xy 36.471468 -224.440057) (xy 36.479486 -224.526586) (xy 36.479988 -224.570036) (xy 36.479486 -224.613486)
			(xy 36.471468 -224.700015) (xy 36.4555 -224.785435) (xy 36.431719 -224.869017) (xy 36.400327 -224.950049)
			(xy 36.361593 -225.027838) (xy 36.315846 -225.101722) (xy 36.263477 -225.171069) (xy 36.204933 -225.235289)
			(xy 36.140713 -225.293833) (xy 36.071366 -225.346202) (xy 35.997482 -225.391949) (xy 35.919693 -225.430683)
			(xy 35.838661 -225.462075) (xy 35.755079 -225.485856) (xy 35.669659 -225.501824) (xy 35.58313 -225.509842)
			(xy 35.49623 -225.509842) (xy 35.409701 -225.501824) (xy 35.324281 -225.485856) (xy 35.240699 -225.462075)
			(xy 35.159667 -225.430683) (xy 35.081878 -225.391949) (xy 35.007994 -225.346202) (xy 34.938647 -225.293833)
			(xy 34.874427 -225.235289) (xy 34.815883 -225.171069) (xy 34.763514 -225.101722) (xy 34.717767 -225.027838)
			(xy 34.679033 -224.950049) (xy 34.647641 -224.869017) (xy 34.62386 -224.785435) (xy 34.607892 -224.700015)
			(xy 34.599874 -224.613486) (xy 31.399486 -224.613486) (xy 31.391468 -224.700015) (xy 31.3755 -224.785435)
			(xy 31.351719 -224.869017) (xy 31.320327 -224.950049) (xy 31.281593 -225.027838) (xy 31.235846 -225.101722)
			(xy 31.183477 -225.171069) (xy 31.124933 -225.235289) (xy 31.060713 -225.293833) (xy 30.991366 -225.346202)
			(xy 30.917482 -225.391949) (xy 30.839693 -225.430683) (xy 30.758661 -225.462075) (xy 30.675079 -225.485856)
			(xy 30.589659 -225.501824) (xy 30.50313 -225.509842) (xy 30.41623 -225.509842) (xy 30.329701 -225.501824)
			(xy 30.244281 -225.485856) (xy 30.160699 -225.462075) (xy 30.079667 -225.430683) (xy 30.001878 -225.391949)
			(xy 29.927994 -225.346202) (xy 29.858647 -225.293833) (xy 29.794427 -225.235289) (xy 29.735883 -225.171069)
			(xy 29.683514 -225.101722) (xy 29.637767 -225.027838) (xy 29.599033 -224.950049) (xy 29.567641 -224.869017)
			(xy 29.54386 -224.785435) (xy 29.527892 -224.700015) (xy 29.519874 -224.613486) (xy 28.461716 -224.613486)
			(xy 28.461716 -225.520758) (xy 28.02509 -225.957384) (xy 28.0145 -225.968542) (xy 27.998481 -225.994793)
			(xy 27.989203 -226.024112) (xy 27.987752 -226.039426) (xy 27.987752 -227.153486) (xy 29.519874 -227.153486)
			(xy 29.519874 -227.066586) (xy 29.527892 -226.980057) (xy 29.54386 -226.894637) (xy 29.567641 -226.811055)
			(xy 29.599033 -226.730023) (xy 29.637767 -226.652234) (xy 29.683514 -226.57835) (xy 29.735883 -226.509003)
			(xy 29.794427 -226.444783) (xy 29.858647 -226.386239) (xy 29.927994 -226.33387) (xy 30.001878 -226.288123)
			(xy 30.079667 -226.249389) (xy 30.160699 -226.217997) (xy 30.244281 -226.194216) (xy 30.329701 -226.178248)
			(xy 30.41623 -226.17023) (xy 30.50313 -226.17023) (xy 30.589659 -226.178248) (xy 30.675079 -226.194216)
			(xy 30.758661 -226.217997) (xy 30.839693 -226.249389) (xy 30.917482 -226.288123) (xy 30.991366 -226.33387)
			(xy 31.060713 -226.386239) (xy 31.124933 -226.444783) (xy 31.183477 -226.509003) (xy 31.235846 -226.57835)
			(xy 31.281593 -226.652234) (xy 31.320327 -226.730023) (xy 31.351719 -226.811055) (xy 31.3755 -226.894637)
			(xy 31.391468 -226.980057) (xy 31.399486 -227.066586) (xy 31.399988 -227.110036) (xy 31.399486 -227.153486)
			(xy 34.599874 -227.153486) (xy 34.599874 -227.066586) (xy 34.607892 -226.980057) (xy 34.62386 -226.894637)
			(xy 34.647641 -226.811055) (xy 34.679033 -226.730023) (xy 34.717767 -226.652234) (xy 34.763514 -226.57835)
			(xy 34.815883 -226.509003) (xy 34.874427 -226.444783) (xy 34.938647 -226.386239) (xy 35.007994 -226.33387)
			(xy 35.081878 -226.288123) (xy 35.159667 -226.249389) (xy 35.240699 -226.217997) (xy 35.324281 -226.194216)
			(xy 35.409701 -226.178248) (xy 35.49623 -226.17023) (xy 35.58313 -226.17023) (xy 35.669659 -226.178248)
			(xy 35.755079 -226.194216) (xy 35.838661 -226.217997) (xy 35.919693 -226.249389) (xy 35.997482 -226.288123)
			(xy 36.071366 -226.33387) (xy 36.140713 -226.386239) (xy 36.204933 -226.444783) (xy 36.263477 -226.509003)
			(xy 36.315846 -226.57835) (xy 36.361593 -226.652234) (xy 36.400327 -226.730023) (xy 36.431719 -226.811055)
			(xy 36.4555 -226.894637) (xy 36.471468 -226.980057) (xy 36.479486 -227.066586) (xy 36.479988 -227.110036)
			(xy 36.479486 -227.153486) (xy 36.471468 -227.240015) (xy 36.4555 -227.325435) (xy 36.431719 -227.409017)
			(xy 36.400327 -227.490049) (xy 36.361593 -227.567838) (xy 36.315846 -227.641722) (xy 36.263477 -227.711069)
			(xy 36.204933 -227.775289) (xy 36.140713 -227.833833) (xy 36.071366 -227.886202) (xy 35.997482 -227.931949)
			(xy 35.919693 -227.970683) (xy 35.838661 -228.002075) (xy 35.755079 -228.025856) (xy 35.669659 -228.041824)
			(xy 35.58313 -228.049842) (xy 35.49623 -228.049842) (xy 35.409701 -228.041824) (xy 35.324281 -228.025856)
			(xy 35.240699 -228.002075) (xy 35.159667 -227.970683) (xy 35.081878 -227.931949) (xy 35.007994 -227.886202)
			(xy 34.938647 -227.833833) (xy 34.874427 -227.775289) (xy 34.815883 -227.711069) (xy 34.763514 -227.641722)
			(xy 34.717767 -227.567838) (xy 34.679033 -227.490049) (xy 34.647641 -227.409017) (xy 34.62386 -227.325435)
			(xy 34.607892 -227.240015) (xy 34.599874 -227.153486) (xy 31.399486 -227.153486) (xy 31.391468 -227.240015)
			(xy 31.3755 -227.325435) (xy 31.351719 -227.409017) (xy 31.320327 -227.490049) (xy 31.281593 -227.567838)
			(xy 31.235846 -227.641722) (xy 31.183477 -227.711069) (xy 31.124933 -227.775289) (xy 31.060713 -227.833833)
			(xy 30.991366 -227.886202) (xy 30.917482 -227.931949) (xy 30.839693 -227.970683) (xy 30.758661 -228.002075)
			(xy 30.675079 -228.025856) (xy 30.589659 -228.041824) (xy 30.50313 -228.049842) (xy 30.41623 -228.049842)
			(xy 30.329701 -228.041824) (xy 30.244281 -228.025856) (xy 30.160699 -228.002075) (xy 30.079667 -227.970683)
			(xy 30.001878 -227.931949) (xy 29.927994 -227.886202) (xy 29.858647 -227.833833) (xy 29.794427 -227.775289)
			(xy 29.735883 -227.711069) (xy 29.683514 -227.641722) (xy 29.637767 -227.567838) (xy 29.599033 -227.490049)
			(xy 29.567641 -227.409017) (xy 29.54386 -227.325435) (xy 29.527892 -227.240015) (xy 29.519874 -227.153486)
			(xy 27.987752 -227.153486) (xy 27.987752 -227.664264) (xy 25.95853 -229.693486) (xy 29.519874 -229.693486)
			(xy 29.519874 -229.606586) (xy 29.527892 -229.520057) (xy 29.54386 -229.434637) (xy 29.567641 -229.351055)
			(xy 29.599033 -229.270023) (xy 29.637767 -229.192234) (xy 29.683514 -229.11835) (xy 29.735883 -229.049003)
			(xy 29.794427 -228.984783) (xy 29.858647 -228.926239) (xy 29.927994 -228.87387) (xy 30.001878 -228.828123)
			(xy 30.079667 -228.789389) (xy 30.160699 -228.757997) (xy 30.244281 -228.734216) (xy 30.329701 -228.718248)
			(xy 30.41623 -228.71023) (xy 30.50313 -228.71023) (xy 30.589659 -228.718248) (xy 30.675079 -228.734216)
			(xy 30.758661 -228.757997) (xy 30.839693 -228.789389) (xy 30.917482 -228.828123) (xy 30.991366 -228.87387)
			(xy 31.060713 -228.926239) (xy 31.124933 -228.984783) (xy 31.183477 -229.049003) (xy 31.235846 -229.11835)
			(xy 31.281593 -229.192234) (xy 31.320327 -229.270023) (xy 31.351719 -229.351055) (xy 31.3755 -229.434637)
			(xy 31.391468 -229.520057) (xy 31.399486 -229.606586) (xy 31.399988 -229.650036) (xy 31.399486 -229.693486)
			(xy 34.599874 -229.693486) (xy 34.599874 -229.606586) (xy 34.607892 -229.520057) (xy 34.62386 -229.434637)
			(xy 34.647641 -229.351055) (xy 34.679033 -229.270023) (xy 34.717767 -229.192234) (xy 34.763514 -229.11835)
			(xy 34.815883 -229.049003) (xy 34.874427 -228.984783) (xy 34.938647 -228.926239) (xy 35.007994 -228.87387)
			(xy 35.081878 -228.828123) (xy 35.159667 -228.789389) (xy 35.240699 -228.757997) (xy 35.324281 -228.734216)
			(xy 35.409701 -228.718248) (xy 35.49623 -228.71023) (xy 35.58313 -228.71023) (xy 35.669659 -228.718248)
			(xy 35.755079 -228.734216) (xy 35.838661 -228.757997) (xy 35.919693 -228.789389) (xy 35.997482 -228.828123)
			(xy 36.071366 -228.87387) (xy 36.140713 -228.926239) (xy 36.204933 -228.984783) (xy 36.263477 -229.049003)
			(xy 36.315846 -229.11835) (xy 36.341678 -229.16007) (xy 39.818564 -229.16007) (xy 39.819058 -229.102661)
			(xy 39.826902 -228.988113) (xy 39.842544 -228.874366) (xy 39.865911 -228.761952) (xy 39.896896 -228.651394)
			(xy 39.935352 -228.543209) (xy 39.981101 -228.4379) (xy 40.03393 -228.335958) (xy 40.093592 -228.237859)
			(xy 40.159809 -228.14406) (xy 40.232272 -228.054998) (xy 40.310645 -227.971089) (xy 40.39456 -227.892723)
			(xy 40.483627 -227.820266) (xy 40.577431 -227.754056) (xy 40.675535 -227.694402) (xy 40.777481 -227.641581)
			(xy 40.882793 -227.595839) (xy 40.990981 -227.557391) (xy 41.101541 -227.526415) (xy 41.213957 -227.503056)
			(xy 41.327705 -227.487423) (xy 41.442254 -227.479588) (xy 41.557072 -227.479588) (xy 41.671621 -227.487423)
			(xy 41.785369 -227.503056) (xy 41.897785 -227.526415) (xy 42.008345 -227.557391) (xy 42.116533 -227.595839)
			(xy 42.221845 -227.641581) (xy 42.323791 -227.694402) (xy 42.421895 -227.754056) (xy 42.501239 -227.81006)
			(xy 43.327577 -227.81006) (xy 43.331612 -227.734356) (xy 43.343671 -227.659511) (xy 43.363617 -227.58637)
			(xy 43.391224 -227.515765) (xy 43.42618 -227.448494) (xy 43.468088 -227.385319) (xy 43.516474 -227.326957)
			(xy 43.57079 -227.274069) (xy 43.630419 -227.227254) (xy 43.694687 -227.187042) (xy 43.762864 -227.15389)
			(xy 43.83418 -227.128172) (xy 43.907825 -227.11018) (xy 43.982965 -227.100118) (xy 44.058749 -227.098099)
			(xy 44.134319 -227.104148) (xy 44.208817 -227.118195) (xy 44.2814 -227.140081) (xy 44.351246 -227.169558)
			(xy 44.417563 -227.206293) (xy 44.479599 -227.249868) (xy 44.536652 -227.29979) (xy 44.588076 -227.355494)
			(xy 44.633287 -227.416349) (xy 44.671774 -227.481664) (xy 44.7031 -227.5507) (xy 44.72691 -227.622675)
			(xy 44.742935 -227.696773) (xy 44.750994 -227.772154) (xy 44.751498 -227.81006) (xy 45.867577 -227.81006)
			(xy 45.871612 -227.734356) (xy 45.883671 -227.659511) (xy 45.903617 -227.58637) (xy 45.931224 -227.515765)
			(xy 45.96618 -227.448494) (xy 46.008088 -227.385319) (xy 46.056474 -227.326957) (xy 46.11079 -227.274069)
			(xy 46.170419 -227.227254) (xy 46.234687 -227.187042) (xy 46.302864 -227.15389) (xy 46.37418 -227.128172)
			(xy 46.447825 -227.11018) (xy 46.522965 -227.100118) (xy 46.598749 -227.098099) (xy 46.674319 -227.104148)
			(xy 46.748817 -227.118195) (xy 46.8214 -227.140081) (xy 46.891246 -227.169558) (xy 46.957563 -227.206293)
			(xy 47.019599 -227.249868) (xy 47.076652 -227.29979) (xy 47.128076 -227.355494) (xy 47.173287 -227.416349)
			(xy 47.211774 -227.481664) (xy 47.2431 -227.5507) (xy 47.26691 -227.622675) (xy 47.282935 -227.696773)
			(xy 47.290994 -227.772154) (xy 47.291498 -227.81006) (xy 48.407577 -227.81006) (xy 48.411612 -227.734356)
			(xy 48.423671 -227.659511) (xy 48.443617 -227.58637) (xy 48.471224 -227.515765) (xy 48.50618 -227.448494)
			(xy 48.548088 -227.385319) (xy 48.596474 -227.326957) (xy 48.65079 -227.274069) (xy 48.710419 -227.227254)
			(xy 48.774687 -227.187042) (xy 48.842864 -227.15389) (xy 48.91418 -227.128172) (xy 48.987825 -227.11018)
			(xy 49.062965 -227.100118) (xy 49.138749 -227.098099) (xy 49.214319 -227.104148) (xy 49.288817 -227.118195)
			(xy 49.3614 -227.140081) (xy 49.431246 -227.169558) (xy 49.497563 -227.206293) (xy 49.559599 -227.249868)
			(xy 49.616652 -227.29979) (xy 49.668076 -227.355494) (xy 49.713287 -227.416349) (xy 49.751774 -227.481664)
			(xy 49.7831 -227.5507) (xy 49.80691 -227.622675) (xy 49.822935 -227.696773) (xy 49.830994 -227.772154)
			(xy 49.831498 -227.81006) (xy 50.947577 -227.81006) (xy 50.951612 -227.734356) (xy 50.963671 -227.659511)
			(xy 50.983617 -227.58637) (xy 51.011224 -227.515765) (xy 51.04618 -227.448494) (xy 51.088088 -227.385319)
			(xy 51.136474 -227.326957) (xy 51.19079 -227.274069) (xy 51.250419 -227.227254) (xy 51.314687 -227.187042)
			(xy 51.382864 -227.15389) (xy 51.45418 -227.128172) (xy 51.527825 -227.11018) (xy 51.602965 -227.100118)
			(xy 51.678749 -227.098099) (xy 51.754319 -227.104148) (xy 51.828817 -227.118195) (xy 51.9014 -227.140081)
			(xy 51.971246 -227.169558) (xy 52.037563 -227.206293) (xy 52.099599 -227.249868) (xy 52.156652 -227.29979)
			(xy 52.208076 -227.355494) (xy 52.253287 -227.416349) (xy 52.291774 -227.481664) (xy 52.3231 -227.5507)
			(xy 52.34691 -227.622675) (xy 52.362935 -227.696773) (xy 52.370994 -227.772154) (xy 52.371498 -227.81006)
			(xy 53.487577 -227.81006) (xy 53.491612 -227.734356) (xy 53.503671 -227.659511) (xy 53.523617 -227.58637)
			(xy 53.551224 -227.515765) (xy 53.58618 -227.448494) (xy 53.628088 -227.385319) (xy 53.676474 -227.326957)
			(xy 53.73079 -227.274069) (xy 53.790419 -227.227254) (xy 53.854687 -227.187042) (xy 53.922864 -227.15389)
			(xy 53.99418 -227.128172) (xy 54.067825 -227.11018) (xy 54.142965 -227.100118) (xy 54.218749 -227.098099)
			(xy 54.294319 -227.104148) (xy 54.368817 -227.118195) (xy 54.4414 -227.140081) (xy 54.511246 -227.169558)
			(xy 54.577563 -227.206293) (xy 54.639599 -227.249868) (xy 54.696652 -227.29979) (xy 54.748076 -227.355494)
			(xy 54.793287 -227.416349) (xy 54.831774 -227.481664) (xy 54.8631 -227.5507) (xy 54.88691 -227.622675)
			(xy 54.902935 -227.696773) (xy 54.910994 -227.772154) (xy 54.911498 -227.81006) (xy 56.027577 -227.81006)
			(xy 56.031612 -227.734356) (xy 56.043671 -227.659511) (xy 56.063617 -227.58637) (xy 56.091224 -227.515765)
			(xy 56.12618 -227.448494) (xy 56.168088 -227.385319) (xy 56.216474 -227.326957) (xy 56.27079 -227.274069)
			(xy 56.330419 -227.227254) (xy 56.394687 -227.187042) (xy 56.462864 -227.15389) (xy 56.53418 -227.128172)
			(xy 56.607825 -227.11018) (xy 56.682965 -227.100118) (xy 56.758749 -227.098099) (xy 56.834319 -227.104148)
			(xy 56.908817 -227.118195) (xy 56.9814 -227.140081) (xy 57.051246 -227.169558) (xy 57.117563 -227.206293)
			(xy 57.179599 -227.249868) (xy 57.236652 -227.29979) (xy 57.288076 -227.355494) (xy 57.333287 -227.416349)
			(xy 57.371774 -227.481664) (xy 57.4031 -227.5507) (xy 57.42691 -227.622675) (xy 57.442935 -227.696773)
			(xy 57.450994 -227.772154) (xy 57.451498 -227.81006) (xy 58.567577 -227.81006) (xy 58.571612 -227.734356)
			(xy 58.583671 -227.659511) (xy 58.603617 -227.58637) (xy 58.631224 -227.515765) (xy 58.66618 -227.448494)
			(xy 58.708088 -227.385319) (xy 58.756474 -227.326957) (xy 58.81079 -227.274069) (xy 58.870419 -227.227254)
			(xy 58.934687 -227.187042) (xy 59.002864 -227.15389) (xy 59.07418 -227.128172) (xy 59.147825 -227.11018)
			(xy 59.222965 -227.100118) (xy 59.298749 -227.098099) (xy 59.374319 -227.104148) (xy 59.448817 -227.118195)
			(xy 59.5214 -227.140081) (xy 59.591246 -227.169558) (xy 59.657563 -227.206293) (xy 59.719599 -227.249868)
			(xy 59.776652 -227.29979) (xy 59.828076 -227.355494) (xy 59.873287 -227.416349) (xy 59.911774 -227.481664)
			(xy 59.9431 -227.5507) (xy 59.96691 -227.622675) (xy 59.982935 -227.696773) (xy 59.990994 -227.772154)
			(xy 59.991498 -227.81006) (xy 61.107577 -227.81006) (xy 61.111612 -227.734356) (xy 61.123671 -227.659511)
			(xy 61.143617 -227.58637) (xy 61.171224 -227.515765) (xy 61.20618 -227.448494) (xy 61.248088 -227.385319)
			(xy 61.296474 -227.326957) (xy 61.35079 -227.274069) (xy 61.410419 -227.227254) (xy 61.474687 -227.187042)
			(xy 61.542864 -227.15389) (xy 61.61418 -227.128172) (xy 61.687825 -227.11018) (xy 61.762965 -227.100118)
			(xy 61.838749 -227.098099) (xy 61.914319 -227.104148) (xy 61.988817 -227.118195) (xy 62.0614 -227.140081)
			(xy 62.131246 -227.169558) (xy 62.197563 -227.206293) (xy 62.259599 -227.249868) (xy 62.316652 -227.29979)
			(xy 62.368076 -227.355494) (xy 62.413287 -227.416349) (xy 62.451774 -227.481664) (xy 62.4831 -227.5507)
			(xy 62.50691 -227.622675) (xy 62.522935 -227.696773) (xy 62.530994 -227.772154) (xy 62.531498 -227.81006)
			(xy 62.530994 -227.847966) (xy 62.522935 -227.923347) (xy 62.50691 -227.997445) (xy 62.4831 -228.06942)
			(xy 62.451774 -228.138456) (xy 62.413287 -228.203771) (xy 62.368076 -228.264626) (xy 62.316652 -228.32033)
			(xy 62.259599 -228.370252) (xy 62.197563 -228.413827) (xy 62.131246 -228.450562) (xy 62.0614 -228.480039)
			(xy 61.988817 -228.501925) (xy 61.914319 -228.515972) (xy 61.838749 -228.522021) (xy 61.762965 -228.520002)
			(xy 61.687825 -228.50994) (xy 61.61418 -228.491948) (xy 61.542864 -228.46623) (xy 61.474687 -228.433078)
			(xy 61.410419 -228.392866) (xy 61.35079 -228.346051) (xy 61.296474 -228.293163) (xy 61.248088 -228.234801)
			(xy 61.20618 -228.171626) (xy 61.171224 -228.104355) (xy 61.143617 -228.03375) (xy 61.123671 -227.960609)
			(xy 61.111612 -227.885764) (xy 61.107577 -227.81006) (xy 59.991498 -227.81006) (xy 59.990994 -227.847966)
			(xy 59.982935 -227.923347) (xy 59.96691 -227.997445) (xy 59.9431 -228.06942) (xy 59.911774 -228.138456)
			(xy 59.873287 -228.203771) (xy 59.828076 -228.264626) (xy 59.776652 -228.32033) (xy 59.719599 -228.370252)
			(xy 59.657563 -228.413827) (xy 59.591246 -228.450562) (xy 59.5214 -228.480039) (xy 59.448817 -228.501925)
			(xy 59.374319 -228.515972) (xy 59.298749 -228.522021) (xy 59.222965 -228.520002) (xy 59.147825 -228.50994)
			(xy 59.07418 -228.491948) (xy 59.002864 -228.46623) (xy 58.934687 -228.433078) (xy 58.870419 -228.392866)
			(xy 58.81079 -228.346051) (xy 58.756474 -228.293163) (xy 58.708088 -228.234801) (xy 58.66618 -228.171626)
			(xy 58.631224 -228.104355) (xy 58.603617 -228.03375) (xy 58.583671 -227.960609) (xy 58.571612 -227.885764)
			(xy 58.567577 -227.81006) (xy 57.451498 -227.81006) (xy 57.450994 -227.847966) (xy 57.442935 -227.923347)
			(xy 57.42691 -227.997445) (xy 57.4031 -228.06942) (xy 57.371774 -228.138456) (xy 57.333287 -228.203771)
			(xy 57.288076 -228.264626) (xy 57.236652 -228.32033) (xy 57.179599 -228.370252) (xy 57.117563 -228.413827)
			(xy 57.051246 -228.450562) (xy 56.9814 -228.480039) (xy 56.908817 -228.501925) (xy 56.834319 -228.515972)
			(xy 56.758749 -228.522021) (xy 56.682965 -228.520002) (xy 56.607825 -228.50994) (xy 56.53418 -228.491948)
			(xy 56.462864 -228.46623) (xy 56.394687 -228.433078) (xy 56.330419 -228.392866) (xy 56.27079 -228.346051)
			(xy 56.216474 -228.293163) (xy 56.168088 -228.234801) (xy 56.12618 -228.171626) (xy 56.091224 -228.104355)
			(xy 56.063617 -228.03375) (xy 56.043671 -227.960609) (xy 56.031612 -227.885764) (xy 56.027577 -227.81006)
			(xy 54.911498 -227.81006) (xy 54.910994 -227.847966) (xy 54.902935 -227.923347) (xy 54.88691 -227.997445)
			(xy 54.8631 -228.06942) (xy 54.831774 -228.138456) (xy 54.793287 -228.203771) (xy 54.748076 -228.264626)
			(xy 54.696652 -228.32033) (xy 54.639599 -228.370252) (xy 54.577563 -228.413827) (xy 54.511246 -228.450562)
			(xy 54.4414 -228.480039) (xy 54.368817 -228.501925) (xy 54.294319 -228.515972) (xy 54.218749 -228.522021)
			(xy 54.142965 -228.520002) (xy 54.067825 -228.50994) (xy 53.99418 -228.491948) (xy 53.922864 -228.46623)
			(xy 53.854687 -228.433078) (xy 53.790419 -228.392866) (xy 53.73079 -228.346051) (xy 53.676474 -228.293163)
			(xy 53.628088 -228.234801) (xy 53.58618 -228.171626) (xy 53.551224 -228.104355) (xy 53.523617 -228.03375)
			(xy 53.503671 -227.960609) (xy 53.491612 -227.885764) (xy 53.487577 -227.81006) (xy 52.371498 -227.81006)
			(xy 52.370994 -227.847966) (xy 52.362935 -227.923347) (xy 52.34691 -227.997445) (xy 52.3231 -228.06942)
			(xy 52.291774 -228.138456) (xy 52.253287 -228.203771) (xy 52.208076 -228.264626) (xy 52.156652 -228.32033)
			(xy 52.099599 -228.370252) (xy 52.037563 -228.413827) (xy 51.971246 -228.450562) (xy 51.9014 -228.480039)
			(xy 51.828817 -228.501925) (xy 51.754319 -228.515972) (xy 51.678749 -228.522021) (xy 51.602965 -228.520002)
			(xy 51.527825 -228.50994) (xy 51.45418 -228.491948) (xy 51.382864 -228.46623) (xy 51.314687 -228.433078)
			(xy 51.250419 -228.392866) (xy 51.19079 -228.346051) (xy 51.136474 -228.293163) (xy 51.088088 -228.234801)
			(xy 51.04618 -228.171626) (xy 51.011224 -228.104355) (xy 50.983617 -228.03375) (xy 50.963671 -227.960609)
			(xy 50.951612 -227.885764) (xy 50.947577 -227.81006) (xy 49.831498 -227.81006) (xy 49.830994 -227.847966)
			(xy 49.822935 -227.923347) (xy 49.80691 -227.997445) (xy 49.7831 -228.06942) (xy 49.751774 -228.138456)
			(xy 49.713287 -228.203771) (xy 49.668076 -228.264626) (xy 49.616652 -228.32033) (xy 49.559599 -228.370252)
			(xy 49.497563 -228.413827) (xy 49.431246 -228.450562) (xy 49.3614 -228.480039) (xy 49.288817 -228.501925)
			(xy 49.214319 -228.515972) (xy 49.138749 -228.522021) (xy 49.062965 -228.520002) (xy 48.987825 -228.50994)
			(xy 48.91418 -228.491948) (xy 48.842864 -228.46623) (xy 48.774687 -228.433078) (xy 48.710419 -228.392866)
			(xy 48.65079 -228.346051) (xy 48.596474 -228.293163) (xy 48.548088 -228.234801) (xy 48.50618 -228.171626)
			(xy 48.471224 -228.104355) (xy 48.443617 -228.03375) (xy 48.423671 -227.960609) (xy 48.411612 -227.885764)
			(xy 48.407577 -227.81006) (xy 47.291498 -227.81006) (xy 47.290994 -227.847966) (xy 47.282935 -227.923347)
			(xy 47.26691 -227.997445) (xy 47.2431 -228.06942) (xy 47.211774 -228.138456) (xy 47.173287 -228.203771)
			(xy 47.128076 -228.264626) (xy 47.076652 -228.32033) (xy 47.019599 -228.370252) (xy 46.957563 -228.413827)
			(xy 46.891246 -228.450562) (xy 46.8214 -228.480039) (xy 46.748817 -228.501925) (xy 46.674319 -228.515972)
			(xy 46.598749 -228.522021) (xy 46.522965 -228.520002) (xy 46.447825 -228.50994) (xy 46.37418 -228.491948)
			(xy 46.302864 -228.46623) (xy 46.234687 -228.433078) (xy 46.170419 -228.392866) (xy 46.11079 -228.346051)
			(xy 46.056474 -228.293163) (xy 46.008088 -228.234801) (xy 45.96618 -228.171626) (xy 45.931224 -228.104355)
			(xy 45.903617 -228.03375) (xy 45.883671 -227.960609) (xy 45.871612 -227.885764) (xy 45.867577 -227.81006)
			(xy 44.751498 -227.81006) (xy 44.750994 -227.847966) (xy 44.742935 -227.923347) (xy 44.72691 -227.997445)
			(xy 44.7031 -228.06942) (xy 44.671774 -228.138456) (xy 44.633287 -228.203771) (xy 44.588076 -228.264626)
			(xy 44.536652 -228.32033) (xy 44.479599 -228.370252) (xy 44.417563 -228.413827) (xy 44.351246 -228.450562)
			(xy 44.2814 -228.480039) (xy 44.208817 -228.501925) (xy 44.134319 -228.515972) (xy 44.058749 -228.522021)
			(xy 43.982965 -228.520002) (xy 43.907825 -228.50994) (xy 43.83418 -228.491948) (xy 43.762864 -228.46623)
			(xy 43.694687 -228.433078) (xy 43.630419 -228.392866) (xy 43.57079 -228.346051) (xy 43.516474 -228.293163)
			(xy 43.468088 -228.234801) (xy 43.42618 -228.171626) (xy 43.391224 -228.104355) (xy 43.363617 -228.03375)
			(xy 43.343671 -227.960609) (xy 43.331612 -227.885764) (xy 43.327577 -227.81006) (xy 42.501239 -227.81006)
			(xy 42.515699 -227.820266) (xy 42.604766 -227.892723) (xy 42.688681 -227.971089) (xy 42.767054 -228.054998)
			(xy 42.839517 -228.14406) (xy 42.905734 -228.237859) (xy 42.965396 -228.335958) (xy 43.018225 -228.4379)
			(xy 43.063974 -228.543209) (xy 43.10243 -228.651394) (xy 43.133415 -228.761952) (xy 43.156782 -228.874366)
			(xy 43.172424 -228.988113) (xy 43.180268 -229.102661) (xy 43.180762 -229.16007) (xy 43.180576 -229.193253)
			(xy 43.177909 -229.259567) (xy 43.175428 -229.292658) (xy 43.170272 -229.350942) (xy 43.152948 -229.466671)
			(xy 43.127616 -229.580914) (xy 43.094401 -229.693119) (xy 43.053462 -229.802742) (xy 43.004999 -229.909253)
			(xy 42.949245 -230.012135) (xy 42.886471 -230.110891) (xy 42.816981 -230.205042) (xy 42.741111 -230.294132)
			(xy 42.659229 -230.377729) (xy 42.571732 -230.45543) (xy 42.500813 -230.51008) (xy 43.327577 -230.51008)
			(xy 43.331612 -230.434376) (xy 43.343671 -230.359531) (xy 43.363617 -230.28639) (xy 43.391224 -230.215785)
			(xy 43.42618 -230.148514) (xy 43.468088 -230.085339) (xy 43.516474 -230.026977) (xy 43.57079 -229.974089)
			(xy 43.630419 -229.927274) (xy 43.694687 -229.887062) (xy 43.762864 -229.85391) (xy 43.83418 -229.828192)
			(xy 43.907825 -229.8102) (xy 43.982965 -229.800138) (xy 44.058749 -229.798119) (xy 44.134319 -229.804168)
			(xy 44.208817 -229.818215) (xy 44.2814 -229.840101) (xy 44.351246 -229.869578) (xy 44.417563 -229.906313)
			(xy 44.479599 -229.949888) (xy 44.536652 -229.99981) (xy 44.588076 -230.055514) (xy 44.633287 -230.116369)
			(xy 44.671774 -230.181684) (xy 44.7031 -230.25072) (xy 44.72691 -230.322695) (xy 44.742935 -230.396793)
			(xy 44.750994 -230.472174) (xy 44.751498 -230.51008) (xy 45.867577 -230.51008) (xy 45.871612 -230.434376)
			(xy 45.883671 -230.359531) (xy 45.903617 -230.28639) (xy 45.931224 -230.215785) (xy 45.96618 -230.148514)
			(xy 46.008088 -230.085339) (xy 46.056474 -230.026977) (xy 46.11079 -229.974089) (xy 46.170419 -229.927274)
			(xy 46.234687 -229.887062) (xy 46.302864 -229.85391) (xy 46.37418 -229.828192) (xy 46.447825 -229.8102)
			(xy 46.522965 -229.800138) (xy 46.598749 -229.798119) (xy 46.674319 -229.804168) (xy 46.748817 -229.818215)
			(xy 46.8214 -229.840101) (xy 46.891246 -229.869578) (xy 46.957563 -229.906313) (xy 47.019599 -229.949888)
			(xy 47.076652 -229.99981) (xy 47.128076 -230.055514) (xy 47.173287 -230.116369) (xy 47.211774 -230.181684)
			(xy 47.2431 -230.25072) (xy 47.26691 -230.322695) (xy 47.282935 -230.396793) (xy 47.290994 -230.472174)
			(xy 47.291498 -230.51008) (xy 48.407577 -230.51008) (xy 48.411612 -230.434376) (xy 48.423671 -230.359531)
			(xy 48.443617 -230.28639) (xy 48.471224 -230.215785) (xy 48.50618 -230.148514) (xy 48.548088 -230.085339)
			(xy 48.596474 -230.026977) (xy 48.65079 -229.974089) (xy 48.710419 -229.927274) (xy 48.774687 -229.887062)
			(xy 48.842864 -229.85391) (xy 48.91418 -229.828192) (xy 48.987825 -229.8102) (xy 49.062965 -229.800138)
			(xy 49.138749 -229.798119) (xy 49.214319 -229.804168) (xy 49.288817 -229.818215) (xy 49.3614 -229.840101)
			(xy 49.431246 -229.869578) (xy 49.497563 -229.906313) (xy 49.559599 -229.949888) (xy 49.616652 -229.99981)
			(xy 49.668076 -230.055514) (xy 49.713287 -230.116369) (xy 49.751774 -230.181684) (xy 49.7831 -230.25072)
			(xy 49.80691 -230.322695) (xy 49.822935 -230.396793) (xy 49.830994 -230.472174) (xy 49.831498 -230.51008)
			(xy 50.947577 -230.51008) (xy 50.951612 -230.434376) (xy 50.963671 -230.359531) (xy 50.983617 -230.28639)
			(xy 51.011224 -230.215785) (xy 51.04618 -230.148514) (xy 51.088088 -230.085339) (xy 51.136474 -230.026977)
			(xy 51.19079 -229.974089) (xy 51.250419 -229.927274) (xy 51.314687 -229.887062) (xy 51.382864 -229.85391)
			(xy 51.45418 -229.828192) (xy 51.527825 -229.8102) (xy 51.602965 -229.800138) (xy 51.678749 -229.798119)
			(xy 51.754319 -229.804168) (xy 51.828817 -229.818215) (xy 51.9014 -229.840101) (xy 51.971246 -229.869578)
			(xy 52.037563 -229.906313) (xy 52.099599 -229.949888) (xy 52.156652 -229.99981) (xy 52.208076 -230.055514)
			(xy 52.253287 -230.116369) (xy 52.291774 -230.181684) (xy 52.3231 -230.25072) (xy 52.34691 -230.322695)
			(xy 52.362935 -230.396793) (xy 52.370994 -230.472174) (xy 52.371498 -230.51008) (xy 53.487577 -230.51008)
			(xy 53.491612 -230.434376) (xy 53.503671 -230.359531) (xy 53.523617 -230.28639) (xy 53.551224 -230.215785)
			(xy 53.58618 -230.148514) (xy 53.628088 -230.085339) (xy 53.676474 -230.026977) (xy 53.73079 -229.974089)
			(xy 53.790419 -229.927274) (xy 53.854687 -229.887062) (xy 53.922864 -229.85391) (xy 53.99418 -229.828192)
			(xy 54.067825 -229.8102) (xy 54.142965 -229.800138) (xy 54.218749 -229.798119) (xy 54.294319 -229.804168)
			(xy 54.368817 -229.818215) (xy 54.4414 -229.840101) (xy 54.511246 -229.869578) (xy 54.577563 -229.906313)
			(xy 54.639599 -229.949888) (xy 54.696652 -229.99981) (xy 54.748076 -230.055514) (xy 54.793287 -230.116369)
			(xy 54.831774 -230.181684) (xy 54.8631 -230.25072) (xy 54.88691 -230.322695) (xy 54.902935 -230.396793)
			(xy 54.910994 -230.472174) (xy 54.911498 -230.51008) (xy 56.027577 -230.51008) (xy 56.031612 -230.434376)
			(xy 56.043671 -230.359531) (xy 56.063617 -230.28639) (xy 56.091224 -230.215785) (xy 56.12618 -230.148514)
			(xy 56.168088 -230.085339) (xy 56.216474 -230.026977) (xy 56.27079 -229.974089) (xy 56.330419 -229.927274)
			(xy 56.394687 -229.887062) (xy 56.462864 -229.85391) (xy 56.53418 -229.828192) (xy 56.607825 -229.8102)
			(xy 56.682965 -229.800138) (xy 56.758749 -229.798119) (xy 56.834319 -229.804168) (xy 56.908817 -229.818215)
			(xy 56.9814 -229.840101) (xy 57.051246 -229.869578) (xy 57.117563 -229.906313) (xy 57.179599 -229.949888)
			(xy 57.236652 -229.99981) (xy 57.288076 -230.055514) (xy 57.333287 -230.116369) (xy 57.371774 -230.181684)
			(xy 57.4031 -230.25072) (xy 57.42691 -230.322695) (xy 57.442935 -230.396793) (xy 57.450994 -230.472174)
			(xy 57.451498 -230.51008) (xy 58.567577 -230.51008) (xy 58.571612 -230.434376) (xy 58.583671 -230.359531)
			(xy 58.603617 -230.28639) (xy 58.631224 -230.215785) (xy 58.66618 -230.148514) (xy 58.708088 -230.085339)
			(xy 58.756474 -230.026977) (xy 58.81079 -229.974089) (xy 58.870419 -229.927274) (xy 58.934687 -229.887062)
			(xy 59.002864 -229.85391) (xy 59.07418 -229.828192) (xy 59.147825 -229.8102) (xy 59.222965 -229.800138)
			(xy 59.298749 -229.798119) (xy 59.374319 -229.804168) (xy 59.448817 -229.818215) (xy 59.5214 -229.840101)
			(xy 59.591246 -229.869578) (xy 59.657563 -229.906313) (xy 59.719599 -229.949888) (xy 59.776652 -229.99981)
			(xy 59.828076 -230.055514) (xy 59.873287 -230.116369) (xy 59.911774 -230.181684) (xy 59.9431 -230.25072)
			(xy 59.96691 -230.322695) (xy 59.982935 -230.396793) (xy 59.990994 -230.472174) (xy 59.991498 -230.51008)
			(xy 61.107577 -230.51008) (xy 61.111612 -230.434376) (xy 61.123671 -230.359531) (xy 61.143617 -230.28639)
			(xy 61.171224 -230.215785) (xy 61.20618 -230.148514) (xy 61.248088 -230.085339) (xy 61.296474 -230.026977)
			(xy 61.35079 -229.974089) (xy 61.410419 -229.927274) (xy 61.474687 -229.887062) (xy 61.542864 -229.85391)
			(xy 61.61418 -229.828192) (xy 61.687825 -229.8102) (xy 61.762965 -229.800138) (xy 61.838749 -229.798119)
			(xy 61.914319 -229.804168) (xy 61.988817 -229.818215) (xy 62.0614 -229.840101) (xy 62.131246 -229.869578)
			(xy 62.197563 -229.906313) (xy 62.259599 -229.949888) (xy 62.316652 -229.99981) (xy 62.368076 -230.055514)
			(xy 62.413287 -230.116369) (xy 62.451774 -230.181684) (xy 62.4831 -230.25072) (xy 62.50691 -230.322695)
			(xy 62.522935 -230.396793) (xy 62.530994 -230.472174) (xy 62.531498 -230.51008) (xy 62.530994 -230.547986)
			(xy 62.522935 -230.623367) (xy 62.50691 -230.697465) (xy 62.4831 -230.76944) (xy 62.451774 -230.838476)
			(xy 62.413287 -230.903791) (xy 62.368076 -230.964646) (xy 62.316652 -231.02035) (xy 62.259599 -231.070272)
			(xy 62.197563 -231.113847) (xy 62.131246 -231.150582) (xy 62.0614 -231.180059) (xy 61.988817 -231.201945)
			(xy 61.914319 -231.215992) (xy 61.838749 -231.222041) (xy 61.762965 -231.220022) (xy 61.687825 -231.20996)
			(xy 61.61418 -231.191968) (xy 61.542864 -231.16625) (xy 61.474687 -231.133098) (xy 61.410419 -231.092886)
			(xy 61.35079 -231.046071) (xy 61.296474 -230.993183) (xy 61.248088 -230.934821) (xy 61.20618 -230.871646)
			(xy 61.171224 -230.804375) (xy 61.143617 -230.73377) (xy 61.123671 -230.660629) (xy 61.111612 -230.585784)
			(xy 61.107577 -230.51008) (xy 59.991498 -230.51008) (xy 59.990994 -230.547986) (xy 59.982935 -230.623367)
			(xy 59.96691 -230.697465) (xy 59.9431 -230.76944) (xy 59.911774 -230.838476) (xy 59.873287 -230.903791)
			(xy 59.828076 -230.964646) (xy 59.776652 -231.02035) (xy 59.719599 -231.070272) (xy 59.657563 -231.113847)
			(xy 59.591246 -231.150582) (xy 59.5214 -231.180059) (xy 59.448817 -231.201945) (xy 59.374319 -231.215992)
			(xy 59.298749 -231.222041) (xy 59.222965 -231.220022) (xy 59.147825 -231.20996) (xy 59.07418 -231.191968)
			(xy 59.002864 -231.16625) (xy 58.934687 -231.133098) (xy 58.870419 -231.092886) (xy 58.81079 -231.046071)
			(xy 58.756474 -230.993183) (xy 58.708088 -230.934821) (xy 58.66618 -230.871646) (xy 58.631224 -230.804375)
			(xy 58.603617 -230.73377) (xy 58.583671 -230.660629) (xy 58.571612 -230.585784) (xy 58.567577 -230.51008)
			(xy 57.451498 -230.51008) (xy 57.450994 -230.547986) (xy 57.442935 -230.623367) (xy 57.42691 -230.697465)
			(xy 57.4031 -230.76944) (xy 57.371774 -230.838476) (xy 57.333287 -230.903791) (xy 57.288076 -230.964646)
			(xy 57.236652 -231.02035) (xy 57.179599 -231.070272) (xy 57.117563 -231.113847) (xy 57.051246 -231.150582)
			(xy 56.9814 -231.180059) (xy 56.908817 -231.201945) (xy 56.834319 -231.215992) (xy 56.758749 -231.222041)
			(xy 56.682965 -231.220022) (xy 56.607825 -231.20996) (xy 56.53418 -231.191968) (xy 56.462864 -231.16625)
			(xy 56.394687 -231.133098) (xy 56.330419 -231.092886) (xy 56.27079 -231.046071) (xy 56.216474 -230.993183)
			(xy 56.168088 -230.934821) (xy 56.12618 -230.871646) (xy 56.091224 -230.804375) (xy 56.063617 -230.73377)
			(xy 56.043671 -230.660629) (xy 56.031612 -230.585784) (xy 56.027577 -230.51008) (xy 54.911498 -230.51008)
			(xy 54.910994 -230.547986) (xy 54.902935 -230.623367) (xy 54.88691 -230.697465) (xy 54.8631 -230.76944)
			(xy 54.831774 -230.838476) (xy 54.793287 -230.903791) (xy 54.748076 -230.964646) (xy 54.696652 -231.02035)
			(xy 54.639599 -231.070272) (xy 54.577563 -231.113847) (xy 54.511246 -231.150582) (xy 54.4414 -231.180059)
			(xy 54.368817 -231.201945) (xy 54.294319 -231.215992) (xy 54.218749 -231.222041) (xy 54.142965 -231.220022)
			(xy 54.067825 -231.20996) (xy 53.99418 -231.191968) (xy 53.922864 -231.16625) (xy 53.854687 -231.133098)
			(xy 53.790419 -231.092886) (xy 53.73079 -231.046071) (xy 53.676474 -230.993183) (xy 53.628088 -230.934821)
			(xy 53.58618 -230.871646) (xy 53.551224 -230.804375) (xy 53.523617 -230.73377) (xy 53.503671 -230.660629)
			(xy 53.491612 -230.585784) (xy 53.487577 -230.51008) (xy 52.371498 -230.51008) (xy 52.370994 -230.547986)
			(xy 52.362935 -230.623367) (xy 52.34691 -230.697465) (xy 52.3231 -230.76944) (xy 52.291774 -230.838476)
			(xy 52.253287 -230.903791) (xy 52.208076 -230.964646) (xy 52.156652 -231.02035) (xy 52.099599 -231.070272)
			(xy 52.037563 -231.113847) (xy 51.971246 -231.150582) (xy 51.9014 -231.180059) (xy 51.828817 -231.201945)
			(xy 51.754319 -231.215992) (xy 51.678749 -231.222041) (xy 51.602965 -231.220022) (xy 51.527825 -231.20996)
			(xy 51.45418 -231.191968) (xy 51.382864 -231.16625) (xy 51.314687 -231.133098) (xy 51.250419 -231.092886)
			(xy 51.19079 -231.046071) (xy 51.136474 -230.993183) (xy 51.088088 -230.934821) (xy 51.04618 -230.871646)
			(xy 51.011224 -230.804375) (xy 50.983617 -230.73377) (xy 50.963671 -230.660629) (xy 50.951612 -230.585784)
			(xy 50.947577 -230.51008) (xy 49.831498 -230.51008) (xy 49.830994 -230.547986) (xy 49.822935 -230.623367)
			(xy 49.80691 -230.697465) (xy 49.7831 -230.76944) (xy 49.751774 -230.838476) (xy 49.713287 -230.903791)
			(xy 49.668076 -230.964646) (xy 49.616652 -231.02035) (xy 49.559599 -231.070272) (xy 49.497563 -231.113847)
			(xy 49.431246 -231.150582) (xy 49.3614 -231.180059) (xy 49.288817 -231.201945) (xy 49.214319 -231.215992)
			(xy 49.138749 -231.222041) (xy 49.062965 -231.220022) (xy 48.987825 -231.20996) (xy 48.91418 -231.191968)
			(xy 48.842864 -231.16625) (xy 48.774687 -231.133098) (xy 48.710419 -231.092886) (xy 48.65079 -231.046071)
			(xy 48.596474 -230.993183) (xy 48.548088 -230.934821) (xy 48.50618 -230.871646) (xy 48.471224 -230.804375)
			(xy 48.443617 -230.73377) (xy 48.423671 -230.660629) (xy 48.411612 -230.585784) (xy 48.407577 -230.51008)
			(xy 47.291498 -230.51008) (xy 47.290994 -230.547986) (xy 47.282935 -230.623367) (xy 47.26691 -230.697465)
			(xy 47.2431 -230.76944) (xy 47.211774 -230.838476) (xy 47.173287 -230.903791) (xy 47.128076 -230.964646)
			(xy 47.076652 -231.02035) (xy 47.019599 -231.070272) (xy 46.957563 -231.113847) (xy 46.891246 -231.150582)
			(xy 46.8214 -231.180059) (xy 46.748817 -231.201945) (xy 46.674319 -231.215992) (xy 46.598749 -231.222041)
			(xy 46.522965 -231.220022) (xy 46.447825 -231.20996) (xy 46.37418 -231.191968) (xy 46.302864 -231.16625)
			(xy 46.234687 -231.133098) (xy 46.170419 -231.092886) (xy 46.11079 -231.046071) (xy 46.056474 -230.993183)
			(xy 46.008088 -230.934821) (xy 45.96618 -230.871646) (xy 45.931224 -230.804375) (xy 45.903617 -230.73377)
			(xy 45.883671 -230.660629) (xy 45.871612 -230.585784) (xy 45.867577 -230.51008) (xy 44.751498 -230.51008)
			(xy 44.750994 -230.547986) (xy 44.742935 -230.623367) (xy 44.72691 -230.697465) (xy 44.7031 -230.76944)
			(xy 44.671774 -230.838476) (xy 44.633287 -230.903791) (xy 44.588076 -230.964646) (xy 44.536652 -231.02035)
			(xy 44.479599 -231.070272) (xy 44.417563 -231.113847) (xy 44.351246 -231.150582) (xy 44.2814 -231.180059)
			(xy 44.208817 -231.201945) (xy 44.134319 -231.215992) (xy 44.058749 -231.222041) (xy 43.982965 -231.220022)
			(xy 43.907825 -231.20996) (xy 43.83418 -231.191968) (xy 43.762864 -231.16625) (xy 43.694687 -231.133098)
			(xy 43.630419 -231.092886) (xy 43.57079 -231.046071) (xy 43.516474 -230.993183) (xy 43.468088 -230.934821)
			(xy 43.42618 -230.871646) (xy 43.391224 -230.804375) (xy 43.363617 -230.73377) (xy 43.343671 -230.660629)
			(xy 43.331612 -230.585784) (xy 43.327577 -230.51008) (xy 42.500813 -230.51008) (xy 42.479042 -230.526857)
			(xy 42.381609 -230.591665) (xy 42.279905 -230.64954) (xy 42.174422 -230.700202) (xy 42.065671 -230.743404)
			(xy 41.954179 -230.778939) (xy 41.840485 -230.806634) (xy 41.725141 -230.826354) (xy 41.608704 -230.838005)
			(xy 41.491739 -230.84153) (xy 41.374812 -230.836912) (xy 41.258489 -230.824173) (xy 41.143334 -230.803375)
			(xy 41.029905 -230.774618) (xy 40.91875 -230.738042) (xy 40.810407 -230.693825) (xy 40.705403 -230.642179)
			(xy 40.604244 -230.583356) (xy 40.507421 -230.51764) (xy 40.415403 -230.445349) (xy 40.328636 -230.366834)
			(xy 40.247539 -230.282474) (xy 40.172506 -230.192679) (xy 40.103899 -230.097883) (xy 40.042051 -229.998544)
			(xy 39.987262 -229.895145) (xy 39.939796 -229.788186) (xy 39.899884 -229.678185) (xy 39.86772 -229.565674)
			(xy 39.843457 -229.451199) (xy 39.827215 -229.335313) (xy 39.819072 -229.218579) (xy 39.818564 -229.16007)
			(xy 36.341678 -229.16007) (xy 36.361593 -229.192234) (xy 36.400327 -229.270023) (xy 36.431719 -229.351055)
			(xy 36.4555 -229.434637) (xy 36.471468 -229.520057) (xy 36.479486 -229.606586) (xy 36.479988 -229.650036)
			(xy 36.479486 -229.693486) (xy 36.471468 -229.780015) (xy 36.4555 -229.865435) (xy 36.431719 -229.949017)
			(xy 36.400327 -230.030049) (xy 36.361593 -230.107838) (xy 36.315846 -230.181722) (xy 36.263477 -230.251069)
			(xy 36.204933 -230.315289) (xy 36.140713 -230.373833) (xy 36.071366 -230.426202) (xy 35.997482 -230.471949)
			(xy 35.919693 -230.510683) (xy 35.838661 -230.542075) (xy 35.755079 -230.565856) (xy 35.669659 -230.581824)
			(xy 35.58313 -230.589842) (xy 35.49623 -230.589842) (xy 35.409701 -230.581824) (xy 35.324281 -230.565856)
			(xy 35.240699 -230.542075) (xy 35.159667 -230.510683) (xy 35.081878 -230.471949) (xy 35.007994 -230.426202)
			(xy 34.938647 -230.373833) (xy 34.874427 -230.315289) (xy 34.815883 -230.251069) (xy 34.763514 -230.181722)
			(xy 34.717767 -230.107838) (xy 34.679033 -230.030049) (xy 34.647641 -229.949017) (xy 34.62386 -229.865435)
			(xy 34.607892 -229.780015) (xy 34.599874 -229.693486) (xy 31.399486 -229.693486) (xy 31.391468 -229.780015)
			(xy 31.3755 -229.865435) (xy 31.351719 -229.949017) (xy 31.320327 -230.030049) (xy 31.281593 -230.107838)
			(xy 31.235846 -230.181722) (xy 31.183477 -230.251069) (xy 31.124933 -230.315289) (xy 31.060713 -230.373833)
			(xy 30.991366 -230.426202) (xy 30.917482 -230.471949) (xy 30.839693 -230.510683) (xy 30.758661 -230.542075)
			(xy 30.675079 -230.565856) (xy 30.589659 -230.581824) (xy 30.50313 -230.589842) (xy 30.41623 -230.589842)
			(xy 30.329701 -230.581824) (xy 30.244281 -230.565856) (xy 30.160699 -230.542075) (xy 30.079667 -230.510683)
			(xy 30.001878 -230.471949) (xy 29.927994 -230.426202) (xy 29.858647 -230.373833) (xy 29.794427 -230.315289)
			(xy 29.735883 -230.251069) (xy 29.683514 -230.181722) (xy 29.637767 -230.107838) (xy 29.599033 -230.030049)
			(xy 29.567641 -229.949017) (xy 29.54386 -229.865435) (xy 29.527892 -229.780015) (xy 29.519874 -229.693486)
			(xy 25.95853 -229.693486) (xy 20.206462 -235.445554) (xy 22.806658 -235.445554) (xy 22.810729 -235.389932)
			(xy 22.822855 -235.335495) (xy 22.842778 -235.283404) (xy 22.870074 -235.234769) (xy 22.90416 -235.190626)
			(xy 22.944309 -235.151917) (xy 22.989667 -235.119466) (xy 23.039267 -235.093965) (xy 23.092051 -235.075958)
			(xy 23.146894 -235.065828) (xy 23.202628 -235.063791) (xy 23.258065 -235.069891) (xy 23.312022 -235.083997)
			(xy 23.363351 -235.105809) (xy 23.410957 -235.134863) (xy 23.453825 -235.170538) (xy 23.491042 -235.212075)
			(xy 23.521815 -235.258588) (xy 23.545487 -235.309085) (xy 23.561555 -235.362492) (xy 23.569675 -235.417668)
			(xy 23.570184 -235.445554) (xy 23.569675 -235.47344) (xy 23.561555 -235.528616) (xy 23.545487 -235.582023)
			(xy 23.521815 -235.63252) (xy 23.491042 -235.679033) (xy 23.453825 -235.72057) (xy 23.410957 -235.756245)
			(xy 23.363351 -235.785299) (xy 23.312022 -235.807111) (xy 23.258065 -235.821217) (xy 23.202628 -235.827317)
			(xy 23.146894 -235.82528) (xy 23.092051 -235.81515) (xy 23.039267 -235.797143) (xy 22.989667 -235.771642)
			(xy 22.944309 -235.739191) (xy 22.90416 -235.700482) (xy 22.870074 -235.656339) (xy 22.842778 -235.607704)
			(xy 22.822855 -235.555613) (xy 22.810729 -235.501176) (xy 22.806658 -235.445554) (xy 20.206462 -235.445554)
			(xy 17.69745 -237.954566) (xy 44.324776 -237.954566) (xy 44.328847 -237.898944) (xy 44.340973 -237.844507)
			(xy 44.360896 -237.792416) (xy 44.388192 -237.743781) (xy 44.422278 -237.699638) (xy 44.462427 -237.660929)
			(xy 44.507785 -237.628478) (xy 44.557385 -237.602977) (xy 44.610169 -237.58497) (xy 44.665012 -237.57484)
			(xy 44.720746 -237.572803) (xy 44.776183 -237.578903) (xy 44.83014 -237.593009) (xy 44.881469 -237.614821)
			(xy 44.929075 -237.643875) (xy 44.971943 -237.67955) (xy 45.00916 -237.721087) (xy 45.039933 -237.7676)
			(xy 45.063605 -237.818097) (xy 45.079673 -237.871504) (xy 45.087793 -237.92668) (xy 45.088302 -237.954566)
			(xy 45.087793 -237.982452) (xy 45.079673 -238.037628) (xy 45.063605 -238.091035) (xy 45.039933 -238.141532)
			(xy 45.00916 -238.188045) (xy 44.971943 -238.229582) (xy 44.929075 -238.265257) (xy 44.881469 -238.294311)
			(xy 44.83014 -238.316123) (xy 44.776183 -238.330229) (xy 44.720746 -238.336329) (xy 44.665012 -238.334292)
			(xy 44.610169 -238.324162) (xy 44.557385 -238.306155) (xy 44.507785 -238.280654) (xy 44.462427 -238.248203)
			(xy 44.422278 -238.209494) (xy 44.388192 -238.165351) (xy 44.360896 -238.116716) (xy 44.340973 -238.064625)
			(xy 44.328847 -238.010188) (xy 44.324776 -237.954566) (xy 17.69745 -237.954566) (xy 15.739618 -239.912398)
			(xy 44.319188 -239.912398) (xy 44.323259 -239.856776) (xy 44.335385 -239.802339) (xy 44.355308 -239.750248)
			(xy 44.382604 -239.701613) (xy 44.41669 -239.65747) (xy 44.456839 -239.618761) (xy 44.502197 -239.58631)
			(xy 44.551797 -239.560809) (xy 44.604581 -239.542802) (xy 44.659424 -239.532672) (xy 44.715158 -239.530635)
			(xy 44.770595 -239.536735) (xy 44.824552 -239.550841) (xy 44.875881 -239.572653) (xy 44.923487 -239.601707)
			(xy 44.966355 -239.637382) (xy 45.003572 -239.678919) (xy 45.034345 -239.725432) (xy 45.058017 -239.775929)
			(xy 45.074085 -239.829336) (xy 45.082205 -239.884512) (xy 45.082714 -239.912398) (xy 45.082205 -239.940284)
			(xy 45.074085 -239.99546) (xy 45.058017 -240.048867) (xy 45.034345 -240.099364) (xy 45.003572 -240.145877)
			(xy 44.966355 -240.187414) (xy 44.923487 -240.223089) (xy 44.875881 -240.252143) (xy 44.824552 -240.273955)
			(xy 44.770595 -240.288061) (xy 44.715158 -240.294161) (xy 44.659424 -240.292124) (xy 44.604581 -240.281994)
			(xy 44.551797 -240.263987) (xy 44.502197 -240.238486) (xy 44.456839 -240.206035) (xy 44.41669 -240.167326)
			(xy 44.382604 -240.123183) (xy 44.355308 -240.074548) (xy 44.335385 -240.022457) (xy 44.323259 -239.96802)
			(xy 44.319188 -239.912398) (xy 15.739618 -239.912398) (xy 14.775942 -240.876074) (xy 46.426118 -240.876074)
			(xy 46.430189 -240.820452) (xy 46.442315 -240.766015) (xy 46.462238 -240.713924) (xy 46.489534 -240.665289)
			(xy 46.52362 -240.621146) (xy 46.563769 -240.582437) (xy 46.609127 -240.549986) (xy 46.658727 -240.524485)
			(xy 46.711511 -240.506478) (xy 46.766354 -240.496348) (xy 46.822088 -240.494311) (xy 46.877525 -240.500411)
			(xy 46.931482 -240.514517) (xy 46.982811 -240.536329) (xy 47.030417 -240.565383) (xy 47.073285 -240.601058)
			(xy 47.099094 -240.629863) (xy 49.037484 -240.629863) (xy 49.037484 -240.548753) (xy 49.045434 -240.468034)
			(xy 49.061257 -240.388483) (xy 49.084802 -240.310867) (xy 49.115841 -240.235931) (xy 49.154076 -240.164399)
			(xy 49.199138 -240.096959) (xy 49.250593 -240.03426) (xy 49.307946 -239.976907) (xy 49.370645 -239.925452)
			(xy 49.438085 -239.88039) (xy 49.509617 -239.842155) (xy 49.584553 -239.811116) (xy 49.662169 -239.787571)
			(xy 49.74172 -239.771748) (xy 49.822439 -239.763798) (xy 49.903549 -239.763798) (xy 49.984268 -239.771748)
			(xy 50.063819 -239.787571) (xy 50.141435 -239.811116) (xy 50.216371 -239.842155) (xy 50.287903 -239.88039)
			(xy 50.355343 -239.925452) (xy 50.418042 -239.976907) (xy 50.475395 -240.03426) (xy 50.52685 -240.096959)
			(xy 50.571912 -240.164399) (xy 50.610147 -240.235931) (xy 50.641186 -240.310867) (xy 50.664731 -240.388483)
			(xy 50.680554 -240.468034) (xy 50.688504 -240.548753) (xy 50.689002 -240.589308) (xy 50.688504 -240.629863)
			(xy 52.537604 -240.629863) (xy 52.537604 -240.548753) (xy 52.545554 -240.468034) (xy 52.561377 -240.388483)
			(xy 52.584922 -240.310867) (xy 52.615961 -240.235931) (xy 52.654196 -240.164399) (xy 52.699258 -240.096959)
			(xy 52.750713 -240.03426) (xy 52.808066 -239.976907) (xy 52.870765 -239.925452) (xy 52.938205 -239.88039)
			(xy 53.009737 -239.842155) (xy 53.084673 -239.811116) (xy 53.162289 -239.787571) (xy 53.24184 -239.771748)
			(xy 53.322559 -239.763798) (xy 53.403669 -239.763798) (xy 53.484388 -239.771748) (xy 53.563939 -239.787571)
			(xy 53.641555 -239.811116) (xy 53.716491 -239.842155) (xy 53.788023 -239.88039) (xy 53.855463 -239.925452)
			(xy 53.918162 -239.976907) (xy 53.975515 -240.03426) (xy 54.02697 -240.096959) (xy 54.072032 -240.164399)
			(xy 54.110267 -240.235931) (xy 54.141306 -240.310867) (xy 54.164851 -240.388483) (xy 54.180674 -240.468034)
			(xy 54.188624 -240.548753) (xy 54.189122 -240.589308) (xy 54.188624 -240.629863) (xy 54.180674 -240.710582)
			(xy 54.164851 -240.790133) (xy 54.141306 -240.867749) (xy 54.110267 -240.942685) (xy 54.072032 -241.014217)
			(xy 54.02697 -241.081657) (xy 53.975515 -241.144356) (xy 53.918162 -241.201709) (xy 53.855463 -241.253164)
			(xy 53.788023 -241.298226) (xy 53.716491 -241.336461) (xy 53.641555 -241.3675) (xy 53.563939 -241.391045)
			(xy 53.484388 -241.406868) (xy 53.403669 -241.414818) (xy 53.322559 -241.414818) (xy 53.24184 -241.406868)
			(xy 53.162289 -241.391045) (xy 53.084673 -241.3675) (xy 53.009737 -241.336461) (xy 52.938205 -241.298226)
			(xy 52.870765 -241.253164) (xy 52.808066 -241.201709) (xy 52.750713 -241.144356) (xy 52.699258 -241.081657)
			(xy 52.654196 -241.014217) (xy 52.615961 -240.942685) (xy 52.584922 -240.867749) (xy 52.561377 -240.790133)
			(xy 52.545554 -240.710582) (xy 52.537604 -240.629863) (xy 50.688504 -240.629863) (xy 50.680554 -240.710582)
			(xy 50.664731 -240.790133) (xy 50.641186 -240.867749) (xy 50.610147 -240.942685) (xy 50.571912 -241.014217)
			(xy 50.52685 -241.081657) (xy 50.475395 -241.144356) (xy 50.418042 -241.201709) (xy 50.355343 -241.253164)
			(xy 50.287903 -241.298226) (xy 50.216371 -241.336461) (xy 50.141435 -241.3675) (xy 50.063819 -241.391045)
			(xy 49.984268 -241.406868) (xy 49.903549 -241.414818) (xy 49.822439 -241.414818) (xy 49.74172 -241.406868)
			(xy 49.662169 -241.391045) (xy 49.584553 -241.3675) (xy 49.509617 -241.336461) (xy 49.438085 -241.298226)
			(xy 49.370645 -241.253164) (xy 49.307946 -241.201709) (xy 49.250593 -241.144356) (xy 49.199138 -241.081657)
			(xy 49.154076 -241.014217) (xy 49.115841 -240.942685) (xy 49.084802 -240.867749) (xy 49.061257 -240.790133)
			(xy 49.045434 -240.710582) (xy 49.037484 -240.629863) (xy 47.099094 -240.629863) (xy 47.110502 -240.642595)
			(xy 47.141275 -240.689108) (xy 47.164947 -240.739605) (xy 47.181015 -240.793012) (xy 47.189135 -240.848188)
			(xy 47.189644 -240.876074) (xy 47.189135 -240.90396) (xy 47.181015 -240.959136) (xy 47.164947 -241.012543)
			(xy 47.141275 -241.06304) (xy 47.110502 -241.109553) (xy 47.073285 -241.15109) (xy 47.030417 -241.186765)
			(xy 46.982811 -241.215819) (xy 46.931482 -241.237631) (xy 46.877525 -241.251737) (xy 46.822088 -241.257837)
			(xy 46.766354 -241.2558) (xy 46.711511 -241.24567) (xy 46.658727 -241.227663) (xy 46.609127 -241.202162)
			(xy 46.563769 -241.169711) (xy 46.52362 -241.131002) (xy 46.489534 -241.086859) (xy 46.462238 -241.038224)
			(xy 46.442315 -240.986133) (xy 46.430189 -240.931696) (xy 46.426118 -240.876074) (xy 14.775942 -240.876074)
			(xy 13.728726 -241.92329) (xy 58.378193 -241.92329) (xy 58.382082 -241.868937) (xy 58.393667 -241.81569)
			(xy 58.412712 -241.764633) (xy 58.438831 -241.716808) (xy 58.471489 -241.673186) (xy 58.510024 -241.634656)
			(xy 58.55365 -241.602003) (xy 58.60148 -241.575891) (xy 58.652538 -241.556853) (xy 58.705787 -241.545275)
			(xy 58.760141 -241.541393) (xy 58.814495 -241.545286) (xy 58.867741 -241.556876) (xy 58.918795 -241.575926)
			(xy 58.966619 -241.602048) (xy 58.988706 -241.618008) (xy 59.007718 -241.631604) (xy 59.049601 -241.652336)
			(xy 59.094569 -241.665062) (xy 59.141106 -241.669352) (xy 59.187643 -241.665062) (xy 59.232611 -241.652336)
			(xy 59.274494 -241.631604) (xy 59.293506 -241.618008) (xy 59.315579 -241.602027) (xy 59.363405 -241.575905)
			(xy 59.414462 -241.556856) (xy 59.46771 -241.545267) (xy 59.522066 -241.541374) (xy 59.576422 -241.545257)
			(xy 59.629672 -241.556837) (xy 59.680733 -241.575877) (xy 59.728563 -241.60199) (xy 59.772191 -241.634645)
			(xy 59.810727 -241.673176) (xy 59.843386 -241.7168) (xy 59.869505 -241.764627) (xy 59.888551 -241.815686)
			(xy 59.900137 -241.868935) (xy 59.904026 -241.92329) (xy 60.264885 -241.92329) (xy 60.268775 -241.868935)
			(xy 60.28036 -241.815686) (xy 60.299407 -241.764629) (xy 60.325526 -241.716802) (xy 60.358186 -241.673179)
			(xy 60.396722 -241.634648) (xy 60.44035 -241.601995) (xy 60.488181 -241.575883) (xy 60.539242 -241.556844)
			(xy 60.592492 -241.545267) (xy 60.646848 -241.541385) (xy 60.701203 -241.54528) (xy 60.75445 -241.556871)
			(xy 60.805506 -241.575923) (xy 60.853331 -241.602046) (xy 60.875418 -241.618008) (xy 60.89443 -241.631604)
			(xy 60.936313 -241.652336) (xy 60.981281 -241.665062) (xy 61.027818 -241.669352) (xy 61.074355 -241.665062)
			(xy 61.119323 -241.652336) (xy 61.161206 -241.631604) (xy 61.180218 -241.618008) (xy 61.202291 -241.602028)
			(xy 61.250116 -241.575908) (xy 61.301172 -241.55686) (xy 61.354419 -241.545273) (xy 61.408773 -241.541381)
			(xy 61.463127 -241.545265) (xy 61.516376 -241.556845) (xy 61.567434 -241.575885) (xy 61.615263 -241.601998)
			(xy 61.658889 -241.634653) (xy 61.697423 -241.673183) (xy 61.730082 -241.716806) (xy 61.756199 -241.764632)
			(xy 61.775245 -241.815689) (xy 61.78683 -241.868936) (xy 61.790719 -241.92329) (xy 61.786832 -241.977645)
			(xy 61.77525 -242.030893) (xy 61.756207 -242.08195) (xy 61.730092 -242.129778) (xy 61.697436 -242.173402)
			(xy 61.658903 -242.211935) (xy 61.615279 -242.244591) (xy 61.567452 -242.270707) (xy 61.516394 -242.28975)
			(xy 61.463146 -242.301332) (xy 61.408792 -242.305219) (xy 61.354438 -242.30133) (xy 61.30119 -242.289745)
			(xy 61.250133 -242.2707) (xy 61.202307 -242.244582) (xy 61.180218 -242.228624) (xy 61.161206 -242.215028)
			(xy 61.119323 -242.194296) (xy 61.074355 -242.18157) (xy 61.027818 -242.17728) (xy 60.981281 -242.18157)
			(xy 60.936313 -242.194296) (xy 60.89443 -242.215028) (xy 60.875418 -242.228624) (xy 60.853314 -242.244564)
			(xy 60.805489 -242.270685) (xy 60.754432 -242.289734) (xy 60.701184 -242.301323) (xy 60.646829 -242.305215)
			(xy 60.592473 -242.301331) (xy 60.539223 -242.28975) (xy 60.488164 -242.270709) (xy 60.440334 -242.244595)
			(xy 60.396708 -242.211939) (xy 60.358173 -242.173407) (xy 60.325515 -242.129782) (xy 60.299399 -242.081954)
			(xy 60.280355 -242.030895) (xy 60.268772 -241.977646) (xy 60.264885 -241.92329) (xy 59.904026 -241.92329)
			(xy 59.900139 -241.977646) (xy 59.888557 -242.030896) (xy 59.869513 -242.081955) (xy 59.843397 -242.129784)
			(xy 59.810739 -242.173409) (xy 59.772205 -242.211943) (xy 59.72858 -242.2446) (xy 59.68075 -242.270715)
			(xy 59.629691 -242.289758) (xy 59.576441 -242.30134) (xy 59.522085 -242.305226) (xy 59.467729 -242.301336)
			(xy 59.41448 -242.28975) (xy 59.363423 -242.270703) (xy 59.315595 -242.244583) (xy 59.293506 -242.228624)
			(xy 59.274494 -242.215028) (xy 59.232611 -242.194296) (xy 59.187643 -242.18157) (xy 59.141106 -242.17728)
			(xy 59.094569 -242.18157) (xy 59.049601 -242.194296) (xy 59.007718 -242.215028) (xy 58.988706 -242.228624)
			(xy 58.966603 -242.244563) (xy 58.918778 -242.270682) (xy 58.867722 -242.28973) (xy 58.814476 -242.301317)
			(xy 58.760122 -242.305207) (xy 58.705768 -242.301323) (xy 58.65252 -242.289742) (xy 58.601462 -242.270701)
			(xy 58.553634 -242.244587) (xy 58.51001 -242.211931) (xy 58.471477 -242.1734) (xy 58.43882 -242.129776)
			(xy 58.412704 -242.081949) (xy 58.393662 -242.030892) (xy 58.382079 -241.977644) (xy 58.378193 -241.92329)
			(xy 13.728726 -241.92329) (xy 12.83716 -242.814856) (xy 44.210476 -242.814856) (xy 44.214547 -242.759234)
			(xy 44.226673 -242.704797) (xy 44.246596 -242.652706) (xy 44.273892 -242.604071) (xy 44.307978 -242.559928)
			(xy 44.348127 -242.521219) (xy 44.393485 -242.488768) (xy 44.443085 -242.463267) (xy 44.495869 -242.44526)
			(xy 44.550712 -242.43513) (xy 44.606446 -242.433093) (xy 44.661883 -242.439193) (xy 44.71584 -242.453299)
			(xy 44.767169 -242.475111) (xy 44.814775 -242.504165) (xy 44.857643 -242.53984) (xy 44.89486 -242.581377)
			(xy 44.925633 -242.62789) (xy 44.949305 -242.678387) (xy 44.965373 -242.731794) (xy 44.973493 -242.78697)
			(xy 44.974002 -242.814856) (xy 44.973493 -242.842742) (xy 44.965373 -242.897918) (xy 44.953835 -242.936268)
			(xy 73.581258 -242.936268) (xy 73.585329 -242.880646) (xy 73.597455 -242.826209) (xy 73.617378 -242.774118)
			(xy 73.644674 -242.725483) (xy 73.67876 -242.68134) (xy 73.718909 -242.642631) (xy 73.764267 -242.61018)
			(xy 73.813867 -242.584679) (xy 73.866651 -242.566672) (xy 73.921494 -242.556542) (xy 73.977228 -242.554505)
			(xy 74.032665 -242.560605) (xy 74.086622 -242.574711) (xy 74.137951 -242.596523) (xy 74.185557 -242.625577)
			(xy 74.228425 -242.661252) (xy 74.265642 -242.702789) (xy 74.296415 -242.749302) (xy 74.320087 -242.799799)
			(xy 74.336155 -242.853206) (xy 74.344275 -242.908382) (xy 74.344784 -242.936268) (xy 74.769978 -242.936268)
			(xy 74.774049 -242.880646) (xy 74.786175 -242.826209) (xy 74.806098 -242.774118) (xy 74.833394 -242.725483)
			(xy 74.86748 -242.68134) (xy 74.907629 -242.642631) (xy 74.952987 -242.61018) (xy 75.002587 -242.584679)
			(xy 75.055371 -242.566672) (xy 75.110214 -242.556542) (xy 75.165948 -242.554505) (xy 75.221385 -242.560605)
			(xy 75.275342 -242.574711) (xy 75.326671 -242.596523) (xy 75.374277 -242.625577) (xy 75.417145 -242.661252)
			(xy 75.454362 -242.702789) (xy 75.485135 -242.749302) (xy 75.508807 -242.799799) (xy 75.524875 -242.853206)
			(xy 75.532995 -242.908382) (xy 75.533504 -242.936268) (xy 75.532995 -242.964154) (xy 75.524875 -243.01933)
			(xy 75.508807 -243.072737) (xy 75.485135 -243.123234) (xy 75.454362 -243.169747) (xy 75.417145 -243.211284)
			(xy 75.374277 -243.246959) (xy 75.326671 -243.276013) (xy 75.275342 -243.297825) (xy 75.221385 -243.311931)
			(xy 75.165948 -243.318031) (xy 75.110214 -243.315994) (xy 75.055371 -243.305864) (xy 75.002587 -243.287857)
			(xy 74.952987 -243.262356) (xy 74.907629 -243.229905) (xy 74.86748 -243.191196) (xy 74.833394 -243.147053)
			(xy 74.806098 -243.098418) (xy 74.786175 -243.046327) (xy 74.774049 -242.99189) (xy 74.769978 -242.936268)
			(xy 74.344784 -242.936268) (xy 74.344275 -242.964154) (xy 74.336155 -243.01933) (xy 74.320087 -243.072737)
			(xy 74.296415 -243.123234) (xy 74.265642 -243.169747) (xy 74.228425 -243.211284) (xy 74.185557 -243.246959)
			(xy 74.137951 -243.276013) (xy 74.086622 -243.297825) (xy 74.032665 -243.311931) (xy 73.977228 -243.318031)
			(xy 73.921494 -243.315994) (xy 73.866651 -243.305864) (xy 73.813867 -243.287857) (xy 73.764267 -243.262356)
			(xy 73.718909 -243.229905) (xy 73.67876 -243.191196) (xy 73.644674 -243.147053) (xy 73.617378 -243.098418)
			(xy 73.597455 -243.046327) (xy 73.585329 -242.99189) (xy 73.581258 -242.936268) (xy 44.953835 -242.936268)
			(xy 44.949305 -242.951325) (xy 44.925633 -243.001822) (xy 44.89486 -243.048335) (xy 44.857643 -243.089872)
			(xy 44.814775 -243.125547) (xy 44.767169 -243.154601) (xy 44.71584 -243.176413) (xy 44.661883 -243.190519)
			(xy 44.606446 -243.196619) (xy 44.550712 -243.194582) (xy 44.495869 -243.184452) (xy 44.443085 -243.166445)
			(xy 44.393485 -243.140944) (xy 44.348127 -243.108493) (xy 44.307978 -243.069784) (xy 44.273892 -243.025641)
			(xy 44.246596 -242.977006) (xy 44.226673 -242.924915) (xy 44.214547 -242.870478) (xy 44.210476 -242.814856)
			(xy 12.83716 -242.814856) (xy 11.895141 -243.756875) (xy 58.378214 -243.756875) (xy 58.382105 -243.702524)
			(xy 58.393691 -243.64928) (xy 58.412738 -243.598228) (xy 58.438856 -243.550406) (xy 58.471515 -243.506788)
			(xy 58.51005 -243.468262) (xy 58.553675 -243.435612) (xy 58.601502 -243.409504) (xy 58.652559 -243.390468)
			(xy 58.705805 -243.378893) (xy 58.760157 -243.375014) (xy 58.814507 -243.378909) (xy 58.86775 -243.3905)
			(xy 58.918801 -243.409551) (xy 58.966621 -243.435673) (xy 58.988706 -243.451634) (xy 59.007718 -243.46523)
			(xy 59.049601 -243.485962) (xy 59.094569 -243.498688) (xy 59.141106 -243.502978) (xy 59.187643 -243.498688)
			(xy 59.232611 -243.485962) (xy 59.274494 -243.46523) (xy 59.293506 -243.451634) (xy 59.315555 -243.435618)
			(xy 59.363382 -243.409493) (xy 59.414441 -243.39044) (xy 59.467692 -243.378849) (xy 59.52205 -243.374953)
			(xy 59.57641 -243.378834) (xy 59.629663 -243.390412) (xy 59.680727 -243.409451) (xy 59.728561 -243.435564)
			(xy 59.772193 -243.468219) (xy 59.810732 -243.506751) (xy 59.843395 -243.550375) (xy 59.869518 -243.598205)
			(xy 59.888567 -243.649265) (xy 59.900155 -243.702516) (xy 59.904047 -243.756875) (xy 60.264906 -243.756875)
			(xy 60.268798 -243.702522) (xy 60.280385 -243.649277) (xy 60.299432 -243.598223) (xy 60.325552 -243.5504)
			(xy 60.358212 -243.506781) (xy 60.396748 -243.468254) (xy 60.440374 -243.435604) (xy 60.488204 -243.409495)
			(xy 60.539262 -243.39046) (xy 60.59251 -243.378885) (xy 60.646863 -243.375006) (xy 60.701215 -243.378903)
			(xy 60.754459 -243.390496) (xy 60.805512 -243.409548) (xy 60.853332 -243.435672) (xy 60.875418 -243.451634)
			(xy 60.89443 -243.46523) (xy 60.936313 -243.485962) (xy 60.981281 -243.498688) (xy 61.027818 -243.502978)
			(xy 61.074355 -243.498688) (xy 61.119323 -243.485962) (xy 61.161206 -243.46523) (xy 61.180218 -243.451634)
			(xy 61.202266 -243.435619) (xy 61.250093 -243.409496) (xy 61.301151 -243.390445) (xy 61.3544 -243.378855)
			(xy 61.408757 -243.374961) (xy 61.463115 -243.378842) (xy 61.516367 -243.390421) (xy 61.567429 -243.40946)
			(xy 61.615261 -243.435572) (xy 61.658891 -243.468227) (xy 61.697429 -243.506758) (xy 61.730091 -243.550381)
			(xy 61.756212 -243.598209) (xy 61.77526 -243.649268) (xy 61.786848 -243.702518) (xy 61.790739 -243.756875)
			(xy 62.506041 -243.756875) (xy 62.509932 -243.70253) (xy 62.521516 -243.649293) (xy 62.54056 -243.598246)
			(xy 62.566674 -243.550429) (xy 62.599328 -243.506815) (xy 62.637857 -243.468292) (xy 62.681476 -243.435644)
			(xy 62.729296 -243.409537) (xy 62.780346 -243.390501) (xy 62.833586 -243.378924) (xy 62.88793 -243.375041)
			(xy 62.942275 -243.378932) (xy 62.995512 -243.390518) (xy 63.046559 -243.409562) (xy 63.094376 -243.435677)
			(xy 63.11646 -243.451634) (xy 63.135472 -243.46523) (xy 63.177355 -243.485962) (xy 63.222323 -243.498688)
			(xy 63.26886 -243.502978) (xy 63.315397 -243.498688) (xy 63.360365 -243.485962) (xy 63.402248 -243.46523)
			(xy 63.42126 -243.451634) (xy 63.44331 -243.435614) (xy 63.49114 -243.409481) (xy 63.542204 -243.390423)
			(xy 63.59546 -243.378825) (xy 63.649824 -243.374926) (xy 63.70419 -243.378804) (xy 63.75745 -243.39038)
			(xy 63.808521 -243.409418) (xy 63.856362 -243.435532) (xy 63.9 -243.468189) (xy 63.938545 -243.506724)
			(xy 63.971213 -243.550352) (xy 63.99734 -243.598187) (xy 64.016392 -243.649252) (xy 64.027982 -243.70251)
			(xy 64.031874 -243.756875) (xy 64.409891 -243.756875) (xy 64.413782 -243.702519) (xy 64.425371 -243.64927)
			(xy 64.44442 -243.598213) (xy 64.470542 -243.550387) (xy 64.503205 -243.506765) (xy 64.541744 -243.468237)
			(xy 64.585374 -243.435586) (xy 64.633207 -243.409477) (xy 64.68427 -243.390441) (xy 64.737521 -243.378868)
			(xy 64.791878 -243.374991) (xy 64.846234 -243.37889) (xy 64.899481 -243.390486) (xy 64.950535 -243.409542)
			(xy 64.998358 -243.43567) (xy 65.020444 -243.451634) (xy 65.039456 -243.46523) (xy 65.081339 -243.485962)
			(xy 65.126307 -243.498688) (xy 65.172844 -243.502978) (xy 65.219381 -243.498688) (xy 65.264349 -243.485962)
			(xy 65.306232 -243.46523) (xy 65.325244 -243.451634) (xy 65.347292 -243.435621) (xy 65.395117 -243.409502)
			(xy 65.446172 -243.390455) (xy 65.499418 -243.378868) (xy 65.553772 -243.374976) (xy 65.608126 -243.37886)
			(xy 65.661374 -243.390439) (xy 65.712432 -243.409479) (xy 65.760261 -243.435591) (xy 65.803887 -243.468244)
			(xy 65.842421 -243.506773) (xy 65.875081 -243.550394) (xy 65.901199 -243.598219) (xy 65.920246 -243.649275)
			(xy 65.931833 -243.702521) (xy 65.935724 -243.756875) (xy 65.934013 -243.780818) (xy 72.253346 -243.780818)
			(xy 72.257417 -243.725196) (xy 72.269543 -243.670759) (xy 72.289466 -243.618668) (xy 72.316762 -243.570033)
			(xy 72.350848 -243.52589) (xy 72.390997 -243.487181) (xy 72.436355 -243.45473) (xy 72.485955 -243.429229)
			(xy 72.538739 -243.411222) (xy 72.593582 -243.401092) (xy 72.649316 -243.399055) (xy 72.704753 -243.405155)
			(xy 72.75871 -243.419261) (xy 72.810039 -243.441073) (xy 72.857645 -243.470127) (xy 72.900513 -243.505802)
			(xy 72.93773 -243.547339) (xy 72.968503 -243.593852) (xy 72.992175 -243.644349) (xy 73.008243 -243.697756)
			(xy 73.016363 -243.752932) (xy 73.016872 -243.780818) (xy 73.016363 -243.808704) (xy 73.008243 -243.86388)
			(xy 72.992175 -243.917287) (xy 72.968503 -243.967784) (xy 72.93773 -244.014297) (xy 72.900513 -244.055834)
			(xy 72.857645 -244.091509) (xy 72.810039 -244.120563) (xy 72.75871 -244.142375) (xy 72.704753 -244.156481)
			(xy 72.649316 -244.162581) (xy 72.593582 -244.160544) (xy 72.538739 -244.150414) (xy 72.485955 -244.132407)
			(xy 72.436355 -244.106906) (xy 72.390997 -244.074455) (xy 72.350848 -244.035746) (xy 72.316762 -243.991603)
			(xy 72.289466 -243.942968) (xy 72.269543 -243.890877) (xy 72.257417 -243.83644) (xy 72.253346 -243.780818)
			(xy 65.934013 -243.780818) (xy 65.93184 -243.811229) (xy 65.92026 -243.864477) (xy 65.90122 -243.915535)
			(xy 65.875108 -243.963363) (xy 65.842454 -244.006989) (xy 65.803925 -244.045523) (xy 65.760303 -244.078182)
			(xy 65.712478 -244.104301) (xy 65.661422 -244.123347) (xy 65.608176 -244.134933) (xy 65.553822 -244.138824)
			(xy 65.499468 -244.134939) (xy 65.44622 -244.123359) (xy 65.395163 -244.104319) (xy 65.347334 -244.078206)
			(xy 65.325244 -244.06225) (xy 65.306232 -244.048654) (xy 65.264349 -244.027922) (xy 65.219381 -244.015196)
			(xy 65.172844 -244.010906) (xy 65.126307 -244.015196) (xy 65.081339 -244.027922) (xy 65.039456 -244.048654)
			(xy 65.020444 -244.06225) (xy 64.998315 -244.078157) (xy 64.950489 -244.104279) (xy 64.899432 -244.123329)
			(xy 64.846184 -244.134917) (xy 64.791828 -244.138809) (xy 64.737471 -244.134925) (xy 64.684221 -244.123344)
			(xy 64.633161 -244.104302) (xy 64.585331 -244.078187) (xy 64.541705 -244.04553) (xy 64.503172 -244.006997)
			(xy 64.470514 -243.963371) (xy 64.444399 -243.915541) (xy 64.425356 -243.864481) (xy 64.413775 -243.811231)
			(xy 64.409891 -243.756875) (xy 64.031874 -243.756875) (xy 64.027989 -243.81124) (xy 64.016406 -243.864499)
			(xy 63.997361 -243.915567) (xy 63.971241 -243.963405) (xy 63.938578 -244.007038) (xy 63.900038 -244.045578)
			(xy 63.856405 -244.078241) (xy 63.808567 -244.104361) (xy 63.757499 -244.123406) (xy 63.70424 -244.134989)
			(xy 63.649874 -244.138874) (xy 63.59551 -244.134982) (xy 63.542252 -244.123392) (xy 63.491186 -244.104339)
			(xy 63.443352 -244.078213) (xy 63.42126 -244.06225) (xy 63.402248 -244.048654) (xy 63.360365 -244.027922)
			(xy 63.315397 -244.015196) (xy 63.26886 -244.010906) (xy 63.222323 -244.015196) (xy 63.177355 -244.027922)
			(xy 63.135472 -244.048654) (xy 63.11646 -244.06225) (xy 63.094333 -244.07815) (xy 63.046513 -244.104259)
			(xy 62.995464 -244.123296) (xy 62.942225 -244.134875) (xy 62.88788 -244.138759) (xy 62.833536 -244.134869)
			(xy 62.780298 -244.123285) (xy 62.729251 -244.104242) (xy 62.681433 -244.078128) (xy 62.637819 -244.045475)
			(xy 62.599295 -244.006947) (xy 62.566647 -243.963329) (xy 62.540539 -243.915508) (xy 62.521502 -243.864459)
			(xy 62.509924 -243.81122) (xy 62.506041 -243.756875) (xy 61.790739 -243.756875) (xy 61.786855 -243.811232)
			(xy 61.775274 -243.864484) (xy 61.756233 -243.915545) (xy 61.730118 -243.963376) (xy 61.697462 -244.007004)
			(xy 61.658929 -244.04554) (xy 61.615304 -244.0782) (xy 61.567474 -244.104319) (xy 61.516415 -244.123365)
			(xy 61.463165 -244.13495) (xy 61.408807 -244.138839) (xy 61.35445 -244.134953) (xy 61.301199 -244.123369)
			(xy 61.250139 -244.104325) (xy 61.202309 -244.078208) (xy 61.180218 -244.06225) (xy 61.161206 -244.048654)
			(xy 61.119323 -244.027922) (xy 61.074355 -244.015196) (xy 61.027818 -244.010906) (xy 60.981281 -244.015196)
			(xy 60.936313 -244.027922) (xy 60.89443 -244.048654) (xy 60.875418 -244.06225) (xy 60.85329 -244.078155)
			(xy 60.805466 -244.104273) (xy 60.754411 -244.123319) (xy 60.701166 -244.134904) (xy 60.646813 -244.138794)
			(xy 60.59246 -244.134908) (xy 60.539214 -244.123326) (xy 60.488158 -244.104284) (xy 60.440332 -244.078169)
			(xy 60.39671 -244.045513) (xy 60.358179 -244.006981) (xy 60.325524 -243.963358) (xy 60.299411 -243.915531)
			(xy 60.280371 -243.864474) (xy 60.26879 -243.811228) (xy 60.264906 -243.756875) (xy 59.904047 -243.756875)
			(xy 59.900162 -243.811234) (xy 59.888581 -243.864487) (xy 59.869538 -243.91555) (xy 59.843423 -243.963382)
			(xy 59.810765 -244.007011) (xy 59.772231 -244.045548) (xy 59.728604 -244.078209) (xy 59.680773 -244.104328)
			(xy 59.629712 -244.123374) (xy 59.576459 -244.134958) (xy 59.522101 -244.138847) (xy 59.467742 -244.134959)
			(xy 59.414489 -244.123374) (xy 59.363428 -244.104328) (xy 59.315597 -244.078209) (xy 59.293506 -244.06225)
			(xy 59.274494 -244.048654) (xy 59.232611 -244.027922) (xy 59.187643 -244.015196) (xy 59.141106 -244.010906)
			(xy 59.094569 -244.015196) (xy 59.049601 -244.027922) (xy 59.007718 -244.048654) (xy 58.988706 -244.06225)
			(xy 58.966578 -244.078154) (xy 58.918755 -244.10427) (xy 58.867701 -244.123314) (xy 58.814457 -244.134898)
			(xy 58.760106 -244.138786) (xy 58.705755 -244.1349) (xy 58.652511 -244.123318) (xy 58.601456 -244.104275)
			(xy 58.553632 -244.078161) (xy 58.510011 -244.045505) (xy 58.471482 -244.006974) (xy 58.438829 -243.963352)
			(xy 58.412717 -243.915526) (xy 58.393677 -243.864471) (xy 58.382097 -243.811226) (xy 58.378214 -243.756875)
			(xy 11.895141 -243.756875) (xy 10.926572 -244.725444) (xy 44.159168 -244.725444) (xy 44.163239 -244.669822)
			(xy 44.175365 -244.615385) (xy 44.195288 -244.563294) (xy 44.222584 -244.514659) (xy 44.25667 -244.470516)
			(xy 44.296819 -244.431807) (xy 44.342177 -244.399356) (xy 44.391777 -244.373855) (xy 44.444561 -244.355848)
			(xy 44.499404 -244.345718) (xy 44.555138 -244.343681) (xy 44.610575 -244.349781) (xy 44.664532 -244.363887)
			(xy 44.715861 -244.385699) (xy 44.763467 -244.414753) (xy 44.806335 -244.450428) (xy 44.843552 -244.491965)
			(xy 44.874325 -244.538478) (xy 44.897997 -244.588975) (xy 44.914065 -244.642382) (xy 44.922185 -244.697558)
			(xy 44.922694 -244.725444) (xy 44.922185 -244.75333) (xy 44.914065 -244.808506) (xy 44.897997 -244.861913)
			(xy 44.874325 -244.91241) (xy 44.843552 -244.958923) (xy 44.806335 -245.00046) (xy 44.763467 -245.036135)
			(xy 44.715861 -245.065189) (xy 44.664532 -245.087001) (xy 44.610575 -245.101107) (xy 44.555138 -245.107207)
			(xy 44.499404 -245.10517) (xy 44.444561 -245.09504) (xy 44.391777 -245.077033) (xy 44.342177 -245.051532)
			(xy 44.296819 -245.019081) (xy 44.25667 -244.980372) (xy 44.222584 -244.936229) (xy 44.195288 -244.887594)
			(xy 44.175365 -244.835503) (xy 44.163239 -244.781066) (xy 44.159168 -244.725444) (xy 10.926572 -244.725444)
			(xy 10.004552 -245.647464) (xy 10.004552 -245.712234) (xy 46.403766 -245.712234) (xy 46.407837 -245.656612)
			(xy 46.419963 -245.602175) (xy 46.439886 -245.550084) (xy 46.467182 -245.501449) (xy 46.501268 -245.457306)
			(xy 46.541417 -245.418597) (xy 46.586775 -245.386146) (xy 46.636375 -245.360645) (xy 46.689159 -245.342638)
			(xy 46.744002 -245.332508) (xy 46.799736 -245.330471) (xy 46.855173 -245.336571) (xy 46.90913 -245.350677)
			(xy 46.960459 -245.372489) (xy 47.008065 -245.401543) (xy 47.050933 -245.437218) (xy 47.08815 -245.478755)
			(xy 47.118923 -245.525268) (xy 47.142595 -245.575765) (xy 47.158663 -245.629172) (xy 47.162893 -245.657913)
			(xy 58.378162 -245.657913) (xy 58.382048 -245.603555) (xy 58.393631 -245.550303) (xy 58.412675 -245.499242)
			(xy 58.438793 -245.45141) (xy 58.471451 -245.407783) (xy 58.509987 -245.369248) (xy 58.553615 -245.33659)
			(xy 58.601446 -245.310473) (xy 58.652508 -245.29143) (xy 58.70576 -245.279848) (xy 58.760118 -245.275962)
			(xy 58.814476 -245.279853) (xy 58.867727 -245.29144) (xy 58.918787 -245.310488) (xy 58.966616 -245.33661)
			(xy 58.988706 -245.35257) (xy 59.007718 -245.366166) (xy 59.049601 -245.386898) (xy 59.094569 -245.399624)
			(xy 59.141106 -245.403914) (xy 59.187643 -245.399624) (xy 59.232611 -245.386898) (xy 59.274494 -245.366166)
			(xy 59.293506 -245.35257) (xy 59.315615 -245.33664) (xy 59.363438 -245.310523) (xy 59.414492 -245.291479)
			(xy 59.467737 -245.279894) (xy 59.522089 -245.276005) (xy 59.57644 -245.279891) (xy 59.629686 -245.291472)
			(xy 59.680741 -245.310514) (xy 59.728566 -245.336628) (xy 59.772188 -245.369283) (xy 59.810719 -245.407813)
			(xy 59.843373 -245.451435) (xy 59.869487 -245.499261) (xy 59.888528 -245.550316) (xy 59.90011 -245.603561)
			(xy 59.903995 -245.657913) (xy 60.264855 -245.657913) (xy 60.268741 -245.603553) (xy 60.280325 -245.5503)
			(xy 60.29937 -245.499237) (xy 60.325488 -245.451404) (xy 60.358148 -245.407776) (xy 60.396685 -245.36924)
			(xy 60.440314 -245.336581) (xy 60.488148 -245.310465) (xy 60.539211 -245.291421) (xy 60.592465 -245.27984)
			(xy 60.646825 -245.275955) (xy 60.701185 -245.279847) (xy 60.754437 -245.291436) (xy 60.805498 -245.310485)
			(xy 60.853328 -245.336609) (xy 60.875418 -245.35257) (xy 60.89443 -245.366166) (xy 60.936313 -245.386898)
			(xy 60.981281 -245.399624) (xy 61.027818 -245.403914) (xy 61.074355 -245.399624) (xy 61.119323 -245.386898)
			(xy 61.161206 -245.366166) (xy 61.180218 -245.35257) (xy 61.202326 -245.336641) (xy 61.250149 -245.310526)
			(xy 61.301202 -245.291483) (xy 61.354445 -245.2799) (xy 61.408795 -245.276012) (xy 61.463145 -245.279899)
			(xy 61.516389 -245.291481) (xy 61.567442 -245.310522) (xy 61.615266 -245.336636) (xy 61.658886 -245.369291)
			(xy 61.697415 -245.40782) (xy 61.730068 -245.451441) (xy 61.756181 -245.499266) (xy 61.775222 -245.550319)
			(xy 61.786803 -245.603563) (xy 61.790688 -245.657913) (xy 62.50599 -245.657913) (xy 62.509875 -245.603561)
			(xy 62.521456 -245.550315) (xy 62.540497 -245.499259) (xy 62.566611 -245.451433) (xy 62.599264 -245.40781)
			(xy 62.637794 -245.369278) (xy 62.681416 -245.336622) (xy 62.72924 -245.310506) (xy 62.780295 -245.291462)
			(xy 62.83354 -245.279878) (xy 62.887892 -245.27599) (xy 62.942244 -245.279876) (xy 62.99549 -245.291458)
			(xy 63.046545 -245.3105) (xy 63.094371 -245.336613) (xy 63.11646 -245.35257) (xy 63.135472 -245.366166)
			(xy 63.177355 -245.386898) (xy 63.222323 -245.399624) (xy 63.26886 -245.403914) (xy 63.315397 -245.399624)
			(xy 63.360365 -245.386898) (xy 63.402248 -245.366166) (xy 63.42126 -245.35257) (xy 63.44337 -245.336636)
			(xy 63.491197 -245.310512) (xy 63.542255 -245.291461) (xy 63.595505 -245.279871) (xy 63.649862 -245.275977)
			(xy 63.704221 -245.27986) (xy 63.757473 -245.29144) (xy 63.808535 -245.310481) (xy 63.856367 -245.336596)
			(xy 63.899995 -245.369252) (xy 63.938532 -245.407786) (xy 63.971191 -245.451412) (xy 63.997309 -245.499243)
			(xy 64.016353 -245.550304) (xy 64.027937 -245.603555) (xy 64.031823 -245.657913) (xy 64.409839 -245.657913)
			(xy 64.413726 -245.60355) (xy 64.425311 -245.550293) (xy 64.444357 -245.499227) (xy 64.470478 -245.451391)
			(xy 64.503141 -245.407761) (xy 64.541681 -245.369223) (xy 64.585314 -245.336563) (xy 64.633151 -245.310446)
			(xy 64.684218 -245.291403) (xy 64.737476 -245.279822) (xy 64.79184 -245.275939) (xy 64.846203 -245.279834)
			(xy 64.899458 -245.291426) (xy 64.950522 -245.310479) (xy 64.998353 -245.336606) (xy 65.020444 -245.35257)
			(xy 65.039456 -245.366166) (xy 65.081339 -245.386898) (xy 65.126307 -245.399624) (xy 65.172844 -245.403914)
			(xy 65.219381 -245.399624) (xy 65.264349 -245.386898) (xy 65.306232 -245.366166) (xy 65.325244 -245.35257)
			(xy 65.347352 -245.336643) (xy 65.395173 -245.310533) (xy 65.446223 -245.291493) (xy 65.499464 -245.279913)
			(xy 65.55381 -245.276027) (xy 65.608156 -245.279916) (xy 65.661396 -245.291499) (xy 65.712446 -245.310541)
			(xy 65.760265 -245.336654) (xy 65.803882 -245.369308) (xy 65.842408 -245.407836) (xy 65.875058 -245.451454)
			(xy 65.901169 -245.499276) (xy 65.920208 -245.550326) (xy 65.931787 -245.603567) (xy 65.935673 -245.657913)
			(xy 65.931784 -245.712259) (xy 65.9202 -245.765499) (xy 65.901158 -245.816548) (xy 65.875044 -245.864368)
			(xy 65.84239 -245.907984) (xy 65.803862 -245.94651) (xy 65.760243 -245.97916) (xy 65.712422 -246.00527)
			(xy 65.661371 -246.024308) (xy 65.60813 -246.035888) (xy 65.553784 -246.039773) (xy 65.499438 -246.035883)
			(xy 65.446198 -246.024299) (xy 65.395149 -246.005256) (xy 65.34733 -245.979142) (xy 65.325244 -245.963186)
			(xy 65.306232 -245.94959) (xy 65.264349 -245.928858) (xy 65.219381 -245.916132) (xy 65.172844 -245.911842)
			(xy 65.126307 -245.916132) (xy 65.081339 -245.928858) (xy 65.039456 -245.94959) (xy 65.020444 -245.963186)
			(xy 64.998375 -245.979179) (xy 64.950546 -246.00531) (xy 64.899484 -246.024367) (xy 64.846229 -246.035963)
			(xy 64.791866 -246.03986) (xy 64.737502 -246.035981) (xy 64.684244 -246.024404) (xy 64.633175 -246.005365)
			(xy 64.585336 -245.979251) (xy 64.541701 -245.946594) (xy 64.503158 -245.908059) (xy 64.470492 -245.864431)
			(xy 64.444368 -245.816597) (xy 64.425318 -245.765533) (xy 64.41373 -245.712276) (xy 64.409839 -245.657913)
			(xy 64.031823 -245.657913) (xy 64.027933 -245.712271) (xy 64.016346 -245.765522) (xy 63.997298 -245.816581)
			(xy 63.971177 -245.86441) (xy 63.938514 -245.908034) (xy 63.899975 -245.946565) (xy 63.856345 -245.979219)
			(xy 63.808511 -246.00533) (xy 63.757448 -246.024368) (xy 63.704195 -246.035944) (xy 63.649836 -246.039823)
			(xy 63.595479 -246.035926) (xy 63.54223 -246.024332) (xy 63.491173 -246.005277) (xy 63.443348 -245.979149)
			(xy 63.42126 -245.963186) (xy 63.402248 -245.94959) (xy 63.360365 -245.928858) (xy 63.315397 -245.916132)
			(xy 63.26886 -245.911842) (xy 63.222323 -245.916132) (xy 63.177355 -245.928858) (xy 63.135472 -245.94959)
			(xy 63.11646 -245.963186) (xy 63.094393 -245.979172) (xy 63.046569 -246.005289) (xy 62.995515 -246.024335)
			(xy 62.94227 -246.03592) (xy 62.887918 -246.03981) (xy 62.833566 -246.035925) (xy 62.78032 -246.024345)
			(xy 62.729264 -246.005305) (xy 62.681438 -245.979192) (xy 62.637814 -245.946539) (xy 62.599282 -245.90801)
			(xy 62.566625 -245.864389) (xy 62.540508 -245.816565) (xy 62.521464 -245.76551) (xy 62.509879 -245.712265)
			(xy 62.50599 -245.657913) (xy 61.790688 -245.657913) (xy 61.786799 -245.712263) (xy 61.775214 -245.765506)
			(xy 61.75617 -245.816558) (xy 61.730054 -245.864381) (xy 61.697398 -245.908) (xy 61.658866 -245.946527)
			(xy 61.615244 -245.979178) (xy 61.567418 -246.005289) (xy 61.516364 -246.024327) (xy 61.463119 -246.035905)
			(xy 61.408769 -246.039788) (xy 61.354419 -246.035896) (xy 61.301177 -246.024309) (xy 61.250125 -246.005263)
			(xy 61.202304 -245.979144) (xy 61.180218 -245.963186) (xy 61.161206 -245.94959) (xy 61.119323 -245.928858)
			(xy 61.074355 -245.916132) (xy 61.027818 -245.911842) (xy 60.981281 -245.916132) (xy 60.936313 -245.928858)
			(xy 60.89443 -245.94959) (xy 60.875418 -245.963186) (xy 60.85335 -245.979177) (xy 60.805522 -246.005304)
			(xy 60.754462 -246.024357) (xy 60.701211 -246.035949) (xy 60.646851 -246.039845) (xy 60.592491 -246.035964)
			(xy 60.539236 -246.024386) (xy 60.488172 -246.005346) (xy 60.440337 -245.979233) (xy 60.396705 -245.946577)
			(xy 60.358165 -245.908044) (xy 60.325502 -245.864418) (xy 60.299381 -245.816587) (xy 60.280332 -245.765526)
			(xy 60.268745 -245.712273) (xy 60.264855 -245.657913) (xy 59.903995 -245.657913) (xy 59.900106 -245.712265)
			(xy 59.888521 -245.765509) (xy 59.869476 -245.816563) (xy 59.843359 -245.864387) (xy 59.810701 -245.908007)
			(xy 59.772168 -245.946535) (xy 59.728544 -245.979186) (xy 59.680717 -246.005297) (xy 59.62966 -246.024335)
			(xy 59.576414 -246.035913) (xy 59.522062 -246.039795) (xy 59.467711 -246.035902) (xy 59.414467 -246.024314)
			(xy 59.363414 -246.005266) (xy 59.315592 -245.979145) (xy 59.293506 -245.963186) (xy 59.274494 -245.94959)
			(xy 59.232611 -245.928858) (xy 59.187643 -245.916132) (xy 59.141106 -245.911842) (xy 59.094569 -245.916132)
			(xy 59.049601 -245.928858) (xy 59.007718 -245.94959) (xy 58.988706 -245.963186) (xy 58.966638 -245.979176)
			(xy 58.918811 -246.005301) (xy 58.867753 -246.024352) (xy 58.814502 -246.035943) (xy 58.760145 -246.039838)
			(xy 58.705786 -246.035956) (xy 58.652533 -246.024378) (xy 58.60147 -246.005338) (xy 58.553637 -245.979224)
			(xy 58.510007 -245.946569) (xy 58.471469 -245.908037) (xy 58.438807 -245.864412) (xy 58.412686 -245.816582)
			(xy 58.393639 -245.765522) (xy 58.382052 -245.712271) (xy 58.378162 -245.657913) (xy 47.162893 -245.657913)
			(xy 47.166783 -245.684348) (xy 47.167292 -245.712234) (xy 47.166783 -245.74012) (xy 47.158663 -245.795296)
			(xy 47.142595 -245.848703) (xy 47.118923 -245.8992) (xy 47.08815 -245.945713) (xy 47.050933 -245.98725)
			(xy 47.008065 -246.022925) (xy 46.960459 -246.051979) (xy 46.90913 -246.073791) (xy 46.855173 -246.087897)
			(xy 46.799736 -246.093997) (xy 46.744002 -246.09196) (xy 46.689159 -246.08183) (xy 46.636375 -246.063823)
			(xy 46.586775 -246.038322) (xy 46.541417 -246.005871) (xy 46.501268 -245.967162) (xy 46.467182 -245.923019)
			(xy 46.439886 -245.874384) (xy 46.419963 -245.822293) (xy 46.407837 -245.767856) (xy 46.403766 -245.712234)
			(xy 10.004552 -245.712234) (xy 10.004552 -246.940612) (xy 25.681069 -246.940612) (xy 25.685634 -246.884923)
			(xy 25.69827 -246.830494) (xy 25.718709 -246.77849) (xy 25.746512 -246.730023) (xy 25.781086 -246.686128)
			(xy 25.821692 -246.647744) (xy 25.867461 -246.615691) (xy 25.917415 -246.590656) (xy 25.970485 -246.573173)
			(xy 26.025538 -246.563616) (xy 26.081396 -246.562189) (xy 26.136865 -246.568922) (xy 26.190759 -246.583673)
			(xy 26.241926 -246.606125) (xy 26.289271 -246.635799) (xy 26.310844 -246.653558) (xy 26.323561 -246.663834)
			(xy 26.352996 -246.678048) (xy 26.38508 -246.684301) (xy 26.417699 -246.682181) (xy 26.448704 -246.671829)
			(xy 26.476053 -246.653926) (xy 26.487374 -246.642128) (xy 26.506519 -246.621781) (xy 26.549647 -246.58627)
			(xy 26.597492 -246.557428) (xy 26.649031 -246.535872) (xy 26.703163 -246.522061) (xy 26.758731 -246.516292)
			(xy 26.814545 -246.518687) (xy 26.869414 -246.529196) (xy 26.922164 -246.547593) (xy 26.971667 -246.573486)
			(xy 27.016865 -246.606321) (xy 27.056792 -246.645395) (xy 27.090594 -246.689875) (xy 27.117549 -246.738808)
			(xy 27.13708 -246.791148) (xy 27.14877 -246.845778) (xy 27.152369 -246.901527) (xy 27.1478 -246.957206)
			(xy 27.13516 -247.011623) (xy 27.134831 -247.01246) (xy 44.102272 -247.01246) (xy 44.106343 -246.956838)
			(xy 44.118469 -246.902401) (xy 44.138392 -246.85031) (xy 44.165688 -246.801675) (xy 44.199774 -246.757532)
			(xy 44.239923 -246.718823) (xy 44.285281 -246.686372) (xy 44.334881 -246.660871) (xy 44.387665 -246.642864)
			(xy 44.442508 -246.632734) (xy 44.498242 -246.630697) (xy 44.553679 -246.636797) (xy 44.607636 -246.650903)
			(xy 44.658965 -246.672715) (xy 44.706571 -246.701769) (xy 44.749439 -246.737444) (xy 44.786656 -246.778981)
			(xy 44.817429 -246.825494) (xy 44.841101 -246.875991) (xy 44.857169 -246.929398) (xy 44.865289 -246.984574)
			(xy 44.865798 -247.01246) (xy 44.865289 -247.040346) (xy 44.857169 -247.095522) (xy 44.841101 -247.148929)
			(xy 44.817429 -247.199426) (xy 44.786656 -247.245939) (xy 44.749439 -247.287476) (xy 44.706571 -247.323151)
			(xy 44.690441 -247.332995) (xy 58.378186 -247.332995) (xy 58.382075 -247.27864) (xy 58.393659 -247.225392)
			(xy 58.412705 -247.174335) (xy 58.438823 -247.126508) (xy 58.471481 -247.082885) (xy 58.510016 -247.044354)
			(xy 58.553643 -247.0117) (xy 58.601472 -246.985588) (xy 58.652532 -246.966548) (xy 58.705781 -246.954969)
			(xy 58.760136 -246.951086) (xy 58.814491 -246.954979) (xy 58.867738 -246.966568) (xy 58.918793 -246.985618)
			(xy 58.966618 -247.01174) (xy 58.988706 -247.0277) (xy 59.007718 -247.041296) (xy 59.049601 -247.062028)
			(xy 59.094569 -247.074754) (xy 59.141106 -247.079044) (xy 59.187643 -247.074754) (xy 59.232611 -247.062028)
			(xy 59.274494 -247.041296) (xy 59.293506 -247.0277) (xy 59.315587 -247.01173) (xy 59.363412 -246.985609)
			(xy 59.414468 -246.966561) (xy 59.467716 -246.954973) (xy 59.522071 -246.951081) (xy 59.576426 -246.954964)
			(xy 59.629675 -246.966544) (xy 59.680734 -246.985585) (xy 59.728564 -247.011698) (xy 59.77219 -247.044353)
			(xy 59.810725 -247.082884) (xy 59.843384 -247.126507) (xy 59.869501 -247.174334) (xy 59.888546 -247.225392)
			(xy 59.900131 -247.27864) (xy 59.904019 -247.332995) (xy 60.264879 -247.332995) (xy 60.268768 -247.278639)
			(xy 60.280353 -247.225389) (xy 60.299399 -247.17433) (xy 60.325518 -247.126502) (xy 60.358178 -247.082878)
			(xy 60.396714 -247.044347) (xy 60.440343 -247.011692) (xy 60.488174 -246.985579) (xy 60.539235 -246.966539)
			(xy 60.592486 -246.954961) (xy 60.646843 -246.951079) (xy 60.701199 -246.954973) (xy 60.754448 -246.966564)
			(xy 60.805504 -246.985615) (xy 60.85333 -247.011739) (xy 60.875418 -247.0277) (xy 60.89443 -247.041296)
			(xy 60.936313 -247.062028) (xy 60.981281 -247.074754) (xy 61.027818 -247.079044) (xy 61.074355 -247.074754)
			(xy 61.119323 -247.062028) (xy 61.161206 -247.041296) (xy 61.180218 -247.0277) (xy 61.202298 -247.011731)
			(xy 61.250123 -246.985612) (xy 61.301178 -246.966565) (xy 61.354424 -246.954979) (xy 61.408777 -246.951088)
			(xy 61.463131 -246.954972) (xy 61.516379 -246.966553) (xy 61.567436 -246.985593) (xy 61.615264 -247.011706)
			(xy 61.658888 -247.044361) (xy 61.697421 -247.082891) (xy 61.730079 -247.126513) (xy 61.756195 -247.174339)
			(xy 61.77524 -247.225395) (xy 61.786824 -247.278642) (xy 61.790712 -247.332995) (xy 62.506014 -247.332995)
			(xy 62.509902 -247.278647) (xy 62.521485 -247.225405) (xy 62.540527 -247.174353) (xy 62.566641 -247.126531)
			(xy 62.599294 -247.082912) (xy 62.637824 -247.044385) (xy 62.681444 -247.011733) (xy 62.729267 -246.985621)
			(xy 62.780319 -246.96658) (xy 62.833561 -246.955) (xy 62.88791 -246.951114) (xy 62.942259 -246.955002)
			(xy 62.9955 -246.966586) (xy 63.046552 -246.985629) (xy 63.094373 -247.011743) (xy 63.11646 -247.0277)
			(xy 63.135472 -247.041296) (xy 63.177355 -247.062028) (xy 63.222323 -247.074754) (xy 63.26886 -247.079044)
			(xy 63.315397 -247.074754) (xy 63.360365 -247.062028) (xy 63.402248 -247.041296) (xy 63.42126 -247.0277)
			(xy 63.443342 -247.011726) (xy 63.49117 -246.985598) (xy 63.542231 -246.966543) (xy 63.595484 -246.954949)
			(xy 63.649844 -246.951053) (xy 63.704206 -246.954934) (xy 63.757462 -246.966512) (xy 63.808529 -246.985552)
			(xy 63.856365 -247.011666) (xy 63.899997 -247.044323) (xy 63.938538 -247.082857) (xy 63.971202 -247.126484)
			(xy 63.997323 -247.174317) (xy 64.016371 -247.22538) (xy 64.027958 -247.278634) (xy 64.031847 -247.332995)
			(xy 64.409864 -247.332995) (xy 64.413752 -247.278635) (xy 64.425339 -247.225382) (xy 64.444386 -247.17432)
			(xy 64.470508 -247.126489) (xy 64.503171 -247.082863) (xy 64.54171 -247.04433) (xy 64.585342 -247.011674)
			(xy 64.633177 -246.98556) (xy 64.684242 -246.966521) (xy 64.737497 -246.954944) (xy 64.791858 -246.951064)
			(xy 64.846217 -246.95496) (xy 64.899469 -246.966554) (xy 64.950528 -246.985608) (xy 64.998355 -247.011736)
			(xy 65.020444 -247.0277) (xy 65.039456 -247.041296) (xy 65.081339 -247.062028) (xy 65.126307 -247.074754)
			(xy 65.172844 -247.079044) (xy 65.219381 -247.074754) (xy 65.264349 -247.062028) (xy 65.306232 -247.041296)
			(xy 65.325244 -247.0277) (xy 65.347324 -247.011733) (xy 65.395147 -246.985618) (xy 65.446199 -246.966575)
			(xy 65.499442 -246.954992) (xy 65.553792 -246.951103) (xy 65.608142 -246.95499) (xy 65.661386 -246.966571)
			(xy 65.712439 -246.985612) (xy 65.760263 -247.011725) (xy 65.803884 -247.044378) (xy 65.842414 -247.082906)
			(xy 65.875069 -247.126526) (xy 65.901183 -247.174349) (xy 65.920226 -247.225402) (xy 65.931809 -247.278645)
			(xy 65.935697 -247.332995) (xy 65.93181 -247.387345) (xy 65.920228 -247.440589) (xy 65.901187 -247.491642)
			(xy 65.875074 -247.539466) (xy 65.84242 -247.583086) (xy 65.803891 -247.621616) (xy 65.760271 -247.65427)
			(xy 65.712448 -247.680384) (xy 65.661395 -247.699426) (xy 65.608152 -247.711009) (xy 65.553802 -247.714897)
			(xy 65.499452 -247.71101) (xy 65.446208 -247.699427) (xy 65.395155 -247.680386) (xy 65.347332 -247.654272)
			(xy 65.325244 -247.638316) (xy 65.306232 -247.62472) (xy 65.264349 -247.603988) (xy 65.219381 -247.591262)
			(xy 65.172844 -247.586972) (xy 65.126307 -247.591262) (xy 65.081339 -247.603988) (xy 65.039456 -247.62472)
			(xy 65.020444 -247.638316) (xy 64.998347 -247.654269) (xy 64.950519 -247.680396) (xy 64.89946 -247.699449)
			(xy 64.846208 -247.711041) (xy 64.791848 -247.714936) (xy 64.737488 -247.711055) (xy 64.684233 -247.699476)
			(xy 64.633169 -247.680436) (xy 64.585334 -247.654321) (xy 64.541703 -247.621664) (xy 64.503164 -247.58313)
			(xy 64.470502 -247.539503) (xy 64.444382 -247.491671) (xy 64.425336 -247.440609) (xy 64.413751 -247.387355)
			(xy 64.409864 -247.332995) (xy 64.031847 -247.332995) (xy 64.027959 -247.387357) (xy 64.016374 -247.440611)
			(xy 63.997327 -247.491675) (xy 63.971207 -247.539508) (xy 63.938544 -247.583136) (xy 63.900005 -247.621671)
			(xy 63.856373 -247.654329) (xy 63.808537 -247.680444) (xy 63.757472 -247.699486) (xy 63.704216 -247.711065)
			(xy 63.649854 -247.714947) (xy 63.595493 -247.711052) (xy 63.54224 -247.69946) (xy 63.491179 -247.680406)
			(xy 63.44335 -247.654279) (xy 63.42126 -247.638316) (xy 63.402248 -247.62472) (xy 63.360365 -247.603988)
			(xy 63.315397 -247.591262) (xy 63.26886 -247.586972) (xy 63.222323 -247.591262) (xy 63.177355 -247.603988)
			(xy 63.135472 -247.62472) (xy 63.11646 -247.638316) (xy 63.094365 -247.654262) (xy 63.046543 -247.680375)
			(xy 62.995491 -247.699417) (xy 62.942249 -247.710999) (xy 62.8879 -247.714886) (xy 62.833552 -247.710999)
			(xy 62.78031 -247.699417) (xy 62.729258 -247.680375) (xy 62.681436 -247.654262) (xy 62.637816 -247.621609)
			(xy 62.599288 -247.58308) (xy 62.566635 -247.539461) (xy 62.540523 -247.491638) (xy 62.521482 -247.440586)
			(xy 62.5099 -247.387344) (xy 62.506014 -247.332995) (xy 61.790712 -247.332995) (xy 61.786825 -247.387349)
			(xy 61.775242 -247.440596) (xy 61.756199 -247.491652) (xy 61.730084 -247.539479) (xy 61.697428 -247.583102)
			(xy 61.658896 -247.621633) (xy 61.615272 -247.654288) (xy 61.567445 -247.680403) (xy 61.516388 -247.699445)
			(xy 61.46314 -247.711026) (xy 61.408787 -247.714912) (xy 61.354434 -247.711023) (xy 61.301187 -247.699437)
			(xy 61.250132 -247.680392) (xy 61.202306 -247.654274) (xy 61.180218 -247.638316) (xy 61.161206 -247.62472)
			(xy 61.119323 -247.603988) (xy 61.074355 -247.591262) (xy 61.027818 -247.586972) (xy 60.981281 -247.591262)
			(xy 60.936313 -247.603988) (xy 60.89443 -247.62472) (xy 60.875418 -247.638316) (xy 60.853322 -247.654267)
			(xy 60.805496 -247.680389) (xy 60.754438 -247.699439) (xy 60.70119 -247.711028) (xy 60.646833 -247.714921)
			(xy 60.592477 -247.711038) (xy 60.539226 -247.699458) (xy 60.488165 -247.680417) (xy 60.440334 -247.654303)
			(xy 60.396707 -247.621647) (xy 60.358172 -247.583115) (xy 60.325513 -247.53949) (xy 60.299395 -247.491661)
			(xy 60.28035 -247.440602) (xy 60.268766 -247.387352) (xy 60.264879 -247.332995) (xy 59.904019 -247.332995)
			(xy 59.900132 -247.38735) (xy 59.888549 -247.440599) (xy 59.869505 -247.491657) (xy 59.843389 -247.539485)
			(xy 59.810731 -247.583109) (xy 59.772197 -247.621641) (xy 59.728572 -247.654297) (xy 59.680743 -247.680411)
			(xy 59.629684 -247.699453) (xy 59.576435 -247.711034) (xy 59.52208 -247.714919) (xy 59.467725 -247.711029)
			(xy 59.414478 -247.699442) (xy 59.363421 -247.680395) (xy 59.315595 -247.654275) (xy 59.293506 -247.638316)
			(xy 59.274494 -247.62472) (xy 59.232611 -247.603988) (xy 59.187643 -247.591262) (xy 59.141106 -247.586972)
			(xy 59.094569 -247.591262) (xy 59.049601 -247.603988) (xy 59.007718 -247.62472) (xy 58.988706 -247.638316)
			(xy 58.96661 -247.654266) (xy 58.918785 -247.680386) (xy 58.867729 -247.699434) (xy 58.814481 -247.711022)
			(xy 58.760127 -247.714914) (xy 58.705772 -247.71103) (xy 58.652523 -247.699449) (xy 58.601464 -247.680408)
			(xy 58.553635 -247.654294) (xy 58.510009 -247.621639) (xy 58.471475 -247.583107) (xy 58.438817 -247.539484)
			(xy 58.412701 -247.491656) (xy 58.393657 -247.440598) (xy 58.382073 -247.38735) (xy 58.378186 -247.332995)
			(xy 44.690441 -247.332995) (xy 44.658965 -247.352205) (xy 44.607636 -247.374017) (xy 44.553679 -247.388123)
			(xy 44.498242 -247.394223) (xy 44.442508 -247.392186) (xy 44.387665 -247.382056) (xy 44.334881 -247.364049)
			(xy 44.285281 -247.338548) (xy 44.239923 -247.306097) (xy 44.199774 -247.267388) (xy 44.165688 -247.223245)
			(xy 44.138392 -247.17461) (xy 44.118469 -247.122519) (xy 44.106343 -247.068082) (xy 44.102272 -247.01246)
			(xy 27.134831 -247.01246) (xy 27.11472 -247.063616) (xy 27.086917 -247.112072) (xy 27.052346 -247.155956)
			(xy 27.011744 -247.194329) (xy 26.965981 -247.226372) (xy 26.916034 -247.251399) (xy 26.862972 -247.268875)
			(xy 26.807929 -247.278426) (xy 26.752081 -247.279849) (xy 26.696623 -247.273113) (xy 26.642739 -247.258361)
			(xy 26.591583 -247.23591) (xy 26.544248 -247.206239) (xy 26.52268 -247.188482) (xy 26.509948 -247.178225)
			(xy 26.480518 -247.164004) (xy 26.448437 -247.157745) (xy 26.41582 -247.15986) (xy 26.384816 -247.170211)
			(xy 26.35747 -247.188113) (xy 26.34615 -247.199912) (xy 26.327067 -247.220322) (xy 26.283936 -247.255846)
			(xy 26.236087 -247.2847) (xy 26.184541 -247.306268) (xy 26.130402 -247.32009) (xy 26.074825 -247.325868)
			(xy 26.019 -247.32348) (xy 25.96412 -247.312977) (xy 25.911358 -247.294583) (xy 25.861842 -247.268692)
			(xy 25.816632 -247.235857) (xy 25.776693 -247.19678) (xy 25.742879 -247.152296) (xy 25.715914 -247.103358)
			(xy 25.696373 -247.05101) (xy 25.684675 -246.996372) (xy 25.681069 -246.940612) (xy 10.004552 -246.940612)
			(xy 10.004552 -247.100852) (xy 9.652 -247.453658) (xy 9.366758 -247.7389) (xy 9.365234 -247.7389)
			(xy 9.291066 -247.813068) (xy 9.291066 -248.15546) (xy 9.26773 -248.156729) (xy 9.222082 -248.166717)
			(xy 9.179028 -248.184879) (xy 9.140019 -248.210604) (xy 9.106367 -248.243024) (xy 9.079208 -248.281049)
			(xy 9.059454 -248.323396) (xy 9.047773 -248.36864) (xy 9.044556 -248.415258) (xy 9.049914 -248.461678)
			(xy 9.05637 -248.484136) (xy 9.066126 -248.517537) (xy 9.079145 -248.585894) (xy 9.084621 -248.655264)
			(xy 9.082488 -248.724817) (xy 9.072772 -248.793722) (xy 9.055589 -248.861153) (xy 9.031144 -248.926304)
			(xy 8.99973 -248.988395) (xy 8.997788 -248.991374) (xy 44.07357 -248.991374) (xy 44.077641 -248.935752)
			(xy 44.089767 -248.881315) (xy 44.10969 -248.829224) (xy 44.136986 -248.780589) (xy 44.171072 -248.736446)
			(xy 44.211221 -248.697737) (xy 44.256579 -248.665286) (xy 44.306179 -248.639785) (xy 44.358963 -248.621778)
			(xy 44.413806 -248.611648) (xy 44.46954 -248.609611) (xy 44.524977 -248.615711) (xy 44.578934 -248.629817)
			(xy 44.630263 -248.651629) (xy 44.677869 -248.680683) (xy 44.720737 -248.716358) (xy 44.757954 -248.757895)
			(xy 44.788727 -248.804408) (xy 44.812399 -248.854905) (xy 44.828467 -248.908312) (xy 44.836587 -248.963488)
			(xy 44.837096 -248.991374) (xy 44.836587 -249.01926) (xy 44.828467 -249.074436) (xy 44.812399 -249.127843)
			(xy 44.788727 -249.17834) (xy 44.757954 -249.224853) (xy 44.720737 -249.26639) (xy 44.677869 -249.302065)
			(xy 44.630263 -249.331119) (xy 44.599452 -249.344212) (xy 58.334784 -249.344212) (xy 58.33867 -249.289859)
			(xy 58.350252 -249.236611) (xy 58.369294 -249.185554) (xy 58.395408 -249.137727) (xy 58.428063 -249.094103)
			(xy 58.466594 -249.055571) (xy 58.510217 -249.022914) (xy 58.558044 -248.996799) (xy 58.6091 -248.977755)
			(xy 58.662347 -248.966172) (xy 58.7167 -248.962284) (xy 58.771053 -248.966172) (xy 58.8243 -248.977755)
			(xy 58.875357 -248.996799) (xy 58.923183 -249.022914) (xy 58.945272 -249.038872) (xy 58.964284 -249.052468)
			(xy 59.006167 -249.0732) (xy 59.051135 -249.085926) (xy 59.097672 -249.090216) (xy 59.144209 -249.085926)
			(xy 59.189177 -249.0732) (xy 59.23106 -249.052468) (xy 59.250072 -249.038872) (xy 59.27218 -249.022937)
			(xy 59.320006 -248.996814) (xy 59.371063 -248.977764) (xy 59.424312 -248.966175) (xy 59.478668 -248.962283)
			(xy 59.533025 -248.966166) (xy 59.586276 -248.977746) (xy 59.637336 -248.996788) (xy 59.685167 -249.022902)
			(xy 59.728794 -249.055558) (xy 59.767329 -249.094091) (xy 59.799987 -249.137717) (xy 59.826104 -249.185546)
			(xy 59.845148 -249.236605) (xy 59.856731 -249.289855) (xy 59.860617 -249.344212) (xy 60.221477 -249.344212)
			(xy 60.225363 -249.289857) (xy 60.236945 -249.236608) (xy 60.255988 -249.18555) (xy 60.282103 -249.137721)
			(xy 60.31476 -249.094096) (xy 60.353292 -249.055563) (xy 60.396917 -249.022906) (xy 60.444745 -248.99679)
			(xy 60.495803 -248.977747) (xy 60.549052 -248.966164) (xy 60.603407 -248.962277) (xy 60.657762 -248.966166)
			(xy 60.71101 -248.977751) (xy 60.762068 -248.996796) (xy 60.809895 -249.022913) (xy 60.831984 -249.038872)
			(xy 60.850996 -249.052468) (xy 60.892879 -249.0732) (xy 60.937847 -249.085926) (xy 60.984384 -249.090216)
			(xy 61.030921 -249.085926) (xy 61.075889 -249.0732) (xy 61.117772 -249.052468) (xy 61.136784 -249.038872)
			(xy 61.158891 -249.022938) (xy 61.206717 -248.996817) (xy 61.257773 -248.977769) (xy 61.31102 -248.966181)
			(xy 61.365375 -248.96229) (xy 61.41973 -248.966174) (xy 61.472979 -248.977755) (xy 61.524038 -248.996796)
			(xy 61.571866 -249.02291) (xy 61.615492 -249.055566) (xy 61.654025 -249.094098) (xy 61.686682 -249.137723)
			(xy 61.712798 -249.185551) (xy 61.731842 -249.236609) (xy 61.743424 -249.289857) (xy 61.74731 -249.344212)
			(xy 62.462452 -249.344212) (xy 62.466338 -249.289851) (xy 62.477922 -249.236597) (xy 62.496968 -249.185533)
			(xy 62.523087 -249.1377) (xy 62.555748 -249.094072) (xy 62.594286 -249.055535) (xy 62.637916 -249.022877)
			(xy 62.68575 -248.99676) (xy 62.736815 -248.977717) (xy 62.79007 -248.966136) (xy 62.844431 -248.962252)
			(xy 62.898791 -248.966145) (xy 62.952044 -248.977734) (xy 63.003106 -248.996785) (xy 63.050936 -249.02291)
			(xy 63.073026 -249.038872) (xy 63.092038 -249.052468) (xy 63.133921 -249.0732) (xy 63.178889 -249.085926)
			(xy 63.225426 -249.090216) (xy 63.271963 -249.085926) (xy 63.316931 -249.0732) (xy 63.358814 -249.052468)
			(xy 63.377826 -249.038872) (xy 63.399932 -249.022941) (xy 63.447755 -248.996827) (xy 63.498807 -248.977785)
			(xy 63.55205 -248.966202) (xy 63.606399 -248.962315) (xy 63.660748 -248.966202) (xy 63.713991 -248.977784)
			(xy 63.765043 -248.996826) (xy 63.812866 -249.02294) (xy 63.856485 -249.055594) (xy 63.895013 -249.094123)
			(xy 63.927666 -249.137743) (xy 63.953778 -249.185567) (xy 63.972819 -249.23662) (xy 63.984399 -249.289863)
			(xy 63.988285 -249.344212) (xy 64.366461 -249.344212) (xy 64.370348 -249.289853) (xy 64.381931 -249.236601)
			(xy 64.400975 -249.18554) (xy 64.427093 -249.137708) (xy 64.459752 -249.094081) (xy 64.498288 -249.055546)
			(xy 64.541916 -249.022888) (xy 64.589748 -248.996771) (xy 64.64081 -248.977728) (xy 64.694063 -248.966146)
			(xy 64.748422 -248.962261) (xy 64.80278 -248.966153) (xy 64.856031 -248.977741) (xy 64.907091 -248.996789)
			(xy 64.95492 -249.022911) (xy 64.97701 -249.038872) (xy 64.996022 -249.052468) (xy 65.037905 -249.0732)
			(xy 65.082873 -249.085926) (xy 65.12941 -249.090216) (xy 65.175947 -249.085926) (xy 65.220915 -249.0732)
			(xy 65.262798 -249.052468) (xy 65.28181 -249.038872) (xy 65.303917 -249.02294) (xy 65.35174 -248.996823)
			(xy 65.402794 -248.977779) (xy 65.456038 -248.966194) (xy 65.51039 -248.962305) (xy 65.564741 -248.966191)
			(xy 65.617986 -248.977773) (xy 65.669041 -248.996815) (xy 65.716866 -249.022929) (xy 65.760488 -249.055583)
			(xy 65.799018 -249.094114) (xy 65.831672 -249.137735) (xy 65.857786 -249.185561) (xy 65.876827 -249.236615)
			(xy 65.888409 -249.289861) (xy 65.892295 -249.344212) (xy 65.888405 -249.398563) (xy 65.876821 -249.451808)
			(xy 65.857776 -249.502861) (xy 65.831659 -249.550685) (xy 65.799002 -249.594304) (xy 65.760469 -249.632832)
			(xy 65.716846 -249.665484) (xy 65.669019 -249.691595) (xy 65.617963 -249.710634) (xy 65.564717 -249.722212)
			(xy 65.510366 -249.726095) (xy 65.456015 -249.722202) (xy 65.402771 -249.710614) (xy 65.351718 -249.691567)
			(xy 65.303896 -249.665447) (xy 65.28181 -249.649488) (xy 65.262798 -249.635892) (xy 65.220915 -249.61516)
			(xy 65.175947 -249.602434) (xy 65.12941 -249.598144) (xy 65.082873 -249.602434) (xy 65.037905 -249.61516)
			(xy 64.996022 -249.635892) (xy 64.97701 -249.649488) (xy 64.95494 -249.665476) (xy 64.907113 -249.691601)
			(xy 64.856054 -249.710653) (xy 64.802804 -249.722244) (xy 64.748446 -249.726139) (xy 64.694087 -249.722257)
			(xy 64.640833 -249.710678) (xy 64.58977 -249.691639) (xy 64.541937 -249.665525) (xy 64.498306 -249.63287)
			(xy 64.459768 -249.594337) (xy 64.427106 -249.550712) (xy 64.400985 -249.502882) (xy 64.381938 -249.451822)
			(xy 64.370351 -249.39857) (xy 64.366461 -249.344212) (xy 63.988285 -249.344212) (xy 63.984396 -249.398561)
			(xy 63.972812 -249.451803) (xy 63.953768 -249.502855) (xy 63.927653 -249.550677) (xy 63.894998 -249.594295)
			(xy 63.856467 -249.632822) (xy 63.812845 -249.665473) (xy 63.765021 -249.691584) (xy 63.713967 -249.710622)
			(xy 63.660724 -249.722201) (xy 63.606375 -249.726085) (xy 63.552026 -249.722194) (xy 63.498784 -249.710608)
			(xy 63.447733 -249.691563) (xy 63.399912 -249.665446) (xy 63.377826 -249.649488) (xy 63.358814 -249.635892)
			(xy 63.316931 -249.61516) (xy 63.271963 -249.602434) (xy 63.225426 -249.598144) (xy 63.178889 -249.602434)
			(xy 63.133921 -249.61516) (xy 63.092038 -249.635892) (xy 63.073026 -249.649488) (xy 63.050956 -249.665477)
			(xy 63.003127 -249.691605) (xy 62.952067 -249.710659) (xy 62.898815 -249.722252) (xy 62.844455 -249.726148)
			(xy 62.790094 -249.722268) (xy 62.736838 -249.71069) (xy 62.685772 -249.69165) (xy 62.637936 -249.665536)
			(xy 62.594304 -249.63288) (xy 62.555763 -249.594347) (xy 62.5231 -249.55072) (xy 62.496978 -249.502889)
			(xy 62.477929 -249.451826) (xy 62.466342 -249.398573) (xy 62.462452 -249.344212) (xy 61.74731 -249.344212)
			(xy 61.743421 -249.398567) (xy 61.731835 -249.451815) (xy 61.712788 -249.502871) (xy 61.686669 -249.550698)
			(xy 61.654009 -249.59432) (xy 61.615474 -249.63285) (xy 61.571846 -249.665502) (xy 61.524016 -249.691614)
			(xy 61.472956 -249.710652) (xy 61.419706 -249.722229) (xy 61.365351 -249.72611) (xy 61.310997 -249.722215)
			(xy 61.25775 -249.710624) (xy 61.206695 -249.691573) (xy 61.158871 -249.665449) (xy 61.136784 -249.649488)
			(xy 61.117772 -249.635892) (xy 61.075889 -249.61516) (xy 61.030921 -249.602434) (xy 60.984384 -249.598144)
			(xy 60.937847 -249.602434) (xy 60.892879 -249.61516) (xy 60.850996 -249.635892) (xy 60.831984 -249.649488)
			(xy 60.809915 -249.665474) (xy 60.762089 -249.691594) (xy 60.711033 -249.710643) (xy 60.657786 -249.722231)
			(xy 60.603431 -249.726123) (xy 60.549076 -249.72224) (xy 60.495826 -249.71066) (xy 60.444767 -249.69162)
			(xy 60.396937 -249.665507) (xy 60.353311 -249.632853) (xy 60.314775 -249.594322) (xy 60.282116 -249.550699)
			(xy 60.255998 -249.502872) (xy 60.236952 -249.451815) (xy 60.225366 -249.398567) (xy 60.221477 -249.344212)
			(xy 59.860617 -249.344212) (xy 59.856728 -249.398568) (xy 59.845141 -249.451818) (xy 59.826094 -249.502876)
			(xy 59.799974 -249.550704) (xy 59.767313 -249.594327) (xy 59.728775 -249.632857) (xy 59.685146 -249.665511)
			(xy 59.637314 -249.691622) (xy 59.586252 -249.71066) (xy 59.533001 -249.722237) (xy 59.478644 -249.726117)
			(xy 59.424288 -249.722221) (xy 59.37104 -249.710629) (xy 59.319984 -249.691576) (xy 59.272159 -249.66545)
			(xy 59.250072 -249.649488) (xy 59.23106 -249.635892) (xy 59.189177 -249.61516) (xy 59.144209 -249.602434)
			(xy 59.097672 -249.598144) (xy 59.051135 -249.602434) (xy 59.006167 -249.61516) (xy 58.964284 -249.635892)
			(xy 58.945272 -249.649488) (xy 58.923203 -249.665473) (xy 58.875378 -249.691591) (xy 58.824323 -249.710638)
			(xy 58.771077 -249.722225) (xy 58.716724 -249.726116) (xy 58.662371 -249.722232) (xy 58.609123 -249.710652)
			(xy 58.558065 -249.691611) (xy 58.510237 -249.665499) (xy 58.466612 -249.632845) (xy 58.428079 -249.594315)
			(xy 58.395421 -249.550693) (xy 58.369304 -249.502867) (xy 58.350259 -249.451812) (xy 58.338673 -249.398565)
			(xy 58.334784 -249.344212) (xy 44.599452 -249.344212) (xy 44.578934 -249.352931) (xy 44.524977 -249.367037)
			(xy 44.46954 -249.373137) (xy 44.413806 -249.3711) (xy 44.358963 -249.36097) (xy 44.306179 -249.342963)
			(xy 44.256579 -249.317462) (xy 44.211221 -249.285011) (xy 44.171072 -249.246302) (xy 44.136986 -249.202159)
			(xy 44.10969 -249.153524) (xy 44.089767 -249.101433) (xy 44.077641 -249.046996) (xy 44.07357 -248.991374)
			(xy 8.997788 -248.991374) (xy 8.961722 -249.046685) (xy 8.917577 -249.100475) (xy 8.86782 -249.149121)
			(xy 8.840724 -249.170952) (xy 8.81888 -249.216164) (xy 8.81888 -249.789442) (xy 46.51451 -249.789442)
			(xy 46.518581 -249.73382) (xy 46.530707 -249.679383) (xy 46.55063 -249.627292) (xy 46.577926 -249.578657)
			(xy 46.612012 -249.534514) (xy 46.652161 -249.495805) (xy 46.697519 -249.463354) (xy 46.747119 -249.437853)
			(xy 46.799903 -249.419846) (xy 46.854746 -249.409716) (xy 46.91048 -249.407679) (xy 46.965917 -249.413779)
			(xy 47.019874 -249.427885) (xy 47.071203 -249.449697) (xy 47.118809 -249.478751) (xy 47.161677 -249.514426)
			(xy 47.198894 -249.555963) (xy 47.229667 -249.602476) (xy 47.253339 -249.652973) (xy 47.269407 -249.70638)
			(xy 47.277527 -249.761556) (xy 47.278036 -249.789442) (xy 47.277527 -249.817328) (xy 47.269407 -249.872504)
			(xy 47.253339 -249.925911) (xy 47.229667 -249.976408) (xy 47.198894 -250.022921) (xy 47.161677 -250.064458)
			(xy 47.118809 -250.100133) (xy 47.071203 -250.129187) (xy 47.019874 -250.150999) (xy 46.965917 -250.165105)
			(xy 46.91048 -250.171205) (xy 46.854746 -250.169168) (xy 46.799903 -250.159038) (xy 46.747119 -250.141031)
			(xy 46.697519 -250.11553) (xy 46.652161 -250.083079) (xy 46.612012 -250.04437) (xy 46.577926 -250.000227)
			(xy 46.55063 -249.951592) (xy 46.530707 -249.899501) (xy 46.518581 -249.845064) (xy 46.51451 -249.789442)
			(xy 8.81888 -249.789442) (xy 8.81888 -250.675394) (xy 8.81942 -250.692012) (xy 8.82801 -250.724118)
			(xy 8.844608 -250.752912) (xy 8.855964 -250.765056) (xy 9.794551 -251.703586) (xy 24.545288 -251.703586)
			(xy 24.549359 -251.647964) (xy 24.561485 -251.593527) (xy 24.581408 -251.541436) (xy 24.608704 -251.492801)
			(xy 24.64279 -251.448658) (xy 24.682939 -251.409949) (xy 24.728297 -251.377498) (xy 24.777897 -251.351997)
			(xy 24.830681 -251.33399) (xy 24.885524 -251.32386) (xy 24.941258 -251.321823) (xy 24.996695 -251.327923)
			(xy 25.050652 -251.342029) (xy 25.101981 -251.363841) (xy 25.149587 -251.392895) (xy 25.192455 -251.42857)
			(xy 25.211058 -251.449332) (xy 44.25645 -251.449332) (xy 44.260521 -251.39371) (xy 44.272647 -251.339273)
			(xy 44.29257 -251.287182) (xy 44.319866 -251.238547) (xy 44.353952 -251.194404) (xy 44.394101 -251.155695)
			(xy 44.439459 -251.123244) (xy 44.489059 -251.097743) (xy 44.541843 -251.079736) (xy 44.596686 -251.069606)
			(xy 44.65242 -251.067569) (xy 44.707857 -251.073669) (xy 44.761814 -251.087775) (xy 44.813143 -251.109587)
			(xy 44.860749 -251.138641) (xy 44.903617 -251.174316) (xy 44.940834 -251.215853) (xy 44.953303 -251.234699)
			(xy 58.334802 -251.234699) (xy 58.338689 -251.180348) (xy 58.350272 -251.127104) (xy 58.369315 -251.07605)
			(xy 58.39543 -251.028226) (xy 58.428085 -250.984605) (xy 58.466616 -250.946076) (xy 58.510238 -250.913422)
			(xy 58.558063 -250.887309) (xy 58.609118 -250.868268) (xy 58.662362 -250.856687) (xy 58.716713 -250.852802)
			(xy 58.771064 -250.856691) (xy 58.824308 -250.868276) (xy 58.875361 -250.88732) (xy 58.923185 -250.913436)
			(xy 58.945272 -250.929394) (xy 58.964284 -250.94299) (xy 59.006167 -250.963722) (xy 59.051135 -250.976448)
			(xy 59.097672 -250.980738) (xy 59.144209 -250.976448) (xy 59.189177 -250.963722) (xy 59.23106 -250.94299)
			(xy 59.250072 -250.929394) (xy 59.272159 -250.913429) (xy 59.319987 -250.887304) (xy 59.371045 -250.868251)
			(xy 59.424296 -250.85666) (xy 59.478655 -250.852765) (xy 59.533014 -250.856647) (xy 59.586268 -250.868226)
			(xy 59.637331 -250.887266) (xy 59.685165 -250.91338) (xy 59.728795 -250.946036) (xy 59.767333 -250.98457)
			(xy 59.799995 -251.028196) (xy 59.826115 -251.076027) (xy 59.845161 -251.127088) (xy 59.856747 -251.18034)
			(xy 59.860635 -251.234699) (xy 60.221495 -251.234699) (xy 60.225382 -251.180346) (xy 60.236966 -251.1271)
			(xy 60.256009 -251.076045) (xy 60.282125 -251.02822) (xy 60.314782 -250.984598) (xy 60.353314 -250.946068)
			(xy 60.396938 -250.913414) (xy 60.444764 -250.8873) (xy 60.495821 -250.86826) (xy 60.549067 -250.856679)
			(xy 60.60342 -250.852795) (xy 60.657772 -250.856685) (xy 60.711018 -250.868271) (xy 60.762072 -250.887317)
			(xy 60.809896 -250.913435) (xy 60.831984 -250.929394) (xy 60.850996 -250.94299) (xy 60.892879 -250.963722)
			(xy 60.937847 -250.976448) (xy 60.984384 -250.980738) (xy 61.030921 -250.976448) (xy 61.075889 -250.963722)
			(xy 61.117772 -250.94299) (xy 61.136784 -250.929394) (xy 61.158871 -250.91343) (xy 61.206697 -250.887306)
			(xy 61.257755 -250.868256) (xy 61.311005 -250.856666) (xy 61.365362 -250.852772) (xy 61.419719 -250.856655)
			(xy 61.472971 -250.868234) (xy 61.524033 -250.887275) (xy 61.571865 -250.913389) (xy 61.615493 -250.946044)
			(xy 61.65403 -250.984577) (xy 61.68669 -251.028202) (xy 61.712809 -251.076031) (xy 61.731855 -251.127091)
			(xy 61.74344 -251.180341) (xy 61.747328 -251.234699) (xy 62.462469 -251.234699) (xy 62.466358 -251.180341)
			(xy 62.477943 -251.127089) (xy 62.496989 -251.076029) (xy 62.523109 -251.028199) (xy 62.55577 -250.984573)
			(xy 62.594307 -250.94604) (xy 62.637937 -250.913384) (xy 62.68577 -250.88727) (xy 62.736833 -250.86823)
			(xy 62.790085 -250.856651) (xy 62.844444 -250.852769) (xy 62.898802 -250.856664) (xy 62.952052 -250.868255)
			(xy 63.00311 -250.887307) (xy 63.050937 -250.913432) (xy 63.073026 -250.929394) (xy 63.092038 -250.94299)
			(xy 63.133921 -250.963722) (xy 63.178889 -250.976448) (xy 63.225426 -250.980738) (xy 63.271963 -250.976448)
			(xy 63.316931 -250.963722) (xy 63.358814 -250.94299) (xy 63.377826 -250.929394) (xy 63.399912 -250.913434)
			(xy 63.447736 -250.887317) (xy 63.498789 -250.868272) (xy 63.552034 -250.856687) (xy 63.606386 -250.852797)
			(xy 63.660737 -250.856683) (xy 63.713983 -250.868264) (xy 63.765038 -250.887305) (xy 63.812864 -250.913418)
			(xy 63.856487 -250.946072) (xy 63.895018 -250.984602) (xy 63.927674 -251.028223) (xy 63.953789 -251.076048)
			(xy 63.972832 -251.127102) (xy 63.984415 -251.180347) (xy 63.988303 -251.234699) (xy 64.366479 -251.234699)
			(xy 64.370367 -251.180343) (xy 64.381952 -251.127093) (xy 64.400997 -251.076035) (xy 64.427115 -251.028207)
			(xy 64.459774 -250.984582) (xy 64.49831 -250.946051) (xy 64.541937 -250.913395) (xy 64.589768 -250.887282)
			(xy 64.640828 -250.868241) (xy 64.694079 -250.856662) (xy 64.748435 -250.852779) (xy 64.802791 -250.856672)
			(xy 64.856039 -250.868261) (xy 64.907096 -250.887311) (xy 64.954922 -250.913433) (xy 64.97701 -250.929394)
			(xy 64.996022 -250.94299) (xy 65.037905 -250.963722) (xy 65.082873 -250.976448) (xy 65.12941 -250.980738)
			(xy 65.175947 -250.976448) (xy 65.220915 -250.963722) (xy 65.262798 -250.94299) (xy 65.28181 -250.929394)
			(xy 65.303896 -250.913432) (xy 65.351721 -250.887313) (xy 65.402776 -250.868266) (xy 65.456023 -250.856679)
			(xy 65.510376 -250.852788) (xy 65.56473 -250.856672) (xy 65.617978 -250.868253) (xy 65.669036 -250.887293)
			(xy 65.716864 -250.913407) (xy 65.760489 -250.946061) (xy 65.799022 -250.984592) (xy 65.83168 -251.028215)
			(xy 65.857796 -251.076041) (xy 65.876841 -251.127098) (xy 65.888424 -251.180345) (xy 65.892312 -251.234699)
			(xy 65.888425 -251.289053) (xy 65.876841 -251.3423) (xy 65.857797 -251.393356) (xy 65.831681 -251.441183)
			(xy 65.799024 -251.484806) (xy 65.760491 -251.523337) (xy 65.716866 -251.555992) (xy 65.669038 -251.582106)
			(xy 65.617981 -251.601147) (xy 65.564733 -251.612728) (xy 65.510379 -251.616612) (xy 65.456025 -251.612722)
			(xy 65.402779 -251.601135) (xy 65.351723 -251.582088) (xy 65.303898 -251.555969) (xy 65.28181 -251.54001)
			(xy 65.262798 -251.526414) (xy 65.220915 -251.505682) (xy 65.175947 -251.492956) (xy 65.12941 -251.488666)
			(xy 65.082873 -251.492956) (xy 65.037905 -251.505682) (xy 64.996022 -251.526414) (xy 64.97701 -251.54001)
			(xy 64.95492 -251.555968) (xy 64.907094 -251.58209) (xy 64.856037 -251.60114) (xy 64.802788 -251.612728)
			(xy 64.748433 -251.616621) (xy 64.694076 -251.612738) (xy 64.640826 -251.601158) (xy 64.589766 -251.582117)
			(xy 64.541935 -251.556003) (xy 64.498308 -251.523348) (xy 64.459773 -251.484816) (xy 64.427114 -251.441191)
			(xy 64.400996 -251.393363) (xy 64.381951 -251.342304) (xy 64.370367 -251.289055) (xy 64.366479 -251.234699)
			(xy 63.988303 -251.234699) (xy 63.984415 -251.28905) (xy 63.972832 -251.342296) (xy 63.95379 -251.39335)
			(xy 63.927675 -251.441175) (xy 63.89502 -251.484797) (xy 63.856488 -251.523327) (xy 63.812866 -251.555981)
			(xy 63.76504 -251.582094) (xy 63.713985 -251.601136) (xy 63.66074 -251.612717) (xy 63.606388 -251.616603)
			(xy 63.552036 -251.612713) (xy 63.498792 -251.601129) (xy 63.447738 -251.582084) (xy 63.399914 -251.555968)
			(xy 63.377826 -251.54001) (xy 63.358814 -251.526414) (xy 63.316931 -251.505682) (xy 63.271963 -251.492956)
			(xy 63.225426 -251.488666) (xy 63.178889 -251.492956) (xy 63.133921 -251.505682) (xy 63.092038 -251.526414)
			(xy 63.073026 -251.54001) (xy 63.050935 -251.555969) (xy 63.003108 -251.582094) (xy 62.95205 -251.601146)
			(xy 62.898799 -251.612737) (xy 62.844442 -251.616631) (xy 62.790083 -251.612748) (xy 62.73683 -251.601169)
			(xy 62.685768 -251.582129) (xy 62.637935 -251.556014) (xy 62.594305 -251.523358) (xy 62.555768 -251.484825)
			(xy 62.523107 -251.441199) (xy 62.496988 -251.393369) (xy 62.477942 -251.342309) (xy 62.466357 -251.289057)
			(xy 62.462469 -251.234699) (xy 61.747328 -251.234699) (xy 61.74344 -251.289056) (xy 61.731855 -251.342307)
			(xy 61.71281 -251.393367) (xy 61.686691 -251.441196) (xy 61.654031 -251.484821) (xy 61.615495 -251.523354)
			(xy 61.571867 -251.55601) (xy 61.524035 -251.582124) (xy 61.472973 -251.601165) (xy 61.419722 -251.612745)
			(xy 61.365364 -251.616628) (xy 61.311007 -251.612735) (xy 61.257758 -251.601145) (xy 61.2067 -251.582095)
			(xy 61.158873 -251.555971) (xy 61.136784 -251.54001) (xy 61.117772 -251.526414) (xy 61.075889 -251.505682)
			(xy 61.030921 -251.492956) (xy 60.984384 -251.488666) (xy 60.937847 -251.492956) (xy 60.892879 -251.505682)
			(xy 60.850996 -251.526414) (xy 60.831984 -251.54001) (xy 60.809894 -251.555966) (xy 60.76207 -251.582084)
			(xy 60.711015 -251.60113) (xy 60.65777 -251.612715) (xy 60.603418 -251.616605) (xy 60.549065 -251.61272)
			(xy 60.495819 -251.60114) (xy 60.444762 -251.582099) (xy 60.396936 -251.555985) (xy 60.353312 -251.523331)
			(xy 60.31478 -251.4848) (xy 60.282124 -251.441178) (xy 60.256008 -251.393353) (xy 60.236965 -251.342297)
			(xy 60.225382 -251.289051) (xy 60.221495 -251.234699) (xy 59.860635 -251.234699) (xy 59.856747 -251.289058)
			(xy 59.845162 -251.34231) (xy 59.826116 -251.393371) (xy 59.799996 -251.441202) (xy 59.767335 -251.484828)
			(xy 59.728797 -251.523362) (xy 59.685167 -251.556019) (xy 59.637333 -251.582133) (xy 59.58627 -251.601174)
			(xy 59.533017 -251.612753) (xy 59.478657 -251.616635) (xy 59.424299 -251.612741) (xy 59.371048 -251.60115)
			(xy 59.319989 -251.582097) (xy 59.272161 -251.555972) (xy 59.250072 -251.54001) (xy 59.23106 -251.526414)
			(xy 59.189177 -251.505682) (xy 59.144209 -251.492956) (xy 59.097672 -251.488666) (xy 59.051135 -251.492956)
			(xy 59.006167 -251.505682) (xy 58.964284 -251.526414) (xy 58.945272 -251.54001) (xy 58.923183 -251.555965)
			(xy 58.875359 -251.582081) (xy 58.824306 -251.601125) (xy 58.771062 -251.612709) (xy 58.716711 -251.616598)
			(xy 58.66236 -251.612712) (xy 58.609115 -251.601131) (xy 58.558061 -251.58209) (xy 58.510236 -251.555977)
			(xy 58.466614 -251.523323) (xy 58.428083 -251.484793) (xy 58.395429 -251.441172) (xy 58.369314 -251.393348)
			(xy 58.350272 -251.342294) (xy 58.338689 -251.28905) (xy 58.334802 -251.234699) (xy 44.953303 -251.234699)
			(xy 44.971607 -251.262366) (xy 44.995279 -251.312863) (xy 45.011347 -251.36627) (xy 45.019467 -251.421446)
			(xy 45.019976 -251.449332) (xy 45.019467 -251.477218) (xy 45.011347 -251.532394) (xy 44.995279 -251.585801)
			(xy 44.971607 -251.636298) (xy 44.940834 -251.682811) (xy 44.903617 -251.724348) (xy 44.860749 -251.760023)
			(xy 44.813143 -251.789077) (xy 44.761814 -251.810889) (xy 44.707857 -251.824995) (xy 44.65242 -251.831095)
			(xy 44.596686 -251.829058) (xy 44.541843 -251.818928) (xy 44.489059 -251.800921) (xy 44.439459 -251.77542)
			(xy 44.394101 -251.742969) (xy 44.353952 -251.70426) (xy 44.319866 -251.660117) (xy 44.29257 -251.611482)
			(xy 44.272647 -251.559391) (xy 44.260521 -251.504954) (xy 44.25645 -251.449332) (xy 25.211058 -251.449332)
			(xy 25.229672 -251.470107) (xy 25.260445 -251.51662) (xy 25.284117 -251.567117) (xy 25.300185 -251.620524)
			(xy 25.308305 -251.6757) (xy 25.308814 -251.703586) (xy 25.308305 -251.731472) (xy 25.300185 -251.786648)
			(xy 25.284117 -251.840055) (xy 25.260445 -251.890552) (xy 25.229672 -251.937065) (xy 25.192455 -251.978602)
			(xy 25.149587 -252.014277) (xy 25.101981 -252.043331) (xy 25.050652 -252.065143) (xy 24.996695 -252.079249)
			(xy 24.941258 -252.085349) (xy 24.885524 -252.083312) (xy 24.830681 -252.073182) (xy 24.777897 -252.055175)
			(xy 24.728297 -252.029674) (xy 24.682939 -251.997223) (xy 24.64279 -251.958514) (xy 24.608704 -251.914371)
			(xy 24.581408 -251.865736) (xy 24.561485 -251.813645) (xy 24.549359 -251.759208) (xy 24.545288 -251.703586)
			(xy 9.794551 -251.703586) (xy 11.496708 -253.40564) (xy 44.182028 -253.40564) (xy 44.186099 -253.350018)
			(xy 44.198225 -253.295581) (xy 44.218148 -253.24349) (xy 44.245444 -253.194855) (xy 44.27953 -253.150712)
			(xy 44.319679 -253.112003) (xy 44.365037 -253.079552) (xy 44.414637 -253.054051) (xy 44.467421 -253.036044)
			(xy 44.522264 -253.025914) (xy 44.577998 -253.023877) (xy 44.633435 -253.029977) (xy 44.687392 -253.044083)
			(xy 44.738721 -253.065895) (xy 44.786327 -253.094949) (xy 44.829195 -253.130624) (xy 44.866412 -253.172161)
			(xy 44.897185 -253.218674) (xy 44.920857 -253.269171) (xy 44.922843 -253.275772) (xy 58.334837 -253.275772)
			(xy 58.338728 -253.221427) (xy 58.350314 -253.168188) (xy 58.369358 -253.11714) (xy 58.395474 -253.069322)
			(xy 58.428129 -253.025708) (xy 58.466659 -252.987185) (xy 58.510279 -252.954537) (xy 58.558102 -252.92843)
			(xy 58.609153 -252.909395) (xy 58.662393 -252.897818) (xy 58.71674 -252.893937) (xy 58.771085 -252.89783)
			(xy 58.824323 -252.909417) (xy 58.875371 -252.928463) (xy 58.923188 -252.95458) (xy 58.945272 -252.970538)
			(xy 58.964284 -252.984134) (xy 59.006167 -253.004866) (xy 59.051135 -253.017592) (xy 59.097672 -253.021882)
			(xy 59.144209 -253.017592) (xy 59.189177 -253.004866) (xy 59.23106 -252.984134) (xy 59.250072 -252.970538)
			(xy 59.272118 -252.954514) (xy 59.319948 -252.928382) (xy 59.37101 -252.909325) (xy 59.424265 -252.897729)
			(xy 59.478628 -252.89383) (xy 59.532993 -252.897708) (xy 59.586252 -252.909284) (xy 59.637322 -252.928323)
			(xy 59.685162 -252.954436) (xy 59.728798 -252.987092) (xy 59.767343 -253.025627) (xy 59.80001 -253.069255)
			(xy 59.826136 -253.117088) (xy 59.845188 -253.168152) (xy 59.856778 -253.221409) (xy 59.86067 -253.275772)
			(xy 60.22153 -253.275772) (xy 60.225421 -253.221425) (xy 60.237007 -253.168185) (xy 60.256052 -253.117136)
			(xy 60.282169 -253.069316) (xy 60.314826 -253.025701) (xy 60.353357 -252.987177) (xy 60.396979 -252.954529)
			(xy 60.444803 -252.928422) (xy 60.495856 -252.909386) (xy 60.549099 -252.89781) (xy 60.603447 -252.89393)
			(xy 60.657794 -252.897824) (xy 60.711033 -252.909412) (xy 60.762082 -252.92846) (xy 60.8099 -252.954579)
			(xy 60.831984 -252.970538) (xy 60.850996 -252.984134) (xy 60.892879 -253.004866) (xy 60.937847 -253.017592)
			(xy 60.984384 -253.021882) (xy 61.030921 -253.017592) (xy 61.075889 -253.004866) (xy 61.117772 -252.984134)
			(xy 61.136784 -252.970538) (xy 61.158829 -252.954515) (xy 61.206659 -252.928385) (xy 61.25772 -252.909329)
			(xy 61.310974 -252.897735) (xy 61.365335 -252.893837) (xy 61.419698 -252.897716) (xy 61.472956 -252.909293)
			(xy 61.524023 -252.928332) (xy 61.571862 -252.954445) (xy 61.615496 -252.9871) (xy 61.654039 -253.025634)
			(xy 61.686705 -253.069261) (xy 61.71283 -253.117093) (xy 61.731881 -253.168156) (xy 61.743471 -253.22141)
			(xy 61.747363 -253.275772) (xy 62.462505 -253.275772) (xy 62.466396 -253.221419) (xy 62.477984 -253.168174)
			(xy 62.497032 -253.117119) (xy 62.523153 -253.069295) (xy 62.555814 -253.025676) (xy 62.59435 -252.987149)
			(xy 62.637978 -252.9545) (xy 62.685808 -252.928391) (xy 62.736868 -252.909357) (xy 62.790117 -252.897782)
			(xy 62.84447 -252.893905) (xy 62.898823 -252.897802) (xy 62.952067 -252.909396) (xy 63.00312 -252.92845)
			(xy 63.050941 -252.954576) (xy 63.073026 -252.970538) (xy 63.092038 -252.984134) (xy 63.133921 -253.004866)
			(xy 63.178889 -253.017592) (xy 63.225426 -253.021882) (xy 63.271963 -253.017592) (xy 63.316931 -253.004866)
			(xy 63.358814 -252.984134) (xy 63.377826 -252.970538) (xy 63.39987 -252.954518) (xy 63.447697 -252.928396)
			(xy 63.498754 -252.909346) (xy 63.552003 -252.897756) (xy 63.606359 -252.893862) (xy 63.660716 -252.897744)
			(xy 63.713967 -252.909323) (xy 63.765029 -252.928362) (xy 63.812861 -252.954474) (xy 63.85649 -252.987128)
			(xy 63.895027 -253.025659) (xy 63.927689 -253.069282) (xy 63.95381 -253.117109) (xy 63.972858 -253.168167)
			(xy 63.984446 -253.221416) (xy 63.988338 -253.275772) (xy 64.366514 -253.275772) (xy 64.370406 -253.221422)
			(xy 64.381993 -253.168178) (xy 64.40104 -253.117125) (xy 64.427159 -253.069303) (xy 64.459818 -253.025686)
			(xy 64.498353 -252.98716) (xy 64.541978 -252.954511) (xy 64.589806 -252.928403) (xy 64.640863 -252.909368)
			(xy 64.69411 -252.897793) (xy 64.748461 -252.893914) (xy 64.802812 -252.897811) (xy 64.856054 -252.909402)
			(xy 64.907105 -252.928454) (xy 64.954925 -252.954577) (xy 64.97701 -252.970538) (xy 64.996022 -252.984134)
			(xy 65.037905 -253.004866) (xy 65.082873 -253.017592) (xy 65.12941 -253.021882) (xy 65.175947 -253.017592)
			(xy 65.220915 -253.004866) (xy 65.262798 -252.984134) (xy 65.28181 -252.970538) (xy 65.303855 -252.954517)
			(xy 65.351682 -252.928392) (xy 65.402741 -252.909339) (xy 65.455992 -252.897748) (xy 65.51035 -252.893853)
			(xy 65.564709 -252.897734) (xy 65.617963 -252.909311) (xy 65.669027 -252.92835) (xy 65.716861 -252.954463)
			(xy 65.760492 -252.987117) (xy 65.799032 -253.025649) (xy 65.831695 -253.069274) (xy 65.857818 -253.117103)
			(xy 65.876867 -253.168163) (xy 65.888455 -253.221414) (xy 65.892347 -253.275772) (xy 65.888463 -253.330131)
			(xy 65.876882 -253.383384) (xy 65.85784 -253.434447) (xy 65.831725 -253.48228) (xy 65.799068 -253.525909)
			(xy 65.760534 -253.564446) (xy 65.716908 -253.597107) (xy 65.669077 -253.623227) (xy 65.618016 -253.642273)
			(xy 65.564764 -253.653859) (xy 65.510405 -253.657747) (xy 65.456046 -253.65386) (xy 65.402794 -253.642276)
			(xy 65.351733 -253.623231) (xy 65.303901 -253.597113) (xy 65.28181 -253.581154) (xy 65.262798 -253.567558)
			(xy 65.220915 -253.546826) (xy 65.175947 -253.5341) (xy 65.12941 -253.52981) (xy 65.082873 -253.5341)
			(xy 65.037905 -253.546826) (xy 64.996022 -253.567558) (xy 64.97701 -253.581154) (xy 64.954878 -253.597053)
			(xy 64.907055 -253.623169) (xy 64.856001 -253.642213) (xy 64.802757 -253.653797) (xy 64.748406 -253.657686)
			(xy 64.694055 -253.653799) (xy 64.64081 -253.642217) (xy 64.589756 -253.623174) (xy 64.541932 -253.597059)
			(xy 64.498311 -253.564404) (xy 64.459782 -253.525873) (xy 64.427129 -253.48225) (xy 64.401017 -253.434424)
			(xy 64.381977 -253.383369) (xy 64.370398 -253.330124) (xy 64.366514 -253.275772) (xy 63.988338 -253.275772)
			(xy 63.984454 -253.330129) (xy 63.972874 -253.38338) (xy 63.953833 -253.434441) (xy 63.927719 -253.482272)
			(xy 63.895063 -253.5259) (xy 63.856531 -253.564436) (xy 63.812907 -253.597096) (xy 63.765079 -253.623215)
			(xy 63.71402 -253.642262) (xy 63.660771 -253.653848) (xy 63.606414 -253.657738) (xy 63.552058 -253.653852)
			(xy 63.498807 -253.64227) (xy 63.447747 -253.623227) (xy 63.399917 -253.597112) (xy 63.377826 -253.581154)
			(xy 63.358814 -253.567558) (xy 63.316931 -253.546826) (xy 63.271963 -253.5341) (xy 63.225426 -253.52981)
			(xy 63.178889 -253.5341) (xy 63.133921 -253.546826) (xy 63.092038 -253.567558) (xy 63.073026 -253.581154)
			(xy 63.050894 -253.597054) (xy 63.00307 -253.623173) (xy 62.952014 -253.642219) (xy 62.898768 -253.653805)
			(xy 62.844415 -253.657695) (xy 62.790062 -253.65381) (xy 62.736815 -253.642228) (xy 62.685758 -253.623186)
			(xy 62.637932 -253.597071) (xy 62.594309 -253.564414) (xy 62.555777 -253.525882) (xy 62.523123 -253.482258)
			(xy 62.497009 -253.434431) (xy 62.477969 -253.383373) (xy 62.466388 -253.330126) (xy 62.462505 -253.275772)
			(xy 61.747363 -253.275772) (xy 61.743479 -253.330135) (xy 61.731897 -253.383391) (xy 61.712853 -253.434457)
			(xy 61.686735 -253.482293) (xy 61.654075 -253.525924) (xy 61.615538 -253.564464) (xy 61.571908 -253.597126)
			(xy 61.524074 -253.623245) (xy 61.473009 -253.642292) (xy 61.419753 -253.653876) (xy 61.36539 -253.657763)
			(xy 61.311028 -253.653873) (xy 61.257773 -253.642286) (xy 61.206709 -253.623238) (xy 61.158876 -253.597115)
			(xy 61.136784 -253.581154) (xy 61.117772 -253.567558) (xy 61.075889 -253.546826) (xy 61.030921 -253.5341)
			(xy 60.984384 -253.52981) (xy 60.937847 -253.5341) (xy 60.892879 -253.546826) (xy 60.850996 -253.567558)
			(xy 60.831984 -253.581154) (xy 60.809853 -253.597051) (xy 60.762031 -253.623163) (xy 60.71098 -253.642203)
			(xy 60.657739 -253.653784) (xy 60.603391 -253.65767) (xy 60.549044 -253.653782) (xy 60.495803 -253.642198)
			(xy 60.444753 -253.623156) (xy 60.396932 -253.597041) (xy 60.353315 -253.564387) (xy 60.314789 -253.525857)
			(xy 60.282139 -253.482237) (xy 60.256029 -253.434414) (xy 60.236992 -253.383362) (xy 60.225413 -253.33012)
			(xy 60.22153 -253.275772) (xy 59.86067 -253.275772) (xy 59.856786 -253.330137) (xy 59.845203 -253.383395)
			(xy 59.826159 -253.434462) (xy 59.80004 -253.482299) (xy 59.767379 -253.525931) (xy 59.72884 -253.564471)
			(xy 59.685208 -253.597134) (xy 59.637372 -253.623254) (xy 59.586305 -253.6423) (xy 59.533048 -253.653884)
			(xy 59.478684 -253.65777) (xy 59.42432 -253.653879) (xy 59.371063 -253.642291) (xy 59.319998 -253.62324)
			(xy 59.272164 -253.597116) (xy 59.250072 -253.581154) (xy 59.23106 -253.567558) (xy 59.189177 -253.546826)
			(xy 59.144209 -253.5341) (xy 59.097672 -253.52981) (xy 59.051135 -253.5341) (xy 59.006167 -253.546826)
			(xy 58.964284 -253.567558) (xy 58.945272 -253.581154) (xy 58.923141 -253.59705) (xy 58.875321 -253.62316)
			(xy 58.82427 -253.642199) (xy 58.771031 -253.653778) (xy 58.716685 -253.657663) (xy 58.662339 -253.653774)
			(xy 58.6091 -253.64219) (xy 58.558051 -253.623147) (xy 58.510233 -253.597033) (xy 58.466617 -253.564379)
			(xy 58.428093 -253.52585) (xy 58.395444 -253.482231) (xy 58.369335 -253.434409) (xy 58.350298 -253.383359)
			(xy 58.33872 -253.330119) (xy 58.334837 -253.275772) (xy 44.922843 -253.275772) (xy 44.936925 -253.322578)
			(xy 44.945045 -253.377754) (xy 44.945554 -253.40564) (xy 44.945045 -253.433526) (xy 44.936925 -253.488702)
			(xy 44.920857 -253.542109) (xy 44.897185 -253.592606) (xy 44.866412 -253.639119) (xy 44.829195 -253.680656)
			(xy 44.786327 -253.716331) (xy 44.738721 -253.745385) (xy 44.687392 -253.767197) (xy 44.633435 -253.781303)
			(xy 44.577998 -253.787403) (xy 44.522264 -253.785366) (xy 44.467421 -253.775236) (xy 44.414637 -253.757229)
			(xy 44.365037 -253.731728) (xy 44.319679 -253.699277) (xy 44.27953 -253.660568) (xy 44.245444 -253.616425)
			(xy 44.218148 -253.56779) (xy 44.198225 -253.515699) (xy 44.186099 -253.461262) (xy 44.182028 -253.40564)
			(xy 11.496708 -253.40564) (xy 11.936409 -253.845314) (xy 25.19248 -253.845314) (xy 25.196551 -253.789692)
			(xy 25.208677 -253.735255) (xy 25.2286 -253.683164) (xy 25.255896 -253.634529) (xy 25.289982 -253.590386)
			(xy 25.330131 -253.551677) (xy 25.375489 -253.519226) (xy 25.425089 -253.493725) (xy 25.477873 -253.475718)
			(xy 25.532716 -253.465588) (xy 25.58845 -253.463551) (xy 25.643887 -253.469651) (xy 25.697844 -253.483757)
			(xy 25.749173 -253.505569) (xy 25.796779 -253.534623) (xy 25.839647 -253.570298) (xy 25.876864 -253.611835)
			(xy 25.907637 -253.658348) (xy 25.931309 -253.708845) (xy 25.947377 -253.762252) (xy 25.955497 -253.817428)
			(xy 25.956006 -253.845314) (xy 25.955497 -253.8732) (xy 25.947377 -253.928376) (xy 25.931309 -253.981783)
			(xy 25.907637 -254.03228) (xy 25.876864 -254.078793) (xy 25.839647 -254.12033) (xy 25.796779 -254.156005)
			(xy 25.749173 -254.185059) (xy 25.697844 -254.206871) (xy 25.643887 -254.220977) (xy 25.58845 -254.227077)
			(xy 25.532716 -254.22504) (xy 25.477873 -254.21491) (xy 25.425089 -254.196903) (xy 25.375489 -254.171402)
			(xy 25.330131 -254.138951) (xy 25.289982 -254.100242) (xy 25.255896 -254.056099) (xy 25.2286 -254.007464)
			(xy 25.208677 -253.955373) (xy 25.196551 -253.900936) (xy 25.19248 -253.845314) (xy 11.936409 -253.845314)
			(xy 12.486353 -254.395224) (xy 46.443644 -254.395224) (xy 46.447715 -254.339602) (xy 46.459841 -254.285165)
			(xy 46.479764 -254.233074) (xy 46.50706 -254.184439) (xy 46.541146 -254.140296) (xy 46.581295 -254.101587)
			(xy 46.626653 -254.069136) (xy 46.676253 -254.043635) (xy 46.729037 -254.025628) (xy 46.78388 -254.015498)
			(xy 46.839614 -254.013461) (xy 46.895051 -254.019561) (xy 46.949008 -254.033667) (xy 47.000337 -254.055479)
			(xy 47.047943 -254.084533) (xy 47.090811 -254.120208) (xy 47.128028 -254.161745) (xy 47.158801 -254.208258)
			(xy 47.182473 -254.258755) (xy 47.198541 -254.312162) (xy 47.206661 -254.367338) (xy 47.20717 -254.395224)
			(xy 47.206661 -254.42311) (xy 47.198541 -254.478286) (xy 47.182473 -254.531693) (xy 47.158801 -254.58219)
			(xy 47.128028 -254.628703) (xy 47.090811 -254.67024) (xy 47.047943 -254.705915) (xy 47.000337 -254.734969)
			(xy 46.949008 -254.756781) (xy 46.895051 -254.770887) (xy 46.839614 -254.776987) (xy 46.78388 -254.77495)
			(xy 46.729037 -254.76482) (xy 46.676253 -254.746813) (xy 46.626653 -254.721312) (xy 46.581295 -254.688861)
			(xy 46.541146 -254.650152) (xy 46.50706 -254.606009) (xy 46.479764 -254.557374) (xy 46.459841 -254.505283)
			(xy 46.447715 -254.450846) (xy 46.443644 -254.395224) (xy 12.486353 -254.395224) (xy 13.036296 -254.945134)
			(xy 13.036296 -255.185717) (xy 58.334778 -255.185717) (xy 58.338663 -255.131362) (xy 58.350244 -255.078114)
			(xy 58.369286 -255.027056) (xy 58.3954 -254.979228) (xy 58.428055 -254.935603) (xy 58.466586 -254.897069)
			(xy 58.51021 -254.864412) (xy 58.558037 -254.838295) (xy 58.609093 -254.81925) (xy 58.662341 -254.807666)
			(xy 58.716695 -254.803778) (xy 58.77105 -254.807665) (xy 58.824298 -254.819248) (xy 58.875355 -254.838291)
			(xy 58.923182 -254.864406) (xy 58.945272 -254.880364) (xy 58.964284 -254.89396) (xy 59.006167 -254.914692)
			(xy 59.051135 -254.927418) (xy 59.097672 -254.931708) (xy 59.144209 -254.927418) (xy 59.189177 -254.914692)
			(xy 59.23106 -254.89396) (xy 59.250072 -254.880364) (xy 59.272187 -254.864439) (xy 59.320013 -254.838318)
			(xy 59.37107 -254.819269) (xy 59.424318 -254.807681) (xy 59.478673 -254.803789) (xy 59.533029 -254.807673)
			(xy 59.586278 -254.819254) (xy 59.637338 -254.838295) (xy 59.685167 -254.86441) (xy 59.728793 -254.897066)
			(xy 59.767327 -254.935599) (xy 59.799984 -254.979224) (xy 59.8261 -255.027053) (xy 59.845143 -255.078112)
			(xy 59.856725 -255.131361) (xy 59.860611 -255.185717) (xy 60.221471 -255.185717) (xy 60.225356 -255.131361)
			(xy 60.236938 -255.078111) (xy 60.25598 -255.027051) (xy 60.282095 -254.979222) (xy 60.314752 -254.935596)
			(xy 60.353285 -254.897061) (xy 60.396909 -254.864403) (xy 60.444738 -254.838286) (xy 60.495797 -254.819242)
			(xy 60.549046 -254.807658) (xy 60.603402 -254.803771) (xy 60.657758 -254.807659) (xy 60.711007 -254.819243)
			(xy 60.762066 -254.838288) (xy 60.809894 -254.864405) (xy 60.831984 -254.880364) (xy 60.850996 -254.89396)
			(xy 60.892879 -254.914692) (xy 60.937847 -254.927418) (xy 60.984384 -254.931708) (xy 61.030921 -254.927418)
			(xy 61.075889 -254.914692) (xy 61.117772 -254.89396) (xy 61.136784 -254.880364) (xy 61.158899 -254.86444)
			(xy 61.206724 -254.838321) (xy 61.257779 -254.819274) (xy 61.311026 -254.807687) (xy 61.36538 -254.803796)
			(xy 61.419734 -254.807681) (xy 61.472982 -254.819262) (xy 61.524039 -254.838304) (xy 61.571867 -254.864418)
			(xy 61.615491 -254.897074) (xy 61.654024 -254.935606) (xy 61.68668 -254.97923) (xy 61.712795 -255.027058)
			(xy 61.731837 -255.078115) (xy 61.743418 -255.131363) (xy 61.747304 -255.185717) (xy 62.462445 -255.185717)
			(xy 62.466331 -255.131355) (xy 62.477915 -255.0781) (xy 62.49696 -255.027035) (xy 62.523079 -254.979201)
			(xy 62.55574 -254.935571) (xy 62.594278 -254.897034) (xy 62.637909 -254.864374) (xy 62.685743 -254.838256)
			(xy 62.736808 -254.819212) (xy 62.790064 -254.80763) (xy 62.844426 -254.803745) (xy 62.898787 -254.807637)
			(xy 62.952041 -254.819227) (xy 63.003104 -254.838278) (xy 63.050935 -254.864402) (xy 63.073026 -254.880364)
			(xy 63.092038 -254.89396) (xy 63.133921 -254.914692) (xy 63.178889 -254.927418) (xy 63.225426 -254.931708)
			(xy 63.271963 -254.927418) (xy 63.316931 -254.914692) (xy 63.358814 -254.89396) (xy 63.377826 -254.880364)
			(xy 63.39994 -254.864444) (xy 63.447762 -254.838331) (xy 63.498813 -254.81929) (xy 63.552055 -254.807708)
			(xy 63.606404 -254.803821) (xy 63.660752 -254.807709) (xy 63.713993 -254.819292) (xy 63.765045 -254.838334)
			(xy 63.812866 -254.864448) (xy 63.856484 -254.897102) (xy 63.895012 -254.935631) (xy 63.927663 -254.979251)
			(xy 63.953774 -255.027074) (xy 63.972814 -255.078126) (xy 63.984394 -255.131368) (xy 63.988279 -255.185717)
			(xy 64.366455 -255.185717) (xy 64.370341 -255.131357) (xy 64.381924 -255.078104) (xy 64.400968 -255.027041)
			(xy 64.427085 -254.979209) (xy 64.459744 -254.93558) (xy 64.49828 -254.897044) (xy 64.541909 -254.864385)
			(xy 64.589741 -254.838267) (xy 64.640804 -254.819223) (xy 64.694057 -254.807641) (xy 64.748417 -254.803755)
			(xy 64.802776 -254.807646) (xy 64.856028 -254.819233) (xy 64.907089 -254.838282) (xy 64.95492 -254.864403)
			(xy 64.97701 -254.880364) (xy 64.996022 -254.89396) (xy 65.037905 -254.914692) (xy 65.082873 -254.927418)
			(xy 65.12941 -254.931708) (xy 65.175947 -254.927418) (xy 65.220915 -254.914692) (xy 65.262798 -254.89396)
			(xy 65.28181 -254.880364) (xy 65.303924 -254.864443) (xy 65.351747 -254.838327) (xy 65.4028 -254.819284)
			(xy 65.456044 -254.8077) (xy 65.510394 -254.803812) (xy 65.564745 -254.807698) (xy 65.617989 -254.819281)
			(xy 65.669043 -254.838323) (xy 65.716866 -254.864437) (xy 65.760487 -254.897091) (xy 65.799016 -254.935621)
			(xy 65.831669 -254.979243) (xy 65.857782 -255.027068) (xy 65.876823 -255.078122) (xy 65.888403 -255.131366)
			(xy 65.892288 -255.185717) (xy 65.888398 -255.240067) (xy 65.876813 -255.29331) (xy 65.857768 -255.344363)
			(xy 65.831651 -255.392185) (xy 65.798994 -255.435804) (xy 65.760462 -255.474331) (xy 65.716838 -255.506981)
			(xy 65.669012 -255.533091) (xy 65.617957 -255.552129) (xy 65.564712 -255.563706) (xy 65.510361 -255.567588)
			(xy 65.456011 -255.563695) (xy 65.402768 -255.552107) (xy 65.351717 -255.533059) (xy 65.303896 -255.506939)
			(xy 65.28181 -255.49098) (xy 65.262798 -255.477384) (xy 65.220915 -255.456652) (xy 65.175947 -255.443926)
			(xy 65.12941 -255.439636) (xy 65.082873 -255.443926) (xy 65.037905 -255.456652) (xy 64.996022 -255.477384)
			(xy 64.97701 -255.49098) (xy 64.954948 -255.506979) (xy 64.90712 -255.533105) (xy 64.856061 -255.552158)
			(xy 64.802809 -255.56375) (xy 64.748451 -255.567645) (xy 64.694091 -255.563764) (xy 64.640836 -255.552186)
			(xy 64.589772 -255.533146) (xy 64.541937 -255.507033) (xy 64.498306 -255.474378) (xy 64.459766 -255.435845)
			(xy 64.427103 -255.392219) (xy 64.400981 -255.344389) (xy 64.381933 -255.293328) (xy 64.370346 -255.240076)
			(xy 64.366455 -255.185717) (xy 63.988279 -255.185717) (xy 63.984389 -255.240065) (xy 63.972804 -255.293306)
			(xy 63.95376 -255.344357) (xy 63.927645 -255.392177) (xy 63.89499 -255.435795) (xy 63.856459 -255.47432)
			(xy 63.812838 -255.50697) (xy 63.765014 -255.53308) (xy 63.713961 -255.552118) (xy 63.660718 -255.563696)
			(xy 63.60637 -255.567579) (xy 63.552022 -255.563687) (xy 63.498781 -255.552101) (xy 63.447731 -255.533055)
			(xy 63.399912 -255.506938) (xy 63.377826 -255.49098) (xy 63.358814 -255.477384) (xy 63.316931 -255.456652)
			(xy 63.271963 -255.443926) (xy 63.225426 -255.439636) (xy 63.178889 -255.443926) (xy 63.133921 -255.456652)
			(xy 63.092038 -255.477384) (xy 63.073026 -255.49098) (xy 63.050963 -255.50698) (xy 63.003135 -255.533108)
			(xy 62.952074 -255.552164) (xy 62.898821 -255.563758) (xy 62.84446 -255.567655) (xy 62.790097 -255.563775)
			(xy 62.736841 -255.552197) (xy 62.685774 -255.533158) (xy 62.637937 -255.507044) (xy 62.594303 -255.474388)
			(xy 62.555762 -255.435854) (xy 62.523097 -255.392227) (xy 62.496974 -255.344396) (xy 62.477924 -255.293333)
			(xy 62.466336 -255.240078) (xy 62.462445 -255.185717) (xy 61.747304 -255.185717) (xy 61.743414 -255.240071)
			(xy 61.731827 -255.293317) (xy 61.712781 -255.344373) (xy 61.686661 -255.392198) (xy 61.654001 -255.435819)
			(xy 61.615466 -255.474348) (xy 61.571839 -255.507) (xy 61.524009 -255.53311) (xy 61.472949 -255.552147)
			(xy 61.419701 -255.563724) (xy 61.365346 -255.567604) (xy 61.310993 -255.563708) (xy 61.257747 -255.552117)
			(xy 61.206693 -255.533065) (xy 61.158871 -255.506941) (xy 61.136784 -255.49098) (xy 61.117772 -255.477384)
			(xy 61.075889 -255.456652) (xy 61.030921 -255.443926) (xy 60.984384 -255.439636) (xy 60.937847 -255.443926)
			(xy 60.892879 -255.456652) (xy 60.850996 -255.477384) (xy 60.831984 -255.49098) (xy 60.809922 -255.506976)
			(xy 60.762096 -255.533098) (xy 60.71104 -255.552147) (xy 60.657791 -255.563737) (xy 60.603436 -255.567629)
			(xy 60.549079 -255.563747) (xy 60.495829 -255.552168) (xy 60.444769 -255.533128) (xy 60.396938 -255.507015)
			(xy 60.35331 -255.474361) (xy 60.314774 -255.43583) (xy 60.282113 -255.392207) (xy 60.255994 -255.344379)
			(xy 60.236947 -255.293321) (xy 60.225361 -255.240073) (xy 60.221471 -255.185717) (xy 59.860611 -255.185717)
			(xy 59.856721 -255.240072) (xy 59.845134 -255.293321) (xy 59.826086 -255.344378) (xy 59.799966 -255.392204)
			(xy 59.767305 -255.435826) (xy 59.728768 -255.474356) (xy 59.685139 -255.507008) (xy 59.637307 -255.533119)
			(xy 59.586246 -255.552156) (xy 59.532995 -255.563732) (xy 59.478639 -255.567611) (xy 59.424284 -255.563714)
			(xy 59.371037 -255.552121) (xy 59.319982 -255.533068) (xy 59.272159 -255.506942) (xy 59.250072 -255.49098)
			(xy 59.23106 -255.477384) (xy 59.189177 -255.456652) (xy 59.144209 -255.443926) (xy 59.097672 -255.439636)
			(xy 59.051135 -255.443926) (xy 59.006167 -255.456652) (xy 58.964284 -255.477384) (xy 58.945272 -255.49098)
			(xy 58.923211 -255.506975) (xy 58.875386 -255.533095) (xy 58.82433 -255.552143) (xy 58.771083 -255.56373)
			(xy 58.716729 -255.567622) (xy 58.662374 -255.563739) (xy 58.609126 -255.552159) (xy 58.558067 -255.533119)
			(xy 58.510238 -255.507007) (xy 58.466612 -255.474353) (xy 58.428077 -255.435823) (xy 58.395418 -255.392201)
			(xy 58.3693 -255.344374) (xy 58.350254 -255.293318) (xy 58.338668 -255.240071) (xy 58.334778 -255.185717)
			(xy 13.036296 -255.185717) (xy 13.036296 -256.21742) (xy 44.245274 -256.21742) (xy 44.249345 -256.161798)
			(xy 44.261471 -256.107361) (xy 44.281394 -256.05527) (xy 44.30869 -256.006635) (xy 44.342776 -255.962492)
			(xy 44.382925 -255.923783) (xy 44.428283 -255.891332) (xy 44.477883 -255.865831) (xy 44.530667 -255.847824)
			(xy 44.58551 -255.837694) (xy 44.641244 -255.835657) (xy 44.696681 -255.841757) (xy 44.750638 -255.855863)
			(xy 44.801967 -255.877675) (xy 44.849573 -255.906729) (xy 44.892441 -255.942404) (xy 44.929658 -255.983941)
			(xy 44.960431 -256.030454) (xy 44.984103 -256.080951) (xy 45.000171 -256.134358) (xy 45.008291 -256.189534)
			(xy 45.0088 -256.21742) (xy 45.008291 -256.245306) (xy 45.000171 -256.300482) (xy 44.984103 -256.353889)
			(xy 44.960431 -256.404386) (xy 44.929658 -256.450899) (xy 44.892441 -256.492436) (xy 44.849573 -256.528111)
			(xy 44.801967 -256.557165) (xy 44.750638 -256.578977) (xy 44.696681 -256.593083) (xy 44.641244 -256.599183)
			(xy 44.58551 -256.597146) (xy 44.530667 -256.587016) (xy 44.477883 -256.569009) (xy 44.428283 -256.543508)
			(xy 44.382925 -256.511057) (xy 44.342776 -256.472348) (xy 44.30869 -256.428205) (xy 44.281394 -256.37957)
			(xy 44.261471 -256.327479) (xy 44.249345 -256.273042) (xy 44.245274 -256.21742) (xy 13.036296 -256.21742)
			(xy 13.036296 -256.62509) (xy 14.188237 -257.777179) (xy 19.03539 -257.777179) (xy 19.039328 -257.722502)
			(xy 19.051053 -257.668951) (xy 19.070324 -257.61763) (xy 19.096744 -257.569598) (xy 19.129768 -257.525843)
			(xy 19.168717 -257.487266) (xy 19.212788 -257.454664) (xy 19.261072 -257.428706) (xy 19.312576 -257.409929)
			(xy 19.366236 -257.39872) (xy 19.420949 -257.395308) (xy 19.475587 -257.399765) (xy 19.529024 -257.411998)
			(xy 19.580159 -257.431756) (xy 19.627939 -257.458631) (xy 19.649948 -257.474974) (xy 19.669174 -257.489086)
			(xy 19.711723 -257.510616) (xy 19.757538 -257.523843) (xy 19.805015 -257.528304) (xy 19.852492 -257.523843)
			(xy 19.898307 -257.510616) (xy 19.940856 -257.489086) (xy 19.960082 -257.474974) (xy 19.982091 -257.458624)
			(xy 20.029876 -257.431746) (xy 20.081018 -257.411986) (xy 20.134462 -257.399752) (xy 20.189107 -257.395295)
			(xy 20.243827 -257.398709) (xy 20.297495 -257.409921) (xy 20.349004 -257.428702) (xy 20.397294 -257.454664)
			(xy 20.441369 -257.487272) (xy 20.480322 -257.525855) (xy 20.513349 -257.569617) (xy 20.539771 -257.617657)
			(xy 20.559042 -257.668984) (xy 20.570767 -257.722543) (xy 20.574702 -257.777228) (xy 20.570767 -257.831913)
			(xy 20.559044 -257.885471) (xy 20.539773 -257.936799) (xy 20.513352 -257.984839) (xy 20.480325 -258.028602)
			(xy 20.441373 -258.067185) (xy 20.397298 -258.099794) (xy 20.349009 -258.125756) (xy 20.312181 -258.139184)
			(xy 44.188124 -258.139184) (xy 44.192195 -258.083562) (xy 44.204321 -258.029125) (xy 44.224244 -257.977034)
			(xy 44.25154 -257.928399) (xy 44.285626 -257.884256) (xy 44.325775 -257.845547) (xy 44.371133 -257.813096)
			(xy 44.420733 -257.787595) (xy 44.473517 -257.769588) (xy 44.52836 -257.759458) (xy 44.584094 -257.757421)
			(xy 44.639531 -257.763521) (xy 44.693488 -257.777627) (xy 44.744817 -257.799439) (xy 44.792423 -257.828493)
			(xy 44.835291 -257.864168) (xy 44.872508 -257.905705) (xy 44.903281 -257.952218) (xy 44.926953 -258.002715)
			(xy 44.943021 -258.056122) (xy 44.951141 -258.111298) (xy 44.95165 -258.139184) (xy 44.951141 -258.16707)
			(xy 44.943021 -258.222246) (xy 44.926953 -258.275653) (xy 44.903281 -258.32615) (xy 44.872508 -258.372663)
			(xy 44.835291 -258.4142) (xy 44.792423 -258.449875) (xy 44.744817 -258.478929) (xy 44.693488 -258.500741)
			(xy 44.639531 -258.514847) (xy 44.584094 -258.520947) (xy 44.52836 -258.51891) (xy 44.473517 -258.50878)
			(xy 44.420733 -258.490773) (xy 44.371133 -258.465272) (xy 44.325775 -258.432821) (xy 44.285626 -258.394112)
			(xy 44.25154 -258.349969) (xy 44.224244 -258.301334) (xy 44.204321 -258.249243) (xy 44.192195 -258.194806)
			(xy 44.188124 -258.139184) (xy 20.312181 -258.139184) (xy 20.2975 -258.144537) (xy 20.243832 -258.155751)
			(xy 20.189112 -258.159165) (xy 20.134467 -258.154709) (xy 20.081023 -258.142476) (xy 20.029881 -258.122716)
			(xy 19.982095 -258.095839) (xy 19.960082 -258.079494) (xy 19.940871 -258.065346) (xy 19.898333 -258.043753)
			(xy 19.85251 -258.030486) (xy 19.805015 -258.026011) (xy 19.75752 -258.030486) (xy 19.711697 -258.043753)
			(xy 19.669159 -258.065346) (xy 19.649948 -258.079494) (xy 19.627904 -258.095792) (xy 19.580122 -258.122662)
			(xy 19.528984 -258.142414) (xy 19.475546 -258.154642) (xy 19.420908 -258.159093) (xy 19.366195 -258.155675)
			(xy 19.312536 -258.144459) (xy 19.261034 -258.125677) (xy 19.212753 -258.099714) (xy 19.168686 -258.067107)
			(xy 19.129741 -258.028526) (xy 19.096721 -257.984767) (xy 19.070306 -257.936732) (xy 19.051041 -257.885409)
			(xy 19.039322 -257.831857) (xy 19.03539 -257.777179) (xy 14.188237 -257.777179) (xy 15.007082 -258.59613)
			(xy 15.029283 -258.598583) (xy 15.0739 -258.596598) (xy 15.117488 -258.586864) (xy 15.158711 -258.569677)
			(xy 15.17777 -258.55803) (xy 15.197223 -258.539615) (xy 15.240313 -258.507795) (xy 15.2874 -258.482258)
			(xy 15.337573 -258.463498) (xy 15.389863 -258.451878) (xy 15.44326 -258.447622) (xy 15.49673 -258.450812)
			(xy 15.549242 -258.461388) (xy 15.599779 -258.479144) (xy 15.647365 -258.503737) (xy 15.691081 -258.534693)
			(xy 15.710916 -258.552696) (xy 15.72768 -258.568698) (xy 15.809722 -258.602988) (xy 15.892272 -258.571746)
			(xy 15.908274 -258.558792) (xy 15.9303 -258.541563) (xy 15.97841 -258.513062) (xy 16.030164 -258.491888)
			(xy 16.084455 -258.478493) (xy 16.140119 -258.473165) (xy 16.195965 -258.476017) (xy 16.250797 -258.48699)
			(xy 16.30344 -258.505847) (xy 16.352767 -258.532185) (xy 16.397723 -258.56544) (xy 16.437344 -258.6049)
			(xy 16.470781 -258.64972) (xy 16.49732 -258.69894) (xy 16.516391 -258.751506) (xy 16.527587 -258.806292)
			(xy 16.530667 -258.862126) (xy 16.528542 -258.890008) (xy 16.525492 -258.917734) (xy 16.512373 -258.971948)
			(xy 16.491501 -259.023674) (xy 16.463322 -259.071811) (xy 16.428436 -259.115333) (xy 16.387586 -259.153313)
			(xy 16.341642 -259.184942) (xy 16.291583 -259.209545) (xy 16.238476 -259.2266) (xy 16.211042 -259.231638)
			(xy 16.188234 -259.235969) (xy 16.144596 -259.251799) (xy 16.104557 -259.275286) (xy 16.069446 -259.30565)
			(xy 16.040429 -259.341883) (xy 16.018472 -259.382782) (xy 16.004302 -259.426986) (xy 15.998391 -259.473028)
			(xy 16.000936 -259.519378) (xy 16.011852 -259.564496) (xy 16.030775 -259.606884) (xy 16.057078 -259.645132)
			(xy 16.07312 -259.661914) (xy 17.219422 -260.808216) (xy 42.31894 -260.808216) (xy 42.704258 -260.423152)
			(xy 44.20997 -260.423152) (xy 44.227959 -260.408658) (xy 44.258866 -260.374328) (xy 44.283071 -260.334986)
			(xy 44.299781 -260.291921) (xy 44.308446 -260.246549) (xy 44.308783 -260.200358) (xy 44.30522 -260.177534)
			(xy 44.29971 -260.150269) (xy 44.295721 -260.094788) (xy 44.29983 -260.039316) (xy 44.311949 -259.985029)
			(xy 44.331822 -259.933076) (xy 44.359028 -259.88456) (xy 44.392991 -259.840508) (xy 44.432989 -259.801854)
			(xy 44.478176 -259.769417) (xy 44.527594 -259.743884) (xy 44.580195 -259.725798) (xy 44.634865 -259.715541)
			(xy 44.690445 -259.71333) (xy 44.745757 -259.719213) (xy 44.799628 -259.733064) (xy 44.850918 -259.754591)
			(xy 44.898538 -259.783336) (xy 44.94148 -259.818691) (xy 44.96054 -259.838952) (xy 44.978534 -259.859454)
			(xy 45.009083 -259.904646) (xy 45.032883 -259.953729) (xy 45.049448 -260.005702) (xy 45.05844 -260.059505)
			(xy 45.059675 -260.114039) (xy 45.053129 -260.168194) (xy 45.038935 -260.220864) (xy 45.028612 -260.246114)
			(xy 45.018452 -260.26999) (xy 45.018452 -260.296152) (xy 45.018989 -260.312807) (xy 45.027598 -260.344984)
			(xy 45.044242 -260.373837) (xy 45.067786 -260.397399) (xy 45.096627 -260.414065) (xy 45.128798 -260.422698)
			(xy 45.145452 -260.423152) (xy 45.287438 -260.423152) (xy 46.32071 -259.38988) (xy 46.326806 -259.38988)
			(xy 46.341877 -259.389461) (xy 46.371178 -259.382393) (xy 46.397994 -259.368632) (xy 46.420822 -259.34895)
			(xy 46.438379 -259.32445) (xy 46.444408 -259.310632) (xy 46.485556 -259.209286) (xy 46.457362 -259.122164)
			(xy 46.44771 -259.107686) (xy 46.432971 -259.084548) (xy 46.409565 -259.034933) (xy 46.393504 -258.982479)
			(xy 46.385119 -258.928264) (xy 46.384585 -258.873408) (xy 46.39191 -258.819041) (xy 46.406945 -258.766283)
			(xy 46.42938 -258.716221) (xy 46.458752 -258.669888) (xy 46.494456 -258.628238) (xy 46.535755 -258.59213)
			(xy 46.5818 -258.562308) (xy 46.63164 -258.539386) (xy 46.684249 -258.523837) (xy 46.738543 -258.515982)
			(xy 46.793401 -258.515982) (xy 46.847695 -258.523837) (xy 46.900304 -258.539386) (xy 46.950144 -258.562308)
			(xy 46.996189 -258.59213) (xy 47.037488 -258.628238) (xy 47.073192 -258.669888) (xy 47.102564 -258.716221)
			(xy 47.124999 -258.766283) (xy 47.140034 -258.819041) (xy 47.147359 -258.873408) (xy 47.146825 -258.928264)
			(xy 47.13844 -258.982479) (xy 47.122379 -259.034933) (xy 47.098973 -259.084548) (xy 47.084234 -259.107686)
			(xy 47.074582 -259.122164) (xy 47.046388 -259.209286) (xy 47.087536 -259.310632) (xy 47.093607 -259.324422)
			(xy 47.111186 -259.348882) (xy 47.134009 -259.368541) (xy 47.160804 -259.382303) (xy 47.190078 -259.389401)
			(xy 47.205138 -259.38988) (xy 47.376842 -259.38988) (xy 47.395255 -259.374987) (xy 47.426725 -259.339607)
			(xy 47.451123 -259.299025) (xy 47.46761 -259.254637) (xy 47.472092 -259.231384) (xy 47.476455 -259.204477)
			(xy 47.491818 -259.152177) (xy 47.514468 -259.102597) (xy 47.543942 -259.056744) (xy 47.579641 -259.015551)
			(xy 47.620838 -258.979858) (xy 47.666696 -258.950391) (xy 47.71628 -258.927749) (xy 47.768581 -258.912393)
			(xy 47.822535 -258.904637) (xy 47.877045 -258.904637) (xy 47.930999 -258.912393) (xy 47.9833 -258.927749)
			(xy 48.032884 -258.950391) (xy 48.078742 -258.979858) (xy 48.119939 -259.015551) (xy 48.155638 -259.056744)
			(xy 48.185112 -259.102597) (xy 48.207762 -259.152177) (xy 48.223125 -259.204477) (xy 48.227488 -259.231384)
			(xy 48.231972 -259.25464) (xy 48.248417 -259.299051) (xy 48.272809 -259.339644) (xy 48.304302 -259.375011)
			(xy 48.322738 -259.38988) (xy 64.592454 -259.38988) (xy 64.609073 -259.389345) (xy 64.641184 -259.380761)
			(xy 64.669982 -259.364165) (xy 64.682116 -259.352796) (xy 77.940916 -246.093742) (xy 77.940916 -235.567728)
			(xy 82.56524 -230.94315) (xy 82.56524 -216.219532) (xy 83.874864 -214.910162) (xy 83.886214 -214.898013)
			(xy 83.902806 -214.869218) (xy 83.911406 -214.837116) (xy 83.911948 -214.8205) (xy 83.911948 -202.80249)
			(xy 83.911406 -202.785874) (xy 83.902809 -202.753773) (xy 83.886202 -202.724988) (xy 83.874864 -202.712828)
			(xy 82.820764 -201.658982) (xy 82.820764 -192.630044) (xy 82.816954 -192.612264) (xy 82.815938 -192.605914)
			(xy 82.813906 -192.594738) (xy 82.810087 -192.566097) (xy 82.810086 -192.508317) (xy 82.813906 -192.479676)
			(xy 82.82051 -192.446148) (xy 82.82696 -192.421723) (xy 82.845433 -192.374702) (xy 82.85734 -192.352422)
			(xy 82.873088 -192.32372) (xy 82.873088 -183.590692) (xy 85.31606 -181.14772) (xy 90.782394 -181.14772)
			(xy 91.711272 -182.076598) (xy 91.721654 -182.08647) (xy 91.745898 -182.101721) (xy 91.77293 -182.111191)
			(xy 91.801392 -182.114402) (xy 91.815666 -182.113174) (xy 91.830144 -182.111396) (xy 91.836494 -182.109872)
			(xy 91.87416 -182.10206) (xy 91.950626 -182.093624) (xy 92.027555 -182.093482) (xy 92.10405 -182.101637)
			(xy 92.179221 -182.117992) (xy 92.252189 -182.142358) (xy 92.322105 -182.17445) (xy 92.388152 -182.213893)
			(xy 92.449562 -182.260229) (xy 92.505616 -182.312916) (xy 92.555663 -182.371341) (xy 92.599118 -182.434821)
			(xy 92.635474 -182.502617) (xy 92.664308 -182.573938) (xy 92.685284 -182.647953) (xy 92.698156 -182.723797)
			(xy 92.702774 -182.800588) (xy 92.699086 -182.877428) (xy 92.687133 -182.953423) (xy 92.667055 -183.027686)
			(xy 92.639087 -183.099351) (xy 92.603554 -183.167582) (xy 92.56087 -183.231584) (xy 92.511535 -183.29061)
			(xy 92.456122 -183.343972) (xy 92.426028 -183.367934) (xy 92.376752 -183.468264) (xy 92.376752 -184.681876)
			(xy 92.42552 -184.780936) (xy 92.447364 -184.799224) (xy 92.447364 -184.799478) (xy 92.475659 -184.823765)
			(xy 92.527535 -184.877335) (xy 92.573523 -184.936037) (xy 92.613117 -184.999229) (xy 92.645885 -185.066215)
			(xy 92.671465 -185.136262) (xy 92.689577 -185.2086) (xy 92.700023 -185.282436) (xy 92.702687 -185.35696)
			(xy 92.697541 -185.431353) (xy 92.684642 -185.5048) (xy 92.664129 -185.576495) (xy 92.63623 -185.645651)
			(xy 92.601249 -185.711508) (xy 92.559572 -185.773345) (xy 92.511654 -185.830483) (xy 92.458022 -185.882295)
			(xy 92.399264 -185.928213) (xy 92.367862 -185.94832) (xy 92.354467 -185.957252) (xy 92.332318 -185.980606)
			(xy 92.316721 -186.00876) (xy 92.308668 -186.039923) (xy 92.308172 -186.056016) (xy 92.308172 -186.06008)
			(xy 93.15476 -186.06008) (xy 93.158776 -185.94381) (xy 93.170803 -185.828095) (xy 93.190785 -185.713485)
			(xy 93.218627 -185.600526) (xy 93.254196 -185.489758) (xy 93.297322 -185.381707) (xy 93.347799 -185.276889)
			(xy 93.405388 -185.175804) (xy 93.469814 -185.078932) (xy 93.540769 -184.986736) (xy 93.617916 -184.899655)
			(xy 93.700887 -184.818104) (xy 93.789287 -184.742472) (xy 93.882694 -184.673118) (xy 93.980663 -184.610375)
			(xy 94.082727 -184.554539) (xy 94.188401 -184.505878) (xy 94.29718 -184.464624) (xy 94.408545 -184.430973)
			(xy 94.521968 -184.405085) (xy 94.636905 -184.387084) (xy 94.752811 -184.377055) (xy 94.869133 -184.375047)
			(xy 94.985316 -184.381069) (xy 95.100807 -184.395092) (xy 95.215055 -184.41705) (xy 95.327516 -184.446837)
			(xy 95.437654 -184.484312) (xy 95.544944 -184.529297) (xy 95.648875 -184.581576) (xy 95.748951 -184.640901)
			(xy 95.844697 -184.706989) (xy 95.935654 -184.779525) (xy 96.02139 -184.858164) (xy 96.101497 -184.94253)
			(xy 96.175593 -185.032222) (xy 96.243323 -185.126812) (xy 96.304367 -185.22585) (xy 96.358432 -185.328863)
			(xy 96.405262 -185.43536) (xy 96.444633 -185.544835) (xy 96.476357 -185.656765) (xy 96.500283 -185.770617)
			(xy 96.516297 -185.885849) (xy 96.524324 -186.001911) (xy 96.524826 -186.06008) (xy 96.524324 -186.118249)
			(xy 96.516297 -186.234311) (xy 96.500283 -186.349543) (xy 96.476357 -186.463395) (xy 96.444633 -186.575325)
			(xy 96.405262 -186.6848) (xy 96.358432 -186.791297) (xy 96.304367 -186.89431) (xy 96.243323 -186.993348)
			(xy 96.175593 -187.087938) (xy 96.101497 -187.17763) (xy 96.02139 -187.261996) (xy 95.935654 -187.340635)
			(xy 95.844697 -187.413171) (xy 95.748951 -187.479259) (xy 95.648875 -187.538584) (xy 95.544944 -187.590863)
			(xy 95.437654 -187.635848) (xy 95.327516 -187.673323) (xy 95.215055 -187.70311) (xy 95.100807 -187.725068)
			(xy 94.985316 -187.739091) (xy 94.869133 -187.745113) (xy 94.752811 -187.743105) (xy 94.636905 -187.733076)
			(xy 94.521968 -187.715075) (xy 94.408545 -187.689187) (xy 94.29718 -187.655536) (xy 94.188401 -187.614282)
			(xy 94.082727 -187.565621) (xy 93.980663 -187.509785) (xy 93.882694 -187.447042) (xy 93.789287 -187.377688)
			(xy 93.700887 -187.302056) (xy 93.617916 -187.220505) (xy 93.540769 -187.133424) (xy 93.469814 -187.041228)
			(xy 93.405388 -186.944356) (xy 93.347799 -186.843271) (xy 93.297322 -186.738453) (xy 93.254196 -186.630402)
			(xy 93.218627 -186.519634) (xy 93.190785 -186.406675) (xy 93.170803 -186.292065) (xy 93.158776 -186.17635)
			(xy 93.15476 -186.06008) (xy 92.308172 -186.06008) (xy 92.308172 -186.572398) (xy 90.668094 -188.212476)
			(xy 90.600276 -188.212476) (xy 87.779352 -191.0334) (xy 87.770462 -191.064896) (xy 87.762441 -191.091094)
			(xy 87.73993 -191.141044) (xy 87.710501 -191.187257) (xy 87.69361 -191.206882) (xy 91.71254 -191.206882)
			(xy 91.716611 -191.15126) (xy 91.728737 -191.096823) (xy 91.74866 -191.044732) (xy 91.775956 -190.996097)
			(xy 91.810042 -190.951954) (xy 91.850191 -190.913245) (xy 91.895549 -190.880794) (xy 91.945149 -190.855293)
			(xy 91.997933 -190.837286) (xy 92.052776 -190.827156) (xy 92.10851 -190.825119) (xy 92.163947 -190.831219)
			(xy 92.217904 -190.845325) (xy 92.269233 -190.867137) (xy 92.316839 -190.896191) (xy 92.359707 -190.931866)
			(xy 92.396924 -190.973403) (xy 92.427697 -191.019916) (xy 92.451369 -191.070413) (xy 92.467437 -191.12382)
			(xy 92.475557 -191.178996) (xy 92.476066 -191.206882) (xy 92.475557 -191.234768) (xy 92.467437 -191.289944)
			(xy 92.451369 -191.343351) (xy 92.427697 -191.393848) (xy 92.396924 -191.440361) (xy 92.359707 -191.481898)
			(xy 92.316839 -191.517573) (xy 92.269233 -191.546627) (xy 92.217904 -191.568439) (xy 92.163947 -191.582545)
			(xy 92.10851 -191.588645) (xy 92.052776 -191.586608) (xy 91.997933 -191.576478) (xy 91.945149 -191.558471)
			(xy 91.895549 -191.53297) (xy 91.850191 -191.500519) (xy 91.810042 -191.46181) (xy 91.775956 -191.417667)
			(xy 91.74866 -191.369032) (xy 91.728737 -191.316941) (xy 91.716611 -191.262504) (xy 91.71254 -191.206882)
			(xy 87.69361 -191.206882) (xy 87.674761 -191.228782) (xy 87.633445 -191.264765) (xy 87.610696 -191.280034)
			(xy 87.599266 -191.2874) (xy 87.180674 -191.705992) (xy 95.288098 -191.705992) (xy 95.292169 -191.65037)
			(xy 95.304295 -191.595933) (xy 95.324218 -191.543842) (xy 95.351514 -191.495207) (xy 95.3856 -191.451064)
			(xy 95.425749 -191.412355) (xy 95.471107 -191.379904) (xy 95.520707 -191.354403) (xy 95.573491 -191.336396)
			(xy 95.628334 -191.326266) (xy 95.684068 -191.324229) (xy 95.739505 -191.330329) (xy 95.793462 -191.344435)
			(xy 95.844791 -191.366247) (xy 95.892397 -191.395301) (xy 95.935265 -191.430976) (xy 95.972482 -191.472513)
			(xy 96.003255 -191.519026) (xy 96.026927 -191.569523) (xy 96.042995 -191.62293) (xy 96.051115 -191.678106)
			(xy 96.051624 -191.705992) (xy 96.051115 -191.733878) (xy 96.042995 -191.789054) (xy 96.026927 -191.842461)
			(xy 96.003255 -191.892958) (xy 95.972482 -191.939471) (xy 95.935265 -191.981008) (xy 95.892397 -192.016683)
			(xy 95.844791 -192.045737) (xy 95.793462 -192.067549) (xy 95.739505 -192.081655) (xy 95.684068 -192.087755)
			(xy 95.628334 -192.085718) (xy 95.573491 -192.075588) (xy 95.520707 -192.057581) (xy 95.471107 -192.03208)
			(xy 95.425749 -191.999629) (xy 95.3856 -191.96092) (xy 95.351514 -191.916777) (xy 95.324218 -191.868142)
			(xy 95.304295 -191.816051) (xy 95.292169 -191.761614) (xy 95.288098 -191.705992) (xy 87.180674 -191.705992)
			(xy 86.534752 -192.351914) (xy 86.534752 -197.81012) (xy 86.877404 -197.81012) (xy 86.881424 -197.619469)
			(xy 86.893478 -197.429156) (xy 86.913544 -197.239521) (xy 86.941587 -197.0509) (xy 86.977556 -196.86363)
			(xy 87.021388 -196.678042) (xy 87.073005 -196.494467) (xy 87.132315 -196.313231) (xy 87.199213 -196.134656)
			(xy 87.273579 -195.959061) (xy 87.355281 -195.786756) (xy 87.444175 -195.618049) (xy 87.540101 -195.453239)
			(xy 87.64289 -195.29262) (xy 87.752359 -195.136477) (xy 87.868313 -194.985088) (xy 87.990547 -194.838721)
			(xy 88.118841 -194.697637) (xy 88.252969 -194.562088) (xy 88.392693 -194.432313) (xy 88.537763 -194.308543)
			(xy 88.687921 -194.191) (xy 88.842902 -194.079891) (xy 89.002429 -193.975414) (xy 89.166218 -193.877755)
			(xy 89.333978 -193.787088) (xy 89.505412 -193.703574) (xy 89.680214 -193.627361) (xy 89.858073 -193.558585)
			(xy 90.038674 -193.497367) (xy 90.221694 -193.443818) (xy 90.40681 -193.398032) (xy 90.593691 -193.36009)
			(xy 90.782006 -193.330061) (xy 90.971419 -193.307996) (xy 91.161593 -193.293937) (xy 91.352192 -193.287907)
			(xy 91.542875 -193.289917) (xy 91.733304 -193.299964) (xy 91.92314 -193.31803) (xy 92.112046 -193.344083)
			(xy 92.299685 -193.378076) (xy 92.485725 -193.419949) (xy 92.669834 -193.469628) (xy 92.851685 -193.527024)
			(xy 93.030955 -193.592035) (xy 93.207325 -193.664546) (xy 93.380481 -193.744427) (xy 93.550116 -193.831537)
			(xy 93.715928 -193.925721) (xy 93.877622 -194.026812) (xy 94.03491 -194.134628) (xy 94.187513 -194.24898)
			(xy 94.335161 -194.369663) (xy 94.477589 -194.496464) (xy 94.614545 -194.629155) (xy 94.745786 -194.767503)
			(xy 94.871078 -194.91126) (xy 94.940737 -194.99834) (xy 96.87255 -194.99834) (xy 96.876621 -194.942718)
			(xy 96.888747 -194.888281) (xy 96.90867 -194.83619) (xy 96.935966 -194.787555) (xy 96.970052 -194.743412)
			(xy 97.010201 -194.704703) (xy 97.055559 -194.672252) (xy 97.105159 -194.646751) (xy 97.157943 -194.628744)
			(xy 97.212786 -194.618614) (xy 97.26852 -194.616577) (xy 97.323957 -194.622677) (xy 97.377914 -194.636783)
			(xy 97.429243 -194.658595) (xy 97.476849 -194.687649) (xy 97.519717 -194.723324) (xy 97.556934 -194.764861)
			(xy 97.587707 -194.811374) (xy 97.611379 -194.861871) (xy 97.627447 -194.915278) (xy 97.635567 -194.970454)
			(xy 97.636076 -194.99834) (xy 97.635567 -195.026226) (xy 97.627447 -195.081402) (xy 97.611379 -195.134809)
			(xy 97.587707 -195.185306) (xy 97.556934 -195.231819) (xy 97.519717 -195.273356) (xy 97.476849 -195.309031)
			(xy 97.429243 -195.338085) (xy 97.377914 -195.359897) (xy 97.323957 -195.374003) (xy 97.26852 -195.380103)
			(xy 97.212786 -195.378066) (xy 97.157943 -195.367936) (xy 97.105159 -195.349929) (xy 97.055559 -195.324428)
			(xy 97.010201 -195.291977) (xy 96.970052 -195.253268) (xy 96.935966 -195.209125) (xy 96.90867 -195.16049)
			(xy 96.888747 -195.108399) (xy 96.876621 -195.053962) (xy 96.87255 -194.99834) (xy 94.940737 -194.99834)
			(xy 94.990198 -195.060171) (xy 95.102934 -195.213972) (xy 95.209087 -195.372388) (xy 95.308467 -195.535139)
			(xy 95.400897 -195.701934) (xy 95.486214 -195.872478) (xy 95.564266 -196.046466) (xy 95.634913 -196.223591)
			(xy 95.698031 -196.403536) (xy 95.753507 -196.585982) (xy 95.778295 -196.681852) (xy 97.862642 -196.681852)
			(xy 97.866713 -196.62623) (xy 97.878839 -196.571793) (xy 97.898762 -196.519702) (xy 97.926058 -196.471067)
			(xy 97.960144 -196.426924) (xy 98.000293 -196.388215) (xy 98.045651 -196.355764) (xy 98.095251 -196.330263)
			(xy 98.148035 -196.312256) (xy 98.202878 -196.302126) (xy 98.258612 -196.300089) (xy 98.314049 -196.306189)
			(xy 98.368006 -196.320295) (xy 98.419335 -196.342107) (xy 98.466941 -196.371161) (xy 98.509809 -196.406836)
			(xy 98.547026 -196.448373) (xy 98.577799 -196.494886) (xy 98.601471 -196.545383) (xy 98.617539 -196.59879)
			(xy 98.625659 -196.653966) (xy 98.626168 -196.681852) (xy 98.625659 -196.709738) (xy 98.617539 -196.764914)
			(xy 98.601471 -196.818321) (xy 98.577799 -196.868818) (xy 98.547026 -196.915331) (xy 98.509809 -196.956868)
			(xy 98.466941 -196.992543) (xy 98.419335 -197.021597) (xy 98.368006 -197.043409) (xy 98.314049 -197.057515)
			(xy 98.258612 -197.063615) (xy 98.202878 -197.061578) (xy 98.148035 -197.051448) (xy 98.095251 -197.033441)
			(xy 98.045651 -197.00794) (xy 98.000293 -196.975489) (xy 97.960144 -196.93678) (xy 97.926058 -196.892637)
			(xy 97.898762 -196.844002) (xy 97.878839 -196.791911) (xy 97.866713 -196.737474) (xy 97.862642 -196.681852)
			(xy 95.778295 -196.681852) (xy 95.801242 -196.770605) (xy 95.841152 -196.957075) (xy 95.873165 -197.145063)
			(xy 95.897225 -197.334233) (xy 95.913288 -197.524249) (xy 95.921327 -197.714773) (xy 95.92183 -197.81012)
			(xy 95.921327 -197.905467) (xy 95.913288 -198.095991) (xy 95.897225 -198.286007) (xy 95.873165 -198.475177)
			(xy 95.841152 -198.663165) (xy 95.801242 -198.849635) (xy 95.753507 -199.034258) (xy 95.698031 -199.216704)
			(xy 95.634913 -199.396649) (xy 95.564266 -199.573774) (xy 95.486214 -199.747762) (xy 95.400897 -199.918306)
			(xy 95.308467 -200.085101) (xy 95.209087 -200.247852) (xy 95.102934 -200.406268) (xy 94.990198 -200.560069)
			(xy 94.871078 -200.70898) (xy 94.745786 -200.852737) (xy 94.614545 -200.991085) (xy 94.477589 -201.123776)
			(xy 94.335161 -201.250577) (xy 94.187513 -201.37126) (xy 94.03491 -201.485612) (xy 93.877622 -201.593428)
			(xy 93.715928 -201.694519) (xy 93.550116 -201.788703) (xy 93.380481 -201.875813) (xy 93.207325 -201.955694)
			(xy 93.030955 -202.028205) (xy 92.851685 -202.093216) (xy 92.669834 -202.150612) (xy 92.485725 -202.200291)
			(xy 92.299685 -202.242164) (xy 92.112046 -202.276157) (xy 91.92314 -202.30221) (xy 91.733304 -202.320276)
			(xy 91.542875 -202.330323) (xy 91.352192 -202.332333) (xy 91.161593 -202.326303) (xy 90.971419 -202.312244)
			(xy 90.782006 -202.290179) (xy 90.593691 -202.26015) (xy 90.40681 -202.222208) (xy 90.221694 -202.176422)
			(xy 90.038674 -202.122873) (xy 89.858073 -202.061655) (xy 89.680214 -201.992879) (xy 89.505412 -201.916666)
			(xy 89.333978 -201.833152) (xy 89.166218 -201.742485) (xy 89.002429 -201.644826) (xy 88.842902 -201.540349)
			(xy 88.687921 -201.42924) (xy 88.537763 -201.311697) (xy 88.392693 -201.187927) (xy 88.252969 -201.058152)
			(xy 88.118841 -200.922603) (xy 87.990547 -200.781519) (xy 87.868313 -200.635152) (xy 87.752359 -200.483763)
			(xy 87.64289 -200.32762) (xy 87.540101 -200.167001) (xy 87.444175 -200.002191) (xy 87.355281 -199.833484)
			(xy 87.273579 -199.661179) (xy 87.199213 -199.485584) (xy 87.132315 -199.307009) (xy 87.073005 -199.125773)
			(xy 87.021388 -198.942198) (xy 86.977556 -198.75661) (xy 86.941587 -198.56934) (xy 86.913544 -198.380719)
			(xy 86.893478 -198.191084) (xy 86.881424 -198.000771) (xy 86.877404 -197.81012) (xy 86.534752 -197.81012)
			(xy 86.534752 -216.048336) (xy 85.19414 -217.388948) (xy 85.19414 -227.25507) (xy 86.197697 -227.25507)
			(xy 86.201732 -227.179366) (xy 86.213791 -227.104521) (xy 86.233737 -227.03138) (xy 86.261344 -226.960775)
			(xy 86.2963 -226.893504) (xy 86.338208 -226.830329) (xy 86.386594 -226.771967) (xy 86.44091 -226.719079)
			(xy 86.500539 -226.672264) (xy 86.564807 -226.632052) (xy 86.632984 -226.5989) (xy 86.7043 -226.573182)
			(xy 86.777945 -226.55519) (xy 86.853085 -226.545128) (xy 86.928869 -226.543109) (xy 87.004439 -226.549158)
			(xy 87.078937 -226.563205) (xy 87.15152 -226.585091) (xy 87.221366 -226.614568) (xy 87.287683 -226.651303)
			(xy 87.349719 -226.694878) (xy 87.406772 -226.7448) (xy 87.458196 -226.800504) (xy 87.503407 -226.861359)
			(xy 87.541894 -226.926674) (xy 87.57322 -226.99571) (xy 87.59703 -227.067685) (xy 87.613055 -227.141783)
			(xy 87.621114 -227.217164) (xy 87.621618 -227.25507) (xy 88.737697 -227.25507) (xy 88.741732 -227.179366)
			(xy 88.753791 -227.104521) (xy 88.773737 -227.03138) (xy 88.801344 -226.960775) (xy 88.8363 -226.893504)
			(xy 88.878208 -226.830329) (xy 88.926594 -226.771967) (xy 88.98091 -226.719079) (xy 89.040539 -226.672264)
			(xy 89.104807 -226.632052) (xy 89.172984 -226.5989) (xy 89.2443 -226.573182) (xy 89.317945 -226.55519)
			(xy 89.393085 -226.545128) (xy 89.468869 -226.543109) (xy 89.544439 -226.549158) (xy 89.618937 -226.563205)
			(xy 89.69152 -226.585091) (xy 89.761366 -226.614568) (xy 89.827683 -226.651303) (xy 89.889719 -226.694878)
			(xy 89.946772 -226.7448) (xy 89.998196 -226.800504) (xy 90.043407 -226.861359) (xy 90.081894 -226.926674)
			(xy 90.11322 -226.99571) (xy 90.13703 -227.067685) (xy 90.153055 -227.141783) (xy 90.161114 -227.217164)
			(xy 90.161618 -227.25507) (xy 91.277697 -227.25507) (xy 91.281732 -227.179366) (xy 91.293791 -227.104521)
			(xy 91.313737 -227.03138) (xy 91.341344 -226.960775) (xy 91.3763 -226.893504) (xy 91.418208 -226.830329)
			(xy 91.466594 -226.771967) (xy 91.52091 -226.719079) (xy 91.580539 -226.672264) (xy 91.644807 -226.632052)
			(xy 91.712984 -226.5989) (xy 91.7843 -226.573182) (xy 91.857945 -226.55519) (xy 91.933085 -226.545128)
			(xy 92.008869 -226.543109) (xy 92.084439 -226.549158) (xy 92.158937 -226.563205) (xy 92.23152 -226.585091)
			(xy 92.301366 -226.614568) (xy 92.367683 -226.651303) (xy 92.429719 -226.694878) (xy 92.486772 -226.7448)
			(xy 92.538196 -226.800504) (xy 92.583407 -226.861359) (xy 92.621894 -226.926674) (xy 92.65322 -226.99571)
			(xy 92.67703 -227.067685) (xy 92.693055 -227.141783) (xy 92.701114 -227.217164) (xy 92.701618 -227.25507)
			(xy 92.701114 -227.292976) (xy 92.693055 -227.368357) (xy 92.67703 -227.442455) (xy 92.65322 -227.51443)
			(xy 92.621894 -227.583466) (xy 92.583407 -227.648781) (xy 92.538196 -227.709636) (xy 92.486772 -227.76534)
			(xy 92.429719 -227.815262) (xy 92.367683 -227.858837) (xy 92.301366 -227.895572) (xy 92.23152 -227.925049)
			(xy 92.158937 -227.946935) (xy 92.084439 -227.960982) (xy 92.008869 -227.967031) (xy 91.933085 -227.965012)
			(xy 91.857945 -227.95495) (xy 91.7843 -227.936958) (xy 91.712984 -227.91124) (xy 91.644807 -227.878088)
			(xy 91.580539 -227.837876) (xy 91.52091 -227.791061) (xy 91.466594 -227.738173) (xy 91.418208 -227.679811)
			(xy 91.3763 -227.616636) (xy 91.341344 -227.549365) (xy 91.313737 -227.47876) (xy 91.293791 -227.405619)
			(xy 91.281732 -227.330774) (xy 91.277697 -227.25507) (xy 90.161618 -227.25507) (xy 90.161114 -227.292976)
			(xy 90.153055 -227.368357) (xy 90.13703 -227.442455) (xy 90.11322 -227.51443) (xy 90.081894 -227.583466)
			(xy 90.043407 -227.648781) (xy 89.998196 -227.709636) (xy 89.946772 -227.76534) (xy 89.889719 -227.815262)
			(xy 89.827683 -227.858837) (xy 89.761366 -227.895572) (xy 89.69152 -227.925049) (xy 89.618937 -227.946935)
			(xy 89.544439 -227.960982) (xy 89.468869 -227.967031) (xy 89.393085 -227.965012) (xy 89.317945 -227.95495)
			(xy 89.2443 -227.936958) (xy 89.172984 -227.91124) (xy 89.104807 -227.878088) (xy 89.040539 -227.837876)
			(xy 88.98091 -227.791061) (xy 88.926594 -227.738173) (xy 88.878208 -227.679811) (xy 88.8363 -227.616636)
			(xy 88.801344 -227.549365) (xy 88.773737 -227.47876) (xy 88.753791 -227.405619) (xy 88.741732 -227.330774)
			(xy 88.737697 -227.25507) (xy 87.621618 -227.25507) (xy 87.621114 -227.292976) (xy 87.613055 -227.368357)
			(xy 87.59703 -227.442455) (xy 87.57322 -227.51443) (xy 87.541894 -227.583466) (xy 87.503407 -227.648781)
			(xy 87.458196 -227.709636) (xy 87.406772 -227.76534) (xy 87.349719 -227.815262) (xy 87.287683 -227.858837)
			(xy 87.221366 -227.895572) (xy 87.15152 -227.925049) (xy 87.078937 -227.946935) (xy 87.004439 -227.960982)
			(xy 86.928869 -227.967031) (xy 86.853085 -227.965012) (xy 86.777945 -227.95495) (xy 86.7043 -227.936958)
			(xy 86.632984 -227.91124) (xy 86.564807 -227.878088) (xy 86.500539 -227.837876) (xy 86.44091 -227.791061)
			(xy 86.386594 -227.738173) (xy 86.338208 -227.679811) (xy 86.2963 -227.616636) (xy 86.261344 -227.549365)
			(xy 86.233737 -227.47876) (xy 86.213791 -227.405619) (xy 86.201732 -227.330774) (xy 86.197697 -227.25507)
			(xy 85.19414 -227.25507) (xy 85.19414 -227.745798) (xy 85.209364 -227.764674) (xy 85.245693 -227.796789)
			(xy 85.287446 -227.821443) (xy 85.333112 -227.837746) (xy 85.381039 -227.845107) (xy 85.429493 -227.84326)
			(xy 85.45322 -227.838254) (xy 85.489387 -227.828916) (xy 85.563128 -227.816981) (xy 85.637714 -227.812835)
			(xy 85.712323 -227.816523) (xy 85.786136 -227.828005) (xy 85.85834 -227.847155) (xy 85.928142 -227.873761)
			(xy 85.994773 -227.907531) (xy 86.057501 -227.948095) (xy 86.115636 -227.995005) (xy 86.168538 -228.047745)
			(xy 86.215625 -228.105736) (xy 86.25638 -228.168339) (xy 86.290354 -228.234867) (xy 86.317174 -228.304587)
			(xy 86.336544 -228.376733) (xy 86.348252 -228.45051) (xy 86.352168 -228.525108) (xy 86.34825 -228.599706)
			(xy 86.336541 -228.673483) (xy 86.317169 -228.745628) (xy 86.290348 -228.815347) (xy 86.256372 -228.881874)
			(xy 86.215616 -228.944477) (xy 86.168527 -229.002467) (xy 86.115624 -229.055206) (xy 86.057489 -229.102115)
			(xy 85.99476 -229.142676) (xy 85.928128 -229.176445) (xy 85.858325 -229.20305) (xy 85.786121 -229.222198)
			(xy 85.712307 -229.233678) (xy 85.637698 -229.237365) (xy 85.563113 -229.233217) (xy 85.489372 -229.22128)
			(xy 85.45322 -229.211886) (xy 85.429488 -229.206918) (xy 85.381043 -229.205071) (xy 85.333124 -229.212432)
			(xy 85.287466 -229.228734) (xy 85.245722 -229.253387) (xy 85.209402 -229.2855) (xy 85.19414 -229.304342)
			(xy 85.19414 -230.285798) (xy 85.209364 -230.304674) (xy 85.245693 -230.336789) (xy 85.287446 -230.361443)
			(xy 85.333112 -230.377746) (xy 85.381039 -230.385107) (xy 85.429493 -230.38326) (xy 85.45322 -230.378254)
			(xy 85.494171 -230.367756) (xy 85.577807 -230.355407) (xy 85.662317 -230.35304) (xy 85.746513 -230.360688)
			(xy 85.787992 -230.368856) (xy 85.8275 -230.377843) (xy 85.904326 -230.403591) (xy 85.977731 -230.437896)
			(xy 86.046766 -230.480314) (xy 86.110538 -230.530297) (xy 86.139782 -230.55834) (xy 86.170624 -230.589702)
			(xy 86.225136 -230.658736) (xy 86.248494 -230.696008) (xy 86.264418 -230.722971) (xy 86.292017 -230.779187)
			(xy 86.303612 -230.808276) (xy 86.313264 -230.833168) (xy 86.33206 -230.852218) (xy 86.344192 -230.863679)
			(xy 86.373071 -230.880388) (xy 86.405294 -230.889039) (xy 86.438658 -230.889039) (xy 86.470881 -230.880388)
			(xy 86.49976 -230.863679) (xy 86.511892 -230.852218) (xy 86.583012 -230.781098) (xy 86.583012 -230.500428)
			(xy 86.582561 -230.484533) (xy 86.574767 -230.453717) (xy 86.559581 -230.425791) (xy 86.537952 -230.402498)
			(xy 86.524846 -230.393494) (xy 86.495439 -230.374071) (xy 86.44022 -230.330274) (xy 86.389599 -230.281235)
			(xy 86.344073 -230.227433) (xy 86.304086 -230.169395) (xy 86.270031 -230.10769) (xy 86.242241 -230.042921)
			(xy 86.231222 -230.009446) (xy 86.219637 -229.970913) (xy 86.204212 -229.891939) (xy 86.197786 -229.81173)
			(xy 86.200441 -229.731307) (xy 86.212143 -229.651696) (xy 86.232743 -229.573912) (xy 86.261979 -229.498944)
			(xy 86.280244 -229.463092) (xy 86.280498 -229.462838) (xy 86.296247 -229.433784) (xy 86.332371 -229.378438)
			(xy 86.373478 -229.326685) (xy 86.396068 -229.302564) (xy 86.414468 -229.283727) (xy 86.453623 -229.24851)
			(xy 86.4743 -229.232206) (xy 86.503245 -229.210377) (xy 86.564797 -229.172064) (xy 86.629926 -229.140208)
			(xy 86.697955 -229.115137) (xy 86.768181 -229.097113) (xy 86.839875 -229.086322) (xy 86.912295 -229.082875)
			(xy 86.948518 -229.084378) (xy 86.989803 -229.08721) (xy 87.071363 -229.101228) (xy 87.150747 -229.124609)
			(xy 87.189056 -229.140258) (xy 87.223969 -229.155688) (xy 87.290581 -229.192968) (xy 87.352823 -229.23716)
			(xy 87.409979 -229.287757) (xy 87.461395 -229.344178) (xy 87.50648 -229.405776) (xy 87.544716 -229.471844)
			(xy 87.560658 -229.506526) (xy 87.560658 -229.50678) (xy 87.57539 -229.5398) (xy 87.6935 -229.620572)
			(xy 87.789004 -229.608888) (xy 87.853012 -229.536752) (xy 87.853012 -229.230428) (xy 87.852561 -229.214533)
			(xy 87.844767 -229.183717) (xy 87.829581 -229.155791) (xy 87.807952 -229.132498) (xy 87.794846 -229.123494)
			(xy 87.765439 -229.104071) (xy 87.71022 -229.060274) (xy 87.659599 -229.011235) (xy 87.614073 -228.957433)
			(xy 87.574086 -228.899395) (xy 87.540031 -228.83769) (xy 87.512241 -228.772921) (xy 87.501222 -228.739446)
			(xy 87.489637 -228.700913) (xy 87.474212 -228.621939) (xy 87.467786 -228.54173) (xy 87.470441 -228.461307)
			(xy 87.482143 -228.381696) (xy 87.502743 -228.303912) (xy 87.531979 -228.228944) (xy 87.550244 -228.193092)
			(xy 87.550498 -228.192838) (xy 87.566247 -228.163784) (xy 87.602371 -228.108438) (xy 87.643478 -228.056685)
			(xy 87.666068 -228.032564) (xy 87.691884 -228.006302) (xy 87.748063 -227.95868) (xy 87.808858 -227.917112)
			(xy 87.873618 -227.882041) (xy 87.941653 -227.853842) (xy 88.012235 -227.832815) (xy 88.048338 -227.825554)
			(xy 88.084194 -227.819279) (xy 88.156737 -227.813194) (xy 88.229522 -227.814536) (xy 88.30179 -227.82329)
			(xy 88.33739 -227.830888) (xy 88.373191 -227.839479) (xy 88.442932 -227.863084) (xy 88.509863 -227.893765)
			(xy 88.573268 -227.931194) (xy 88.632468 -227.974971) (xy 88.686831 -228.024627) (xy 88.735775 -228.079633)
			(xy 88.778777 -228.139398) (xy 88.815377 -228.203285) (xy 88.830658 -228.23678) (xy 88.845067 -228.270473)
			(xy 88.867704 -228.340173) (xy 88.883062 -228.411829) (xy 88.890977 -228.484684) (xy 88.891191 -228.52507)
			(xy 90.007697 -228.52507) (xy 90.011732 -228.449366) (xy 90.023791 -228.374521) (xy 90.043737 -228.30138)
			(xy 90.071344 -228.230775) (xy 90.1063 -228.163504) (xy 90.148208 -228.100329) (xy 90.196594 -228.041967)
			(xy 90.25091 -227.989079) (xy 90.310539 -227.942264) (xy 90.374807 -227.902052) (xy 90.442984 -227.8689)
			(xy 90.5143 -227.843182) (xy 90.587945 -227.82519) (xy 90.663085 -227.815128) (xy 90.738869 -227.813109)
			(xy 90.814439 -227.819158) (xy 90.888937 -227.833205) (xy 90.96152 -227.855091) (xy 91.031366 -227.884568)
			(xy 91.097683 -227.921303) (xy 91.159719 -227.964878) (xy 91.216772 -228.0148) (xy 91.268196 -228.070504)
			(xy 91.313407 -228.131359) (xy 91.351894 -228.196674) (xy 91.38322 -228.26571) (xy 91.40703 -228.337685)
			(xy 91.423055 -228.411783) (xy 91.431114 -228.487164) (xy 91.431618 -228.52507) (xy 91.431114 -228.562976)
			(xy 91.423055 -228.638357) (xy 91.40703 -228.712455) (xy 91.38322 -228.78443) (xy 91.351894 -228.853466)
			(xy 91.313407 -228.918781) (xy 91.268196 -228.979636) (xy 91.216772 -229.03534) (xy 91.159719 -229.085262)
			(xy 91.097683 -229.128837) (xy 91.031366 -229.165572) (xy 90.96152 -229.195049) (xy 90.888937 -229.216935)
			(xy 90.814439 -229.230982) (xy 90.738869 -229.237031) (xy 90.663085 -229.235012) (xy 90.587945 -229.22495)
			(xy 90.5143 -229.206958) (xy 90.442984 -229.18124) (xy 90.374807 -229.148088) (xy 90.310539 -229.107876)
			(xy 90.25091 -229.061061) (xy 90.196594 -229.008173) (xy 90.148208 -228.949811) (xy 90.1063 -228.886636)
			(xy 90.071344 -228.819365) (xy 90.043737 -228.74876) (xy 90.023791 -228.675619) (xy 90.011732 -228.600774)
			(xy 90.007697 -228.52507) (xy 88.891191 -228.52507) (xy 88.891365 -228.557967) (xy 88.884224 -228.630901)
			(xy 88.869628 -228.702717) (xy 88.847731 -228.772652) (xy 88.818766 -228.839969) (xy 88.783039 -228.903954)
			(xy 88.740927 -228.96393) (xy 88.692878 -229.019262) (xy 88.639398 -229.069366) (xy 88.581054 -229.113711)
			(xy 88.549988 -229.133146) (xy 88.52154 -229.150418) (xy 88.489028 -229.20833) (xy 88.489028 -229.79507)
			(xy 88.734138 -229.79507) (xy 88.742266 -229.71887) (xy 88.746832 -229.681246) (xy 88.762912 -229.607178)
			(xy 88.786772 -229.535239) (xy 88.818141 -229.466242) (xy 88.856665 -229.400969) (xy 88.901907 -229.34016)
			(xy 88.953355 -229.284503) (xy 89.010426 -229.234628) (xy 89.072474 -229.1911) (xy 89.138796 -229.154412)
			(xy 89.208641 -229.12498) (xy 89.281218 -229.103137) (xy 89.355706 -229.08913) (xy 89.43126 -229.083117)
			(xy 89.507026 -229.085168) (xy 89.582144 -229.095258) (xy 89.655765 -229.113274) (xy 89.727055 -229.139011)
			(xy 89.795206 -229.172179) (xy 89.859446 -229.2124) (xy 89.919048 -229.259221) (xy 89.973338 -229.31211)
			(xy 90.0217 -229.370468) (xy 90.063586 -229.433636) (xy 90.098523 -229.500897) (xy 90.126114 -229.57149)
			(xy 90.146047 -229.644615) (xy 90.158097 -229.719444) (xy 90.162124 -229.79507) (xy 91.277697 -229.79507)
			(xy 91.281732 -229.719366) (xy 91.293791 -229.644521) (xy 91.313737 -229.57138) (xy 91.341344 -229.500775)
			(xy 91.3763 -229.433504) (xy 91.418208 -229.370329) (xy 91.466594 -229.311967) (xy 91.52091 -229.259079)
			(xy 91.580539 -229.212264) (xy 91.644807 -229.172052) (xy 91.712984 -229.1389) (xy 91.7843 -229.113182)
			(xy 91.857945 -229.09519) (xy 91.933085 -229.085128) (xy 92.008869 -229.083109) (xy 92.084439 -229.089158)
			(xy 92.158937 -229.103205) (xy 92.23152 -229.125091) (xy 92.301366 -229.154568) (xy 92.367683 -229.191303)
			(xy 92.429719 -229.234878) (xy 92.486772 -229.2848) (xy 92.538196 -229.340504) (xy 92.583407 -229.401359)
			(xy 92.621894 -229.466674) (xy 92.65322 -229.53571) (xy 92.67703 -229.607685) (xy 92.693055 -229.681783)
			(xy 92.701114 -229.757164) (xy 92.701618 -229.79507) (xy 92.701114 -229.832976) (xy 92.693055 -229.908357)
			(xy 92.67703 -229.982455) (xy 92.65322 -230.05443) (xy 92.621894 -230.123466) (xy 92.583407 -230.188781)
			(xy 92.538196 -230.249636) (xy 92.486772 -230.30534) (xy 92.429719 -230.355262) (xy 92.367683 -230.398837)
			(xy 92.301366 -230.435572) (xy 92.23152 -230.465049) (xy 92.158937 -230.486935) (xy 92.084439 -230.500982)
			(xy 92.008869 -230.507031) (xy 91.933085 -230.505012) (xy 91.857945 -230.49495) (xy 91.7843 -230.476958)
			(xy 91.712984 -230.45124) (xy 91.644807 -230.418088) (xy 91.580539 -230.377876) (xy 91.52091 -230.331061)
			(xy 91.466594 -230.278173) (xy 91.418208 -230.219811) (xy 91.3763 -230.156636) (xy 91.341344 -230.089365)
			(xy 91.313737 -230.01876) (xy 91.293791 -229.945619) (xy 91.281732 -229.870774) (xy 91.277697 -229.79507)
			(xy 90.162124 -229.79507) (xy 90.162127 -229.79513) (xy 90.158091 -229.870815) (xy 90.146035 -229.945644)
			(xy 90.126095 -230.018767) (xy 90.098498 -230.089357) (xy 90.063556 -230.156615) (xy 90.021664 -230.219779)
			(xy 89.973297 -230.278134) (xy 89.919003 -230.331019) (xy 89.859397 -230.377834) (xy 89.795153 -230.41805)
			(xy 89.727 -230.451212) (xy 89.655708 -230.476943) (xy 89.582086 -230.494953) (xy 89.506966 -230.505037)
			(xy 89.431201 -230.507081) (xy 89.355647 -230.501063) (xy 89.28116 -230.487049) (xy 89.208585 -230.4652)
			(xy 89.138742 -230.435762) (xy 89.072423 -230.399069) (xy 89.010379 -230.355536) (xy 88.953312 -230.305656)
			(xy 88.901869 -230.249994) (xy 88.856632 -230.189181) (xy 88.818114 -230.123905) (xy 88.78675 -230.054906)
			(xy 88.762896 -229.982964) (xy 88.746823 -229.908895) (xy 88.742266 -229.87127) (xy 88.734138 -229.79507)
			(xy 88.489028 -229.79507) (xy 88.489028 -230.021384) (xy 88.378284 -230.132128) (xy 88.378284 -230.291894)
			(xy 88.454992 -230.407464) (xy 88.486742 -230.422704) (xy 88.52041 -230.439318) (xy 88.584383 -230.478622)
			(xy 88.643864 -230.52444) (xy 88.698192 -230.576265) (xy 88.746763 -230.633519) (xy 88.789039 -230.695568)
			(xy 88.82455 -230.761722) (xy 88.8529 -230.831246) (xy 88.873776 -230.903367) (xy 88.886945 -230.977285)
			(xy 88.892261 -231.052179) (xy 88.891815 -231.06507) (xy 90.007697 -231.06507) (xy 90.011732 -230.989366)
			(xy 90.023791 -230.914521) (xy 90.043737 -230.84138) (xy 90.071344 -230.770775) (xy 90.1063 -230.703504)
			(xy 90.148208 -230.640329) (xy 90.196594 -230.581967) (xy 90.25091 -230.529079) (xy 90.310539 -230.482264)
			(xy 90.374807 -230.442052) (xy 90.442984 -230.4089) (xy 90.5143 -230.383182) (xy 90.587945 -230.36519)
			(xy 90.663085 -230.355128) (xy 90.738869 -230.353109) (xy 90.814439 -230.359158) (xy 90.888937 -230.373205)
			(xy 90.96152 -230.395091) (xy 91.031366 -230.424568) (xy 91.097683 -230.461303) (xy 91.159719 -230.504878)
			(xy 91.165664 -230.51008) (xy 93.154506 -230.51008) (xy 93.158522 -230.39381) (xy 93.170549 -230.278095)
			(xy 93.190531 -230.163485) (xy 93.218373 -230.050526) (xy 93.253942 -229.939758) (xy 93.297068 -229.831707)
			(xy 93.347545 -229.726889) (xy 93.405134 -229.625804) (xy 93.46956 -229.528932) (xy 93.540515 -229.436736)
			(xy 93.617662 -229.349655) (xy 93.700633 -229.268104) (xy 93.789033 -229.192472) (xy 93.88244 -229.123118)
			(xy 93.980409 -229.060375) (xy 94.082473 -229.004539) (xy 94.188147 -228.955878) (xy 94.296926 -228.914624)
			(xy 94.408291 -228.880973) (xy 94.521714 -228.855085) (xy 94.636651 -228.837084) (xy 94.752557 -228.827055)
			(xy 94.868879 -228.825047) (xy 94.985062 -228.831069) (xy 95.100553 -228.845092) (xy 95.214801 -228.86705)
			(xy 95.327262 -228.896837) (xy 95.4374 -228.934312) (xy 95.54469 -228.979297) (xy 95.648621 -229.031576)
			(xy 95.748697 -229.090901) (xy 95.844443 -229.156989) (xy 95.9354 -229.229525) (xy 96.021136 -229.308164)
			(xy 96.101243 -229.39253) (xy 96.175339 -229.482222) (xy 96.243069 -229.576812) (xy 96.304113 -229.67585)
			(xy 96.358178 -229.778863) (xy 96.405008 -229.88536) (xy 96.444379 -229.994835) (xy 96.476103 -230.106765)
			(xy 96.500029 -230.220617) (xy 96.516043 -230.335849) (xy 96.52407 -230.451911) (xy 96.524572 -230.51008)
			(xy 96.52407 -230.568249) (xy 96.516043 -230.684311) (xy 96.500029 -230.799543) (xy 96.476103 -230.913395)
			(xy 96.444379 -231.025325) (xy 96.405008 -231.1348) (xy 96.358178 -231.241297) (xy 96.304113 -231.34431)
			(xy 96.243069 -231.443348) (xy 96.175339 -231.537938) (xy 96.101243 -231.62763) (xy 96.021136 -231.711996)
			(xy 95.9354 -231.790635) (xy 95.844443 -231.863171) (xy 95.748697 -231.929259) (xy 95.648621 -231.988584)
			(xy 95.54469 -232.040863) (xy 95.4374 -232.085848) (xy 95.327262 -232.123323) (xy 95.214801 -232.15311)
			(xy 95.100553 -232.175068) (xy 94.985062 -232.189091) (xy 94.868879 -232.195113) (xy 94.752557 -232.193105)
			(xy 94.636651 -232.183076) (xy 94.521714 -232.165075) (xy 94.408291 -232.139187) (xy 94.296926 -232.105536)
			(xy 94.188147 -232.064282) (xy 94.082473 -232.015621) (xy 93.980409 -231.959785) (xy 93.88244 -231.897042)
			(xy 93.789033 -231.827688) (xy 93.700633 -231.752056) (xy 93.617662 -231.670505) (xy 93.540515 -231.583424)
			(xy 93.46956 -231.491228) (xy 93.405134 -231.394356) (xy 93.347545 -231.293271) (xy 93.297068 -231.188453)
			(xy 93.253942 -231.080402) (xy 93.218373 -230.969634) (xy 93.190531 -230.856675) (xy 93.170549 -230.742065)
			(xy 93.158522 -230.62635) (xy 93.154506 -230.51008) (xy 91.165664 -230.51008) (xy 91.216772 -230.5548)
			(xy 91.268196 -230.610504) (xy 91.313407 -230.671359) (xy 91.351894 -230.736674) (xy 91.38322 -230.80571)
			(xy 91.40703 -230.877685) (xy 91.423055 -230.951783) (xy 91.431114 -231.027164) (xy 91.431618 -231.06507)
			(xy 91.431114 -231.102976) (xy 91.423055 -231.178357) (xy 91.40703 -231.252455) (xy 91.38322 -231.32443)
			(xy 91.351894 -231.393466) (xy 91.313407 -231.458781) (xy 91.268196 -231.519636) (xy 91.216772 -231.57534)
			(xy 91.159719 -231.625262) (xy 91.097683 -231.668837) (xy 91.031366 -231.705572) (xy 90.96152 -231.735049)
			(xy 90.888937 -231.756935) (xy 90.814439 -231.770982) (xy 90.738869 -231.777031) (xy 90.663085 -231.775012)
			(xy 90.587945 -231.76495) (xy 90.5143 -231.746958) (xy 90.442984 -231.72124) (xy 90.374807 -231.688088)
			(xy 90.310539 -231.647876) (xy 90.25091 -231.601061) (xy 90.196594 -231.548173) (xy 90.148208 -231.489811)
			(xy 90.1063 -231.426636) (xy 90.071344 -231.359365) (xy 90.043737 -231.28876) (xy 90.023791 -231.215619)
			(xy 90.011732 -231.140774) (xy 90.007697 -231.06507) (xy 88.891815 -231.06507) (xy 88.889665 -231.127216)
			(xy 88.879186 -231.201563) (xy 88.860939 -231.274394) (xy 88.835129 -231.3449) (xy 88.802041 -231.412299)
			(xy 88.762044 -231.47584) (xy 88.715581 -231.534819) (xy 88.663168 -231.58858) (xy 88.605389 -231.636525)
			(xy 88.542883 -231.678124) (xy 88.476347 -231.712912) (xy 88.406519 -231.740505) (xy 88.334175 -231.760595)
			(xy 88.260118 -231.772958) (xy 88.185171 -231.777459) (xy 88.110166 -231.774047) (xy 88.072976 -231.768904)
			(xy 88.05819 -231.767083) (xy 88.028512 -231.769584) (xy 88.00022 -231.778892) (xy 87.974854 -231.794502)
			(xy 87.96401 -231.804718) (xy 83.867244 -235.90123) (xy 83.855893 -235.913378) (xy 83.839298 -235.942173)
			(xy 83.830695 -235.974275) (xy 83.83016 -235.990892) (xy 83.83016 -236.954822) (xy 83.832954 -236.96803)
			(xy 83.838274 -236.994915) (xy 83.842052 -237.049588) (xy 83.837962 -237.10424) (xy 83.826089 -237.157742)
			(xy 83.822905 -237.16615) (xy 86.906606 -237.16615) (xy 86.910677 -237.110528) (xy 86.922803 -237.056091)
			(xy 86.942726 -237.004) (xy 86.970022 -236.955365) (xy 87.004108 -236.911222) (xy 87.044257 -236.872513)
			(xy 87.089615 -236.840062) (xy 87.139215 -236.814561) (xy 87.191999 -236.796554) (xy 87.246842 -236.786424)
			(xy 87.302576 -236.784387) (xy 87.358013 -236.790487) (xy 87.41197 -236.804593) (xy 87.463299 -236.826405)
			(xy 87.510905 -236.855459) (xy 87.553773 -236.891134) (xy 87.59099 -236.932671) (xy 87.621763 -236.979184)
			(xy 87.645435 -237.029681) (xy 87.661503 -237.083088) (xy 87.669623 -237.138264) (xy 87.670132 -237.16615)
			(xy 87.669623 -237.194036) (xy 87.661503 -237.249212) (xy 87.645435 -237.302619) (xy 87.621763 -237.353116)
			(xy 87.59099 -237.399629) (xy 87.553773 -237.441166) (xy 87.510905 -237.476841) (xy 87.463299 -237.505895)
			(xy 87.41197 -237.527707) (xy 87.358013 -237.541813) (xy 87.302576 -237.547913) (xy 87.246842 -237.545876)
			(xy 87.191999 -237.535746) (xy 87.139215 -237.517739) (xy 87.089615 -237.492238) (xy 87.044257 -237.459787)
			(xy 87.004108 -237.421078) (xy 86.970022 -237.376935) (xy 86.942726 -237.3283) (xy 86.922803 -237.276209)
			(xy 86.910677 -237.221772) (xy 86.906606 -237.16615) (xy 83.822905 -237.16615) (xy 83.806678 -237.208993)
			(xy 83.793838 -237.233206) (xy 83.777836 -237.261908) (xy 83.777836 -238.064548) (xy 85.002622 -238.064548)
			(xy 85.006693 -238.008926) (xy 85.018819 -237.954489) (xy 85.038742 -237.902398) (xy 85.066038 -237.853763)
			(xy 85.100124 -237.80962) (xy 85.140273 -237.770911) (xy 85.185631 -237.73846) (xy 85.235231 -237.712959)
			(xy 85.288015 -237.694952) (xy 85.342858 -237.684822) (xy 85.398592 -237.682785) (xy 85.454029 -237.688885)
			(xy 85.507986 -237.702991) (xy 85.559315 -237.724803) (xy 85.606921 -237.753857) (xy 85.649789 -237.789532)
			(xy 85.687006 -237.831069) (xy 85.717779 -237.877582) (xy 85.741451 -237.928079) (xy 85.757519 -237.981486)
			(xy 85.765639 -238.036662) (xy 85.766148 -238.064548) (xy 85.765639 -238.092434) (xy 85.757519 -238.14761)
			(xy 85.741451 -238.201017) (xy 85.717779 -238.251514) (xy 85.687006 -238.298027) (xy 85.649789 -238.339564)
			(xy 85.606921 -238.375239) (xy 85.559315 -238.404293) (xy 85.507986 -238.426105) (xy 85.454029 -238.440211)
			(xy 85.398592 -238.446311) (xy 85.342858 -238.444274) (xy 85.288015 -238.434144) (xy 85.235231 -238.416137)
			(xy 85.185631 -238.390636) (xy 85.140273 -238.358185) (xy 85.100124 -238.319476) (xy 85.066038 -238.275333)
			(xy 85.038742 -238.226698) (xy 85.018819 -238.174607) (xy 85.006693 -238.12017) (xy 85.002622 -238.064548)
			(xy 83.777836 -238.064548) (xy 83.777836 -239.691672) (xy 83.864196 -239.778032) (xy 83.876321 -239.789414)
			(xy 83.905091 -239.806068) (xy 83.937189 -239.814714) (xy 83.970432 -239.814764) (xy 84.002556 -239.806214)
			(xy 84.031376 -239.789646) (xy 84.04352 -239.778286) (xy 84.078572 -239.743234) (xy 84.080858 -239.693958)
			(xy 84.082583 -239.666928) (xy 84.092713 -239.613722) (xy 84.110266 -239.562483) (xy 84.134888 -239.514242)
			(xy 84.166084 -239.469967) (xy 84.203228 -239.430549) (xy 84.245573 -239.396779) (xy 84.292268 -239.369337)
			(xy 84.342375 -239.348774) (xy 84.394886 -239.335504) (xy 84.448745 -239.329792) (xy 84.475828 -239.33023)
			(xy 84.503757 -239.331747) (xy 84.558754 -239.341937) (xy 84.611674 -239.360043) (xy 84.661386 -239.385678)
			(xy 84.706825 -239.418293) (xy 84.747018 -239.45719) (xy 84.781105 -239.501535) (xy 84.808355 -239.55038)
			(xy 84.818728 -239.576356) (xy 84.822284 -239.586262) (xy 84.830871 -239.612433) (xy 84.841287 -239.666517)
			(xy 84.843814 -239.721537) (xy 84.838399 -239.776348) (xy 84.825155 -239.82981) (xy 84.804358 -239.88081)
			(xy 84.790788 -239.904778) (xy 84.775443 -239.929824) (xy 84.738273 -239.975303) (xy 84.694572 -240.014547)
			(xy 84.645373 -240.04663) (xy 84.61883 -240.05921) (xy 84.599444 -240.06939) (xy 84.564189 -240.095355)
			(xy 84.533902 -240.126974) (xy 84.509478 -240.163313) (xy 84.491638 -240.203298) (xy 84.48091 -240.245747)
			(xy 84.47761 -240.289407) (xy 84.481837 -240.332986) (xy 84.493465 -240.375198) (xy 84.51215 -240.414795)
			(xy 84.537341 -240.450607) (xy 84.552536 -240.466372) (xy 84.562696 -240.476532) (xy 84.574888 -240.488978)
			(xy 84.574888 -240.646966) (xy 84.598256 -240.701576) (xy 84.598256 -240.846864) (xy 84.574888 -240.870232)
			(xy 84.574888 -241.581178) (xy 83.895946 -242.26012) (xy 86.877404 -242.26012) (xy 86.881424 -242.069469)
			(xy 86.893478 -241.879156) (xy 86.913544 -241.689521) (xy 86.941587 -241.5009) (xy 86.977556 -241.31363)
			(xy 87.021388 -241.128042) (xy 87.073005 -240.944467) (xy 87.132315 -240.763231) (xy 87.199213 -240.584656)
			(xy 87.273579 -240.409061) (xy 87.355281 -240.236756) (xy 87.444175 -240.068049) (xy 87.540101 -239.903239)
			(xy 87.64289 -239.74262) (xy 87.752359 -239.586477) (xy 87.868313 -239.435088) (xy 87.990547 -239.288721)
			(xy 88.118841 -239.147637) (xy 88.252969 -239.012088) (xy 88.392693 -238.882313) (xy 88.537763 -238.758543)
			(xy 88.687921 -238.641) (xy 88.842902 -238.529891) (xy 89.002429 -238.425414) (xy 89.166218 -238.327755)
			(xy 89.333978 -238.237088) (xy 89.505412 -238.153574) (xy 89.680214 -238.077361) (xy 89.858073 -238.008585)
			(xy 90.038674 -237.947367) (xy 90.221694 -237.893818) (xy 90.40681 -237.848032) (xy 90.593691 -237.81009)
			(xy 90.782006 -237.780061) (xy 90.971419 -237.757996) (xy 91.161593 -237.743937) (xy 91.352192 -237.737907)
			(xy 91.542875 -237.739917) (xy 91.733304 -237.749964) (xy 91.92314 -237.76803) (xy 92.112046 -237.794083)
			(xy 92.299685 -237.828076) (xy 92.485725 -237.869949) (xy 92.669834 -237.919628) (xy 92.851685 -237.977024)
			(xy 93.030955 -238.042035) (xy 93.207325 -238.114546) (xy 93.380481 -238.194427) (xy 93.550116 -238.281537)
			(xy 93.715928 -238.375721) (xy 93.877622 -238.476812) (xy 94.03491 -238.584628) (xy 94.187513 -238.69898)
			(xy 94.335161 -238.819663) (xy 94.477589 -238.946464) (xy 94.614545 -239.079155) (xy 94.745786 -239.217503)
			(xy 94.871078 -239.36126) (xy 94.990198 -239.510171) (xy 95.102934 -239.663972) (xy 95.209087 -239.822388)
			(xy 95.308467 -239.985139) (xy 95.400897 -240.151934) (xy 95.486214 -240.322478) (xy 95.564266 -240.496466)
			(xy 95.634913 -240.673591) (xy 95.698031 -240.853536) (xy 95.753507 -241.035982) (xy 95.801242 -241.220605)
			(xy 95.841152 -241.407075) (xy 95.873165 -241.595063) (xy 95.897225 -241.784233) (xy 95.913288 -241.974249)
			(xy 95.921327 -242.164773) (xy 95.92183 -242.26012) (xy 95.921327 -242.355467) (xy 95.913288 -242.545991)
			(xy 95.897225 -242.736007) (xy 95.873165 -242.925177) (xy 95.841152 -243.113165) (xy 95.801242 -243.299635)
			(xy 95.753507 -243.484258) (xy 95.698031 -243.666704) (xy 95.634913 -243.846649) (xy 95.564266 -244.023774)
			(xy 95.486214 -244.197762) (xy 95.400897 -244.368306) (xy 95.308467 -244.535101) (xy 95.209087 -244.697852)
			(xy 95.102934 -244.856268) (xy 94.990198 -245.010069) (xy 94.871078 -245.15898) (xy 94.745786 -245.302737)
			(xy 94.614545 -245.441085) (xy 94.477589 -245.573776) (xy 94.335161 -245.700577) (xy 94.187513 -245.82126)
			(xy 94.03491 -245.935612) (xy 93.877622 -246.043428) (xy 93.715928 -246.144519) (xy 93.550116 -246.238703)
			(xy 93.380481 -246.325813) (xy 93.207325 -246.405694) (xy 93.030955 -246.478205) (xy 92.851685 -246.543216)
			(xy 92.669834 -246.600612) (xy 92.485725 -246.650291) (xy 92.299685 -246.692164) (xy 92.112046 -246.726157)
			(xy 91.92314 -246.75221) (xy 91.733304 -246.770276) (xy 91.542875 -246.780323) (xy 91.352192 -246.782333)
			(xy 91.161593 -246.776303) (xy 90.971419 -246.762244) (xy 90.782006 -246.740179) (xy 90.593691 -246.71015)
			(xy 90.40681 -246.672208) (xy 90.221694 -246.626422) (xy 90.038674 -246.572873) (xy 89.858073 -246.511655)
			(xy 89.680214 -246.442879) (xy 89.505412 -246.366666) (xy 89.333978 -246.283152) (xy 89.166218 -246.192485)
			(xy 89.002429 -246.094826) (xy 88.842902 -245.990349) (xy 88.687921 -245.87924) (xy 88.537763 -245.761697)
			(xy 88.392693 -245.637927) (xy 88.252969 -245.508152) (xy 88.118841 -245.372603) (xy 87.990547 -245.231519)
			(xy 87.868313 -245.085152) (xy 87.752359 -244.933763) (xy 87.64289 -244.77762) (xy 87.540101 -244.617001)
			(xy 87.444175 -244.452191) (xy 87.355281 -244.283484) (xy 87.273579 -244.111179) (xy 87.199213 -243.935584)
			(xy 87.132315 -243.757009) (xy 87.073005 -243.575773) (xy 87.021388 -243.392198) (xy 86.977556 -243.20661)
			(xy 86.941587 -243.01934) (xy 86.913544 -242.830719) (xy 86.893478 -242.641084) (xy 86.881424 -242.450771)
			(xy 86.877404 -242.26012) (xy 83.895946 -242.26012) (xy 83.777836 -242.37823) (xy 83.777836 -245.504462)
			(xy 71.73595 -257.546602) (xy 71.720298 -257.562943) (xy 71.694471 -257.600091) (xy 71.675641 -257.64123)
			(xy 71.664405 -257.685057) (xy 71.661119 -257.730181) (xy 71.665888 -257.775173) (xy 71.67856 -257.818606)
			(xy 71.698733 -257.859104) (xy 71.71182 -257.877564) (xy 71.727645 -257.899675) (xy 71.753543 -257.947483)
			(xy 71.772392 -257.998483) (xy 71.783811 -258.051642) (xy 71.787517 -258.105148) (xy 72.177146 -258.105148)
			(xy 72.181217 -258.049526) (xy 72.193343 -257.995089) (xy 72.213266 -257.942998) (xy 72.240562 -257.894363)
			(xy 72.274648 -257.85022) (xy 72.314797 -257.811511) (xy 72.360155 -257.77906) (xy 72.409755 -257.753559)
			(xy 72.462539 -257.735552) (xy 72.517382 -257.725422) (xy 72.573116 -257.723385) (xy 72.628553 -257.729485)
			(xy 72.68251 -257.743591) (xy 72.733839 -257.765403) (xy 72.781445 -257.794457) (xy 72.824313 -257.830132)
			(xy 72.86153 -257.871669) (xy 72.892303 -257.918182) (xy 72.915975 -257.968679) (xy 72.932043 -258.022086)
			(xy 72.940163 -258.077262) (xy 72.940672 -258.105148) (xy 73.30516 -258.105148) (xy 73.309231 -258.049526)
			(xy 73.321357 -257.995089) (xy 73.34128 -257.942998) (xy 73.368576 -257.894363) (xy 73.402662 -257.85022)
			(xy 73.442811 -257.811511) (xy 73.488169 -257.77906) (xy 73.537769 -257.753559) (xy 73.590553 -257.735552)
			(xy 73.645396 -257.725422) (xy 73.70113 -257.723385) (xy 73.756567 -257.729485) (xy 73.810524 -257.743591)
			(xy 73.861853 -257.765403) (xy 73.909459 -257.794457) (xy 73.952327 -257.830132) (xy 73.989544 -257.871669)
			(xy 74.020317 -257.918182) (xy 74.043989 -257.968679) (xy 74.060057 -258.022086) (xy 74.068177 -258.077262)
			(xy 74.068686 -258.105148) (xy 74.4507 -258.105148) (xy 74.454771 -258.049526) (xy 74.466897 -257.995089)
			(xy 74.48682 -257.942998) (xy 74.514116 -257.894363) (xy 74.548202 -257.85022) (xy 74.588351 -257.811511)
			(xy 74.633709 -257.77906) (xy 74.683309 -257.753559) (xy 74.736093 -257.735552) (xy 74.790936 -257.725422)
			(xy 74.84667 -257.723385) (xy 74.902107 -257.729485) (xy 74.956064 -257.743591) (xy 75.007393 -257.765403)
			(xy 75.054999 -257.794457) (xy 75.097867 -257.830132) (xy 75.135084 -257.871669) (xy 75.165857 -257.918182)
			(xy 75.189529 -257.968679) (xy 75.205597 -258.022086) (xy 75.213717 -258.077262) (xy 75.214226 -258.105148)
			(xy 75.213717 -258.133034) (xy 75.205597 -258.18821) (xy 75.189529 -258.241617) (xy 75.165857 -258.292114)
			(xy 75.135084 -258.338627) (xy 75.097867 -258.380164) (xy 75.054999 -258.415839) (xy 75.007393 -258.444893)
			(xy 74.956064 -258.466705) (xy 74.902107 -258.480811) (xy 74.84667 -258.486911) (xy 74.790936 -258.484874)
			(xy 74.736093 -258.474744) (xy 74.683309 -258.456737) (xy 74.633709 -258.431236) (xy 74.588351 -258.398785)
			(xy 74.548202 -258.360076) (xy 74.514116 -258.315933) (xy 74.48682 -258.267298) (xy 74.466897 -258.215207)
			(xy 74.454771 -258.16077) (xy 74.4507 -258.105148) (xy 74.068686 -258.105148) (xy 74.068177 -258.133034)
			(xy 74.060057 -258.18821) (xy 74.043989 -258.241617) (xy 74.020317 -258.292114) (xy 73.989544 -258.338627)
			(xy 73.952327 -258.380164) (xy 73.909459 -258.415839) (xy 73.861853 -258.444893) (xy 73.810524 -258.466705)
			(xy 73.756567 -258.480811) (xy 73.70113 -258.486911) (xy 73.645396 -258.484874) (xy 73.590553 -258.474744)
			(xy 73.537769 -258.456737) (xy 73.488169 -258.431236) (xy 73.442811 -258.398785) (xy 73.402662 -258.360076)
			(xy 73.368576 -258.315933) (xy 73.34128 -258.267298) (xy 73.321357 -258.215207) (xy 73.309231 -258.16077)
			(xy 73.30516 -258.105148) (xy 72.940672 -258.105148) (xy 72.940163 -258.133034) (xy 72.932043 -258.18821)
			(xy 72.915975 -258.241617) (xy 72.892303 -258.292114) (xy 72.86153 -258.338627) (xy 72.824313 -258.380164)
			(xy 72.781445 -258.415839) (xy 72.733839 -258.444893) (xy 72.68251 -258.466705) (xy 72.628553 -258.480811)
			(xy 72.573116 -258.486911) (xy 72.517382 -258.484874) (xy 72.462539 -258.474744) (xy 72.409755 -258.456737)
			(xy 72.360155 -258.431236) (xy 72.314797 -258.398785) (xy 72.274648 -258.360076) (xy 72.240562 -258.315933)
			(xy 72.213266 -258.267298) (xy 72.193343 -258.215207) (xy 72.181217 -258.16077) (xy 72.177146 -258.105148)
			(xy 71.787517 -258.105148) (xy 71.787568 -258.105884) (xy 71.783588 -258.16011) (xy 71.771951 -258.213222)
			(xy 71.752893 -258.264144) (xy 71.726799 -258.311845) (xy 71.694199 -258.35536) (xy 71.655752 -258.393806)
			(xy 71.612236 -258.426405) (xy 71.564534 -258.452497) (xy 71.513611 -258.471554) (xy 71.460499 -258.48319)
			(xy 71.406273 -258.487168) (xy 71.352031 -258.483409) (xy 71.298872 -258.471989) (xy 71.247873 -258.453138)
			(xy 71.200066 -258.427239) (xy 71.177912 -258.411472) (xy 71.159461 -258.398384) (xy 71.118948 -258.378267)
			(xy 71.075515 -258.365636) (xy 71.030533 -258.360888) (xy 70.98542 -258.364173) (xy 70.9416 -258.375388)
			(xy 70.900456 -258.39418) (xy 70.863285 -258.419954) (xy 70.84695 -258.435602) (xy 64.760094 -264.522458)
			(xy 64.760094 -265.06043) (xy 65.27292 -265.573256) (xy 87.647018 -265.573256) (xy 87.850726 -265.77671)
			(xy 87.882222 -265.7856) (xy 87.913464 -265.796268) (xy 87.94877 -265.811762) (xy 87.971958 -265.823956)
			(xy 88.015057 -265.853742) (xy 88.053681 -265.88914) (xy 88.087104 -265.929484) (xy 88.114699 -265.974019)
			(xy 88.135948 -266.021906) (xy 88.143588 -266.046966) (xy 88.152478 -266.078462) (xy 93.178884 -271.105122)
			(xy 93.178884 -272.326862) (xy 92.212922 -273.292824) (xy 92.14231 -273.292824) (xy 92.125656 -273.293317)
			(xy 92.093481 -273.301937) (xy 92.064635 -273.318592) (xy 92.041084 -273.342146) (xy 92.024432 -273.370994)
			(xy 92.015816 -273.403169) (xy 92.01531 -273.419824) (xy 92.01531 -273.466052) (xy 92.073984 -273.53641)
			(xy 92.119196 -273.544792) (xy 92.155339 -273.551955) (xy 92.226022 -273.572779) (xy 92.294176 -273.600791)
			(xy 92.359072 -273.635693) (xy 92.420016 -273.677111) (xy 92.476357 -273.724602) (xy 92.527491 -273.777658)
			(xy 92.572872 -273.835711) (xy 92.612015 -273.898141) (xy 92.644501 -273.96428) (xy 92.657676 -273.99869)
			(xy 92.669362 -274.031604) (xy 92.687003 -274.099188) (xy 92.69794 -274.168174) (xy 92.702069 -274.2379)
			(xy 92.69935 -274.307695) (xy 92.695014 -274.342352) (xy 92.688536 -274.384667) (xy 92.666739 -274.467451)
			(xy 92.635148 -274.547015) (xy 92.615258 -274.584922) (xy 92.60586 -274.601432) (xy 92.588137 -274.631241)
			(xy 92.547734 -274.687612) (xy 92.502037 -274.739784) (xy 92.45148 -274.787262) (xy 92.396544 -274.829595)
			(xy 92.367354 -274.84832) (xy 92.35396 -274.857253) (xy 92.331812 -274.880607) (xy 92.316216 -274.908761)
			(xy 92.308163 -274.939923) (xy 92.307664 -274.956016) (xy 92.307664 -274.96008) (xy 93.154506 -274.96008)
			(xy 93.158522 -274.84381) (xy 93.170549 -274.728095) (xy 93.190531 -274.613485) (xy 93.218373 -274.500526)
			(xy 93.253942 -274.389758) (xy 93.297068 -274.281707) (xy 93.347545 -274.176889) (xy 93.405134 -274.075804)
			(xy 93.46956 -273.978932) (xy 93.540515 -273.886736) (xy 93.617662 -273.799655) (xy 93.700633 -273.718104)
			(xy 93.789033 -273.642472) (xy 93.88244 -273.573118) (xy 93.980409 -273.510375) (xy 94.082473 -273.454539)
			(xy 94.188147 -273.405878) (xy 94.296926 -273.364624) (xy 94.408291 -273.330973) (xy 94.521714 -273.305085)
			(xy 94.636651 -273.287084) (xy 94.752557 -273.277055) (xy 94.868879 -273.275047) (xy 94.985062 -273.281069)
			(xy 95.100553 -273.295092) (xy 95.214801 -273.31705) (xy 95.327262 -273.346837) (xy 95.4374 -273.384312)
			(xy 95.54469 -273.429297) (xy 95.648621 -273.481576) (xy 95.748697 -273.540901) (xy 95.844443 -273.606989)
			(xy 95.9354 -273.679525) (xy 96.021136 -273.758164) (xy 96.101243 -273.84253) (xy 96.175339 -273.932222)
			(xy 96.243069 -274.026812) (xy 96.304113 -274.12585) (xy 96.358178 -274.228863) (xy 96.405008 -274.33536)
			(xy 96.444379 -274.444835) (xy 96.476103 -274.556765) (xy 96.500029 -274.670617) (xy 96.516043 -274.785849)
			(xy 96.52407 -274.901911) (xy 96.524572 -274.96008) (xy 96.52407 -275.018249) (xy 96.516043 -275.134311)
			(xy 96.500029 -275.249543) (xy 96.476103 -275.363395) (xy 96.444379 -275.475325) (xy 96.405008 -275.5848)
			(xy 96.358178 -275.691297) (xy 96.304113 -275.79431) (xy 96.243069 -275.893348) (xy 96.175339 -275.987938)
			(xy 96.101243 -276.07763) (xy 96.021136 -276.161996) (xy 95.9354 -276.240635) (xy 95.844443 -276.313171)
			(xy 95.748697 -276.379259) (xy 95.648621 -276.438584) (xy 95.54469 -276.490863) (xy 95.4374 -276.535848)
			(xy 95.327262 -276.573323) (xy 95.214801 -276.60311) (xy 95.100553 -276.625068) (xy 94.985062 -276.639091)
			(xy 94.868879 -276.645113) (xy 94.752557 -276.643105) (xy 94.636651 -276.633076) (xy 94.521714 -276.615075)
			(xy 94.408291 -276.589187) (xy 94.296926 -276.555536) (xy 94.188147 -276.514282) (xy 94.082473 -276.465621)
			(xy 93.980409 -276.409785) (xy 93.88244 -276.347042) (xy 93.789033 -276.277688) (xy 93.700633 -276.202056)
			(xy 93.617662 -276.120505) (xy 93.540515 -276.033424) (xy 93.46956 -275.941228) (xy 93.405134 -275.844356)
			(xy 93.347545 -275.743271) (xy 93.297068 -275.638453) (xy 93.253942 -275.530402) (xy 93.218373 -275.419634)
			(xy 93.190531 -275.306675) (xy 93.170549 -275.192065) (xy 93.158522 -275.07635) (xy 93.154506 -274.96008)
			(xy 92.307664 -274.96008) (xy 92.307664 -275.66112) (xy 89.932256 -278.036528) (xy 85.01126 -278.036528)
			(xy 84.20862 -277.233888) (xy 84.107528 -277.13305) (xy 83.851496 -276.877018) (xy 83.851496 -272.469356)
			(xy 79.790544 -268.408404) (xy 22.315932 -268.408404) (xy 21.397468 -269.326868) (xy 21.388578 -269.358364)
			(xy 21.380498 -269.384733) (xy 21.357799 -269.434996) (xy 21.328101 -269.481468) (xy 21.292022 -269.52318)
			(xy 21.250315 -269.559265) (xy 21.203848 -269.58897) (xy 21.153589 -269.611677) (xy 21.127212 -269.61973)
			(xy 21.095716 -269.62862) (xy 20.890969 -269.83336) (xy 29.519874 -269.83336) (xy 29.519874 -269.74646)
			(xy 29.527892 -269.659931) (xy 29.54386 -269.574511) (xy 29.567641 -269.490929) (xy 29.599033 -269.409897)
			(xy 29.637767 -269.332108) (xy 29.683514 -269.258224) (xy 29.735883 -269.188877) (xy 29.794427 -269.124657)
			(xy 29.858647 -269.066113) (xy 29.927994 -269.013744) (xy 30.001878 -268.967997) (xy 30.079667 -268.929263)
			(xy 30.160699 -268.897871) (xy 30.244281 -268.87409) (xy 30.329701 -268.858122) (xy 30.41623 -268.850104)
			(xy 30.50313 -268.850104) (xy 30.589659 -268.858122) (xy 30.675079 -268.87409) (xy 30.758661 -268.897871)
			(xy 30.839693 -268.929263) (xy 30.917482 -268.967997) (xy 30.991366 -269.013744) (xy 31.060713 -269.066113)
			(xy 31.124933 -269.124657) (xy 31.183477 -269.188877) (xy 31.235846 -269.258224) (xy 31.281593 -269.332108)
			(xy 31.320327 -269.409897) (xy 31.351719 -269.490929) (xy 31.3755 -269.574511) (xy 31.391468 -269.659931)
			(xy 31.399486 -269.74646) (xy 31.399988 -269.78991) (xy 31.399486 -269.83336) (xy 34.599874 -269.83336)
			(xy 34.599874 -269.74646) (xy 34.607892 -269.659931) (xy 34.62386 -269.574511) (xy 34.647641 -269.490929)
			(xy 34.679033 -269.409897) (xy 34.717767 -269.332108) (xy 34.763514 -269.258224) (xy 34.815883 -269.188877)
			(xy 34.874427 -269.124657) (xy 34.938647 -269.066113) (xy 35.007994 -269.013744) (xy 35.081878 -268.967997)
			(xy 35.159667 -268.929263) (xy 35.240699 -268.897871) (xy 35.324281 -268.87409) (xy 35.409701 -268.858122)
			(xy 35.49623 -268.850104) (xy 35.58313 -268.850104) (xy 35.669659 -268.858122) (xy 35.755079 -268.87409)
			(xy 35.838661 -268.897871) (xy 35.919693 -268.929263) (xy 35.997482 -268.967997) (xy 36.071366 -269.013744)
			(xy 36.140713 -269.066113) (xy 36.204933 -269.124657) (xy 36.263477 -269.188877) (xy 36.315846 -269.258224)
			(xy 36.361593 -269.332108) (xy 36.400327 -269.409897) (xy 36.431719 -269.490929) (xy 36.4555 -269.574511)
			(xy 36.471468 -269.659931) (xy 36.479486 -269.74646) (xy 36.479988 -269.78991) (xy 36.479486 -269.83336)
			(xy 36.471468 -269.919889) (xy 36.4555 -270.005309) (xy 36.431719 -270.088891) (xy 36.400327 -270.169923)
			(xy 36.361593 -270.247712) (xy 36.315846 -270.321596) (xy 36.263477 -270.390943) (xy 36.204933 -270.455163)
			(xy 36.140713 -270.513707) (xy 36.071366 -270.566076) (xy 35.997482 -270.611823) (xy 35.919693 -270.650557)
			(xy 35.838661 -270.681949) (xy 35.755079 -270.70573) (xy 35.669659 -270.721698) (xy 35.58313 -270.729716)
			(xy 35.49623 -270.729716) (xy 35.409701 -270.721698) (xy 35.324281 -270.70573) (xy 35.240699 -270.681949)
			(xy 35.159667 -270.650557) (xy 35.081878 -270.611823) (xy 35.007994 -270.566076) (xy 34.938647 -270.513707)
			(xy 34.874427 -270.455163) (xy 34.815883 -270.390943) (xy 34.763514 -270.321596) (xy 34.717767 -270.247712)
			(xy 34.679033 -270.169923) (xy 34.647641 -270.088891) (xy 34.62386 -270.005309) (xy 34.607892 -269.919889)
			(xy 34.599874 -269.83336) (xy 31.399486 -269.83336) (xy 31.391468 -269.919889) (xy 31.3755 -270.005309)
			(xy 31.351719 -270.088891) (xy 31.320327 -270.169923) (xy 31.281593 -270.247712) (xy 31.235846 -270.321596)
			(xy 31.183477 -270.390943) (xy 31.124933 -270.455163) (xy 31.060713 -270.513707) (xy 30.991366 -270.566076)
			(xy 30.917482 -270.611823) (xy 30.839693 -270.650557) (xy 30.758661 -270.681949) (xy 30.675079 -270.70573)
			(xy 30.589659 -270.721698) (xy 30.50313 -270.729716) (xy 30.41623 -270.729716) (xy 30.329701 -270.721698)
			(xy 30.244281 -270.70573) (xy 30.160699 -270.681949) (xy 30.079667 -270.650557) (xy 30.001878 -270.611823)
			(xy 29.927994 -270.566076) (xy 29.858647 -270.513707) (xy 29.794427 -270.455163) (xy 29.735883 -270.390943)
			(xy 29.683514 -270.321596) (xy 29.637767 -270.247712) (xy 29.599033 -270.169923) (xy 29.567641 -270.088891)
			(xy 29.54386 -270.005309) (xy 29.527892 -269.919889) (xy 29.519874 -269.83336) (xy 20.890969 -269.83336)
			(xy 19.575476 -271.14881) (xy 24.231598 -271.14881) (xy 24.235669 -271.093188) (xy 24.247795 -271.038751)
			(xy 24.267718 -270.98666) (xy 24.295014 -270.938025) (xy 24.3291 -270.893882) (xy 24.369249 -270.855173)
			(xy 24.414607 -270.822722) (xy 24.464207 -270.797221) (xy 24.516991 -270.779214) (xy 24.571834 -270.769084)
			(xy 24.627568 -270.767047) (xy 24.683005 -270.773147) (xy 24.736962 -270.787253) (xy 24.788291 -270.809065)
			(xy 24.835897 -270.838119) (xy 24.878765 -270.873794) (xy 24.915982 -270.915331) (xy 24.946755 -270.961844)
			(xy 24.970427 -271.012341) (xy 24.986495 -271.065748) (xy 24.994615 -271.120924) (xy 24.995124 -271.14881)
			(xy 24.994615 -271.176696) (xy 24.986495 -271.231872) (xy 24.970427 -271.285279) (xy 24.946755 -271.335776)
			(xy 24.915982 -271.382289) (xy 24.878765 -271.423826) (xy 24.835897 -271.459501) (xy 24.788291 -271.488555)
			(xy 24.736962 -271.510367) (xy 24.683005 -271.524473) (xy 24.627568 -271.530573) (xy 24.571834 -271.528536)
			(xy 24.516991 -271.518406) (xy 24.464207 -271.500399) (xy 24.414607 -271.474898) (xy 24.369249 -271.442447)
			(xy 24.3291 -271.403738) (xy 24.295014 -271.359595) (xy 24.267718 -271.31096) (xy 24.247795 -271.258869)
			(xy 24.235669 -271.204432) (xy 24.231598 -271.14881) (xy 19.575476 -271.14881) (xy 18.378842 -272.345404)
			(xy 24.198578 -272.345404) (xy 24.202649 -272.289782) (xy 24.214775 -272.235345) (xy 24.234698 -272.183254)
			(xy 24.261994 -272.134619) (xy 24.29608 -272.090476) (xy 24.336229 -272.051767) (xy 24.381587 -272.019316)
			(xy 24.431187 -271.993815) (xy 24.483971 -271.975808) (xy 24.538814 -271.965678) (xy 24.594548 -271.963641)
			(xy 24.649985 -271.969741) (xy 24.703942 -271.983847) (xy 24.755271 -272.005659) (xy 24.802877 -272.034713)
			(xy 24.845745 -272.070388) (xy 24.882962 -272.111925) (xy 24.913735 -272.158438) (xy 24.937407 -272.208935)
			(xy 24.953475 -272.262342) (xy 24.961595 -272.317518) (xy 24.962021 -272.340832) (xy 26.850592 -272.340832)
			(xy 26.854663 -272.28521) (xy 26.866789 -272.230773) (xy 26.886712 -272.178682) (xy 26.914008 -272.130047)
			(xy 26.948094 -272.085904) (xy 26.988243 -272.047195) (xy 27.033601 -272.014744) (xy 27.083201 -271.989243)
			(xy 27.135985 -271.971236) (xy 27.190828 -271.961106) (xy 27.246562 -271.959069) (xy 27.301999 -271.965169)
			(xy 27.355956 -271.979275) (xy 27.407285 -272.001087) (xy 27.454891 -272.030141) (xy 27.497759 -272.065816)
			(xy 27.534976 -272.107353) (xy 27.565749 -272.153866) (xy 27.589421 -272.204363) (xy 27.605489 -272.25777)
			(xy 27.613609 -272.312946) (xy 27.614118 -272.340832) (xy 27.613609 -272.368718) (xy 27.612926 -272.37336)
			(xy 29.519874 -272.37336) (xy 29.519874 -272.28646) (xy 29.527892 -272.199931) (xy 29.54386 -272.114511)
			(xy 29.567641 -272.030929) (xy 29.599033 -271.949897) (xy 29.637767 -271.872108) (xy 29.683514 -271.798224)
			(xy 29.735883 -271.728877) (xy 29.794427 -271.664657) (xy 29.858647 -271.606113) (xy 29.927994 -271.553744)
			(xy 30.001878 -271.507997) (xy 30.079667 -271.469263) (xy 30.160699 -271.437871) (xy 30.244281 -271.41409)
			(xy 30.329701 -271.398122) (xy 30.41623 -271.390104) (xy 30.50313 -271.390104) (xy 30.589659 -271.398122)
			(xy 30.675079 -271.41409) (xy 30.758661 -271.437871) (xy 30.839693 -271.469263) (xy 30.917482 -271.507997)
			(xy 30.991366 -271.553744) (xy 31.060713 -271.606113) (xy 31.124933 -271.664657) (xy 31.183477 -271.728877)
			(xy 31.235846 -271.798224) (xy 31.281593 -271.872108) (xy 31.320327 -271.949897) (xy 31.351719 -272.030929)
			(xy 31.3755 -272.114511) (xy 31.391468 -272.199931) (xy 31.399486 -272.28646) (xy 31.399988 -272.32991)
			(xy 31.399486 -272.37336) (xy 34.599874 -272.37336) (xy 34.599874 -272.28646) (xy 34.607892 -272.199931)
			(xy 34.62386 -272.114511) (xy 34.647641 -272.030929) (xy 34.679033 -271.949897) (xy 34.717767 -271.872108)
			(xy 34.763514 -271.798224) (xy 34.815883 -271.728877) (xy 34.874427 -271.664657) (xy 34.938647 -271.606113)
			(xy 35.007994 -271.553744) (xy 35.081878 -271.507997) (xy 35.159667 -271.469263) (xy 35.240699 -271.437871)
			(xy 35.324281 -271.41409) (xy 35.409701 -271.398122) (xy 35.49623 -271.390104) (xy 35.58313 -271.390104)
			(xy 35.669659 -271.398122) (xy 35.755079 -271.41409) (xy 35.838661 -271.437871) (xy 35.919693 -271.469263)
			(xy 35.997482 -271.507997) (xy 36.071366 -271.553744) (xy 36.140713 -271.606113) (xy 36.204933 -271.664657)
			(xy 36.263477 -271.728877) (xy 36.315846 -271.798224) (xy 36.361593 -271.872108) (xy 36.400327 -271.949897)
			(xy 36.431719 -272.030929) (xy 36.4555 -272.114511) (xy 36.471468 -272.199931) (xy 36.479486 -272.28646)
			(xy 36.479988 -272.32991) (xy 36.479486 -272.37336) (xy 36.471468 -272.459889) (xy 36.4555 -272.545309)
			(xy 36.431719 -272.628891) (xy 36.400327 -272.709923) (xy 36.361593 -272.787712) (xy 36.315846 -272.861596)
			(xy 36.263477 -272.930943) (xy 36.204933 -272.995163) (xy 36.140713 -273.053707) (xy 36.071366 -273.106076)
			(xy 35.997482 -273.151823) (xy 35.919693 -273.190557) (xy 35.838661 -273.221949) (xy 35.755079 -273.24573)
			(xy 35.669659 -273.261698) (xy 35.58313 -273.269716) (xy 35.49623 -273.269716) (xy 35.409701 -273.261698)
			(xy 35.324281 -273.24573) (xy 35.240699 -273.221949) (xy 35.159667 -273.190557) (xy 35.081878 -273.151823)
			(xy 35.007994 -273.106076) (xy 34.938647 -273.053707) (xy 34.874427 -272.995163) (xy 34.815883 -272.930943)
			(xy 34.763514 -272.861596) (xy 34.717767 -272.787712) (xy 34.679033 -272.709923) (xy 34.647641 -272.628891)
			(xy 34.62386 -272.545309) (xy 34.607892 -272.459889) (xy 34.599874 -272.37336) (xy 31.399486 -272.37336)
			(xy 31.391468 -272.459889) (xy 31.3755 -272.545309) (xy 31.351719 -272.628891) (xy 31.320327 -272.709923)
			(xy 31.281593 -272.787712) (xy 31.235846 -272.861596) (xy 31.183477 -272.930943) (xy 31.124933 -272.995163)
			(xy 31.060713 -273.053707) (xy 30.991366 -273.106076) (xy 30.917482 -273.151823) (xy 30.839693 -273.190557)
			(xy 30.758661 -273.221949) (xy 30.675079 -273.24573) (xy 30.589659 -273.261698) (xy 30.50313 -273.269716)
			(xy 30.41623 -273.269716) (xy 30.329701 -273.261698) (xy 30.244281 -273.24573) (xy 30.160699 -273.221949)
			(xy 30.079667 -273.190557) (xy 30.001878 -273.151823) (xy 29.927994 -273.106076) (xy 29.858647 -273.053707)
			(xy 29.794427 -272.995163) (xy 29.735883 -272.930943) (xy 29.683514 -272.861596) (xy 29.637767 -272.787712)
			(xy 29.599033 -272.709923) (xy 29.567641 -272.628891) (xy 29.54386 -272.545309) (xy 29.527892 -272.459889)
			(xy 29.519874 -272.37336) (xy 27.612926 -272.37336) (xy 27.605489 -272.423894) (xy 27.589421 -272.477301)
			(xy 27.565749 -272.527798) (xy 27.534976 -272.574311) (xy 27.497759 -272.615848) (xy 27.454891 -272.651523)
			(xy 27.407285 -272.680577) (xy 27.355956 -272.702389) (xy 27.301999 -272.716495) (xy 27.246562 -272.722595)
			(xy 27.190828 -272.720558) (xy 27.135985 -272.710428) (xy 27.083201 -272.692421) (xy 27.033601 -272.66692)
			(xy 26.988243 -272.634469) (xy 26.948094 -272.59576) (xy 26.914008 -272.551617) (xy 26.886712 -272.502982)
			(xy 26.866789 -272.450891) (xy 26.854663 -272.396454) (xy 26.850592 -272.340832) (xy 24.962021 -272.340832)
			(xy 24.962104 -272.345404) (xy 24.961595 -272.37329) (xy 24.953475 -272.428466) (xy 24.937407 -272.481873)
			(xy 24.913735 -272.53237) (xy 24.882962 -272.578883) (xy 24.845745 -272.62042) (xy 24.802877 -272.656095)
			(xy 24.755271 -272.685149) (xy 24.703942 -272.706961) (xy 24.649985 -272.721067) (xy 24.594548 -272.727167)
			(xy 24.538814 -272.72513) (xy 24.483971 -272.715) (xy 24.431187 -272.696993) (xy 24.381587 -272.671492)
			(xy 24.336229 -272.639041) (xy 24.29608 -272.600332) (xy 24.261994 -272.556189) (xy 24.234698 -272.507554)
			(xy 24.214775 -272.455463) (xy 24.202649 -272.401026) (xy 24.198578 -272.345404) (xy 18.378842 -272.345404)
			(xy 17.114134 -273.61007) (xy 39.818564 -273.61007) (xy 39.819058 -273.552661) (xy 39.826902 -273.438113)
			(xy 39.842544 -273.324366) (xy 39.865911 -273.211952) (xy 39.896896 -273.101394) (xy 39.935352 -272.993209)
			(xy 39.981101 -272.8879) (xy 40.03393 -272.785958) (xy 40.093592 -272.687859) (xy 40.159809 -272.59406)
			(xy 40.232272 -272.504998) (xy 40.310645 -272.421089) (xy 40.39456 -272.342723) (xy 40.483627 -272.270266)
			(xy 40.577431 -272.204056) (xy 40.675535 -272.144402) (xy 40.777481 -272.091581) (xy 40.882793 -272.045839)
			(xy 40.990981 -272.007391) (xy 41.101541 -271.976415) (xy 41.213957 -271.953056) (xy 41.327705 -271.937423)
			(xy 41.442254 -271.929588) (xy 41.557072 -271.929588) (xy 41.671621 -271.937423) (xy 41.785369 -271.953056)
			(xy 41.897785 -271.976415) (xy 42.008345 -272.007391) (xy 42.116533 -272.045839) (xy 42.221845 -272.091581)
			(xy 42.323791 -272.144402) (xy 42.421895 -272.204056) (xy 42.501239 -272.26006) (xy 43.327577 -272.26006)
			(xy 43.331612 -272.184356) (xy 43.343671 -272.109511) (xy 43.363617 -272.03637) (xy 43.391224 -271.965765)
			(xy 43.42618 -271.898494) (xy 43.468088 -271.835319) (xy 43.516474 -271.776957) (xy 43.57079 -271.724069)
			(xy 43.630419 -271.677254) (xy 43.694687 -271.637042) (xy 43.762864 -271.60389) (xy 43.83418 -271.578172)
			(xy 43.907825 -271.56018) (xy 43.982965 -271.550118) (xy 44.058749 -271.548099) (xy 44.134319 -271.554148)
			(xy 44.208817 -271.568195) (xy 44.2814 -271.590081) (xy 44.351246 -271.619558) (xy 44.417563 -271.656293)
			(xy 44.479599 -271.699868) (xy 44.536652 -271.74979) (xy 44.588076 -271.805494) (xy 44.633287 -271.866349)
			(xy 44.671774 -271.931664) (xy 44.7031 -272.0007) (xy 44.72691 -272.072675) (xy 44.742935 -272.146773)
			(xy 44.750994 -272.222154) (xy 44.751498 -272.26006) (xy 45.867577 -272.26006) (xy 45.871612 -272.184356)
			(xy 45.883671 -272.109511) (xy 45.903617 -272.03637) (xy 45.931224 -271.965765) (xy 45.96618 -271.898494)
			(xy 46.008088 -271.835319) (xy 46.056474 -271.776957) (xy 46.11079 -271.724069) (xy 46.170419 -271.677254)
			(xy 46.234687 -271.637042) (xy 46.302864 -271.60389) (xy 46.37418 -271.578172) (xy 46.447825 -271.56018)
			(xy 46.522965 -271.550118) (xy 46.598749 -271.548099) (xy 46.674319 -271.554148) (xy 46.748817 -271.568195)
			(xy 46.8214 -271.590081) (xy 46.891246 -271.619558) (xy 46.957563 -271.656293) (xy 47.019599 -271.699868)
			(xy 47.076652 -271.74979) (xy 47.128076 -271.805494) (xy 47.173287 -271.866349) (xy 47.211774 -271.931664)
			(xy 47.2431 -272.0007) (xy 47.26691 -272.072675) (xy 47.282935 -272.146773) (xy 47.290994 -272.222154)
			(xy 47.291498 -272.26006) (xy 48.407577 -272.26006) (xy 48.411612 -272.184356) (xy 48.423671 -272.109511)
			(xy 48.443617 -272.03637) (xy 48.471224 -271.965765) (xy 48.50618 -271.898494) (xy 48.548088 -271.835319)
			(xy 48.596474 -271.776957) (xy 48.65079 -271.724069) (xy 48.710419 -271.677254) (xy 48.774687 -271.637042)
			(xy 48.842864 -271.60389) (xy 48.91418 -271.578172) (xy 48.987825 -271.56018) (xy 49.062965 -271.550118)
			(xy 49.138749 -271.548099) (xy 49.214319 -271.554148) (xy 49.288817 -271.568195) (xy 49.3614 -271.590081)
			(xy 49.431246 -271.619558) (xy 49.497563 -271.656293) (xy 49.559599 -271.699868) (xy 49.616652 -271.74979)
			(xy 49.668076 -271.805494) (xy 49.713287 -271.866349) (xy 49.751774 -271.931664) (xy 49.7831 -272.0007)
			(xy 49.80691 -272.072675) (xy 49.822935 -272.146773) (xy 49.830994 -272.222154) (xy 49.831498 -272.26006)
			(xy 50.947577 -272.26006) (xy 50.951612 -272.184356) (xy 50.963671 -272.109511) (xy 50.983617 -272.03637)
			(xy 51.011224 -271.965765) (xy 51.04618 -271.898494) (xy 51.088088 -271.835319) (xy 51.136474 -271.776957)
			(xy 51.19079 -271.724069) (xy 51.250419 -271.677254) (xy 51.314687 -271.637042) (xy 51.382864 -271.60389)
			(xy 51.45418 -271.578172) (xy 51.527825 -271.56018) (xy 51.602965 -271.550118) (xy 51.678749 -271.548099)
			(xy 51.754319 -271.554148) (xy 51.828817 -271.568195) (xy 51.9014 -271.590081) (xy 51.971246 -271.619558)
			(xy 52.037563 -271.656293) (xy 52.099599 -271.699868) (xy 52.156652 -271.74979) (xy 52.208076 -271.805494)
			(xy 52.253287 -271.866349) (xy 52.291774 -271.931664) (xy 52.3231 -272.0007) (xy 52.34691 -272.072675)
			(xy 52.362935 -272.146773) (xy 52.370994 -272.222154) (xy 52.371498 -272.26006) (xy 53.487577 -272.26006)
			(xy 53.491612 -272.184356) (xy 53.503671 -272.109511) (xy 53.523617 -272.03637) (xy 53.551224 -271.965765)
			(xy 53.58618 -271.898494) (xy 53.628088 -271.835319) (xy 53.676474 -271.776957) (xy 53.73079 -271.724069)
			(xy 53.790419 -271.677254) (xy 53.854687 -271.637042) (xy 53.922864 -271.60389) (xy 53.99418 -271.578172)
			(xy 54.067825 -271.56018) (xy 54.142965 -271.550118) (xy 54.218749 -271.548099) (xy 54.294319 -271.554148)
			(xy 54.368817 -271.568195) (xy 54.4414 -271.590081) (xy 54.511246 -271.619558) (xy 54.577563 -271.656293)
			(xy 54.639599 -271.699868) (xy 54.696652 -271.74979) (xy 54.748076 -271.805494) (xy 54.793287 -271.866349)
			(xy 54.831774 -271.931664) (xy 54.8631 -272.0007) (xy 54.88691 -272.072675) (xy 54.902935 -272.146773)
			(xy 54.910994 -272.222154) (xy 54.911498 -272.26006) (xy 56.027577 -272.26006) (xy 56.031612 -272.184356)
			(xy 56.043671 -272.109511) (xy 56.063617 -272.03637) (xy 56.091224 -271.965765) (xy 56.12618 -271.898494)
			(xy 56.168088 -271.835319) (xy 56.216474 -271.776957) (xy 56.27079 -271.724069) (xy 56.330419 -271.677254)
			(xy 56.394687 -271.637042) (xy 56.462864 -271.60389) (xy 56.53418 -271.578172) (xy 56.607825 -271.56018)
			(xy 56.682965 -271.550118) (xy 56.758749 -271.548099) (xy 56.834319 -271.554148) (xy 56.908817 -271.568195)
			(xy 56.9814 -271.590081) (xy 57.051246 -271.619558) (xy 57.117563 -271.656293) (xy 57.179599 -271.699868)
			(xy 57.236652 -271.74979) (xy 57.288076 -271.805494) (xy 57.333287 -271.866349) (xy 57.371774 -271.931664)
			(xy 57.4031 -272.0007) (xy 57.42691 -272.072675) (xy 57.442935 -272.146773) (xy 57.450994 -272.222154)
			(xy 57.451498 -272.26006) (xy 58.567577 -272.26006) (xy 58.571612 -272.184356) (xy 58.583671 -272.109511)
			(xy 58.603617 -272.03637) (xy 58.631224 -271.965765) (xy 58.66618 -271.898494) (xy 58.708088 -271.835319)
			(xy 58.756474 -271.776957) (xy 58.81079 -271.724069) (xy 58.870419 -271.677254) (xy 58.934687 -271.637042)
			(xy 59.002864 -271.60389) (xy 59.07418 -271.578172) (xy 59.147825 -271.56018) (xy 59.222965 -271.550118)
			(xy 59.298749 -271.548099) (xy 59.374319 -271.554148) (xy 59.448817 -271.568195) (xy 59.5214 -271.590081)
			(xy 59.591246 -271.619558) (xy 59.657563 -271.656293) (xy 59.719599 -271.699868) (xy 59.776652 -271.74979)
			(xy 59.828076 -271.805494) (xy 59.873287 -271.866349) (xy 59.911774 -271.931664) (xy 59.9431 -272.0007)
			(xy 59.96691 -272.072675) (xy 59.982935 -272.146773) (xy 59.990994 -272.222154) (xy 59.991498 -272.26006)
			(xy 61.107577 -272.26006) (xy 61.111612 -272.184356) (xy 61.123671 -272.109511) (xy 61.143617 -272.03637)
			(xy 61.171224 -271.965765) (xy 61.20618 -271.898494) (xy 61.248088 -271.835319) (xy 61.296474 -271.776957)
			(xy 61.35079 -271.724069) (xy 61.410419 -271.677254) (xy 61.474687 -271.637042) (xy 61.542864 -271.60389)
			(xy 61.61418 -271.578172) (xy 61.687825 -271.56018) (xy 61.762965 -271.550118) (xy 61.838749 -271.548099)
			(xy 61.914319 -271.554148) (xy 61.988817 -271.568195) (xy 62.0614 -271.590081) (xy 62.131246 -271.619558)
			(xy 62.197563 -271.656293) (xy 62.259599 -271.699868) (xy 62.316652 -271.74979) (xy 62.368076 -271.805494)
			(xy 62.413287 -271.866349) (xy 62.451774 -271.931664) (xy 62.4831 -272.0007) (xy 62.50691 -272.072675)
			(xy 62.522935 -272.146773) (xy 62.530994 -272.222154) (xy 62.531498 -272.26006) (xy 62.530994 -272.297966)
			(xy 62.522935 -272.373347) (xy 62.50691 -272.447445) (xy 62.4831 -272.51942) (xy 62.451774 -272.588456)
			(xy 62.413287 -272.653771) (xy 62.368076 -272.714626) (xy 62.316652 -272.77033) (xy 62.259599 -272.820252)
			(xy 62.197563 -272.863827) (xy 62.131246 -272.900562) (xy 62.0614 -272.930039) (xy 61.988817 -272.951925)
			(xy 61.914319 -272.965972) (xy 61.838749 -272.972021) (xy 61.762965 -272.970002) (xy 61.687825 -272.95994)
			(xy 61.61418 -272.941948) (xy 61.542864 -272.91623) (xy 61.474687 -272.883078) (xy 61.410419 -272.842866)
			(xy 61.35079 -272.796051) (xy 61.296474 -272.743163) (xy 61.248088 -272.684801) (xy 61.20618 -272.621626)
			(xy 61.171224 -272.554355) (xy 61.143617 -272.48375) (xy 61.123671 -272.410609) (xy 61.111612 -272.335764)
			(xy 61.107577 -272.26006) (xy 59.991498 -272.26006) (xy 59.990994 -272.297966) (xy 59.982935 -272.373347)
			(xy 59.96691 -272.447445) (xy 59.9431 -272.51942) (xy 59.911774 -272.588456) (xy 59.873287 -272.653771)
			(xy 59.828076 -272.714626) (xy 59.776652 -272.77033) (xy 59.719599 -272.820252) (xy 59.657563 -272.863827)
			(xy 59.591246 -272.900562) (xy 59.5214 -272.930039) (xy 59.448817 -272.951925) (xy 59.374319 -272.965972)
			(xy 59.298749 -272.972021) (xy 59.222965 -272.970002) (xy 59.147825 -272.95994) (xy 59.07418 -272.941948)
			(xy 59.002864 -272.91623) (xy 58.934687 -272.883078) (xy 58.870419 -272.842866) (xy 58.81079 -272.796051)
			(xy 58.756474 -272.743163) (xy 58.708088 -272.684801) (xy 58.66618 -272.621626) (xy 58.631224 -272.554355)
			(xy 58.603617 -272.48375) (xy 58.583671 -272.410609) (xy 58.571612 -272.335764) (xy 58.567577 -272.26006)
			(xy 57.451498 -272.26006) (xy 57.450994 -272.297966) (xy 57.442935 -272.373347) (xy 57.42691 -272.447445)
			(xy 57.4031 -272.51942) (xy 57.371774 -272.588456) (xy 57.333287 -272.653771) (xy 57.288076 -272.714626)
			(xy 57.236652 -272.77033) (xy 57.179599 -272.820252) (xy 57.117563 -272.863827) (xy 57.051246 -272.900562)
			(xy 56.9814 -272.930039) (xy 56.908817 -272.951925) (xy 56.834319 -272.965972) (xy 56.758749 -272.972021)
			(xy 56.682965 -272.970002) (xy 56.607825 -272.95994) (xy 56.53418 -272.941948) (xy 56.462864 -272.91623)
			(xy 56.394687 -272.883078) (xy 56.330419 -272.842866) (xy 56.27079 -272.796051) (xy 56.216474 -272.743163)
			(xy 56.168088 -272.684801) (xy 56.12618 -272.621626) (xy 56.091224 -272.554355) (xy 56.063617 -272.48375)
			(xy 56.043671 -272.410609) (xy 56.031612 -272.335764) (xy 56.027577 -272.26006) (xy 54.911498 -272.26006)
			(xy 54.910994 -272.297966) (xy 54.902935 -272.373347) (xy 54.88691 -272.447445) (xy 54.8631 -272.51942)
			(xy 54.831774 -272.588456) (xy 54.793287 -272.653771) (xy 54.748076 -272.714626) (xy 54.696652 -272.77033)
			(xy 54.639599 -272.820252) (xy 54.577563 -272.863827) (xy 54.511246 -272.900562) (xy 54.4414 -272.930039)
			(xy 54.368817 -272.951925) (xy 54.294319 -272.965972) (xy 54.218749 -272.972021) (xy 54.142965 -272.970002)
			(xy 54.067825 -272.95994) (xy 53.99418 -272.941948) (xy 53.922864 -272.91623) (xy 53.854687 -272.883078)
			(xy 53.790419 -272.842866) (xy 53.73079 -272.796051) (xy 53.676474 -272.743163) (xy 53.628088 -272.684801)
			(xy 53.58618 -272.621626) (xy 53.551224 -272.554355) (xy 53.523617 -272.48375) (xy 53.503671 -272.410609)
			(xy 53.491612 -272.335764) (xy 53.487577 -272.26006) (xy 52.371498 -272.26006) (xy 52.370994 -272.297966)
			(xy 52.362935 -272.373347) (xy 52.34691 -272.447445) (xy 52.3231 -272.51942) (xy 52.291774 -272.588456)
			(xy 52.253287 -272.653771) (xy 52.208076 -272.714626) (xy 52.156652 -272.77033) (xy 52.099599 -272.820252)
			(xy 52.037563 -272.863827) (xy 51.971246 -272.900562) (xy 51.9014 -272.930039) (xy 51.828817 -272.951925)
			(xy 51.754319 -272.965972) (xy 51.678749 -272.972021) (xy 51.602965 -272.970002) (xy 51.527825 -272.95994)
			(xy 51.45418 -272.941948) (xy 51.382864 -272.91623) (xy 51.314687 -272.883078) (xy 51.250419 -272.842866)
			(xy 51.19079 -272.796051) (xy 51.136474 -272.743163) (xy 51.088088 -272.684801) (xy 51.04618 -272.621626)
			(xy 51.011224 -272.554355) (xy 50.983617 -272.48375) (xy 50.963671 -272.410609) (xy 50.951612 -272.335764)
			(xy 50.947577 -272.26006) (xy 49.831498 -272.26006) (xy 49.830994 -272.297966) (xy 49.822935 -272.373347)
			(xy 49.80691 -272.447445) (xy 49.7831 -272.51942) (xy 49.751774 -272.588456) (xy 49.713287 -272.653771)
			(xy 49.668076 -272.714626) (xy 49.616652 -272.77033) (xy 49.559599 -272.820252) (xy 49.497563 -272.863827)
			(xy 49.431246 -272.900562) (xy 49.3614 -272.930039) (xy 49.288817 -272.951925) (xy 49.214319 -272.965972)
			(xy 49.138749 -272.972021) (xy 49.062965 -272.970002) (xy 48.987825 -272.95994) (xy 48.91418 -272.941948)
			(xy 48.842864 -272.91623) (xy 48.774687 -272.883078) (xy 48.710419 -272.842866) (xy 48.65079 -272.796051)
			(xy 48.596474 -272.743163) (xy 48.548088 -272.684801) (xy 48.50618 -272.621626) (xy 48.471224 -272.554355)
			(xy 48.443617 -272.48375) (xy 48.423671 -272.410609) (xy 48.411612 -272.335764) (xy 48.407577 -272.26006)
			(xy 47.291498 -272.26006) (xy 47.290994 -272.297966) (xy 47.282935 -272.373347) (xy 47.26691 -272.447445)
			(xy 47.2431 -272.51942) (xy 47.211774 -272.588456) (xy 47.173287 -272.653771) (xy 47.128076 -272.714626)
			(xy 47.076652 -272.77033) (xy 47.019599 -272.820252) (xy 46.957563 -272.863827) (xy 46.891246 -272.900562)
			(xy 46.8214 -272.930039) (xy 46.748817 -272.951925) (xy 46.674319 -272.965972) (xy 46.598749 -272.972021)
			(xy 46.522965 -272.970002) (xy 46.447825 -272.95994) (xy 46.37418 -272.941948) (xy 46.302864 -272.91623)
			(xy 46.234687 -272.883078) (xy 46.170419 -272.842866) (xy 46.11079 -272.796051) (xy 46.056474 -272.743163)
			(xy 46.008088 -272.684801) (xy 45.96618 -272.621626) (xy 45.931224 -272.554355) (xy 45.903617 -272.48375)
			(xy 45.883671 -272.410609) (xy 45.871612 -272.335764) (xy 45.867577 -272.26006) (xy 44.751498 -272.26006)
			(xy 44.750994 -272.297966) (xy 44.742935 -272.373347) (xy 44.72691 -272.447445) (xy 44.7031 -272.51942)
			(xy 44.671774 -272.588456) (xy 44.633287 -272.653771) (xy 44.588076 -272.714626) (xy 44.536652 -272.77033)
			(xy 44.479599 -272.820252) (xy 44.417563 -272.863827) (xy 44.351246 -272.900562) (xy 44.2814 -272.930039)
			(xy 44.208817 -272.951925) (xy 44.134319 -272.965972) (xy 44.058749 -272.972021) (xy 43.982965 -272.970002)
			(xy 43.907825 -272.95994) (xy 43.83418 -272.941948) (xy 43.762864 -272.91623) (xy 43.694687 -272.883078)
			(xy 43.630419 -272.842866) (xy 43.57079 -272.796051) (xy 43.516474 -272.743163) (xy 43.468088 -272.684801)
			(xy 43.42618 -272.621626) (xy 43.391224 -272.554355) (xy 43.363617 -272.48375) (xy 43.343671 -272.410609)
			(xy 43.331612 -272.335764) (xy 43.327577 -272.26006) (xy 42.501239 -272.26006) (xy 42.515699 -272.270266)
			(xy 42.604766 -272.342723) (xy 42.688681 -272.421089) (xy 42.767054 -272.504998) (xy 42.839517 -272.59406)
			(xy 42.905734 -272.687859) (xy 42.965396 -272.785958) (xy 43.018225 -272.8879) (xy 43.063974 -272.993209)
			(xy 43.10243 -273.101394) (xy 43.133415 -273.211952) (xy 43.156782 -273.324366) (xy 43.172424 -273.438113)
			(xy 43.180268 -273.552661) (xy 43.180762 -273.61007) (xy 43.180576 -273.643253) (xy 43.177909 -273.709567)
			(xy 43.175428 -273.742658) (xy 43.170272 -273.800942) (xy 43.152948 -273.916671) (xy 43.127616 -274.030914)
			(xy 43.094401 -274.143119) (xy 43.053462 -274.252742) (xy 43.004999 -274.359253) (xy 42.949245 -274.462135)
			(xy 42.886471 -274.560891) (xy 42.816981 -274.655042) (xy 42.741111 -274.744132) (xy 42.659229 -274.827729)
			(xy 42.571732 -274.90543) (xy 42.500813 -274.96008) (xy 43.327577 -274.96008) (xy 43.331612 -274.884376)
			(xy 43.343671 -274.809531) (xy 43.363617 -274.73639) (xy 43.391224 -274.665785) (xy 43.42618 -274.598514)
			(xy 43.468088 -274.535339) (xy 43.516474 -274.476977) (xy 43.57079 -274.424089) (xy 43.630419 -274.377274)
			(xy 43.694687 -274.337062) (xy 43.762864 -274.30391) (xy 43.83418 -274.278192) (xy 43.907825 -274.2602)
			(xy 43.982965 -274.250138) (xy 44.058749 -274.248119) (xy 44.134319 -274.254168) (xy 44.208817 -274.268215)
			(xy 44.2814 -274.290101) (xy 44.351246 -274.319578) (xy 44.417563 -274.356313) (xy 44.479599 -274.399888)
			(xy 44.536652 -274.44981) (xy 44.588076 -274.505514) (xy 44.633287 -274.566369) (xy 44.671774 -274.631684)
			(xy 44.7031 -274.70072) (xy 44.72691 -274.772695) (xy 44.742935 -274.846793) (xy 44.750994 -274.922174)
			(xy 44.751498 -274.96008) (xy 45.867577 -274.96008) (xy 45.871612 -274.884376) (xy 45.883671 -274.809531)
			(xy 45.903617 -274.73639) (xy 45.931224 -274.665785) (xy 45.96618 -274.598514) (xy 46.008088 -274.535339)
			(xy 46.056474 -274.476977) (xy 46.11079 -274.424089) (xy 46.170419 -274.377274) (xy 46.234687 -274.337062)
			(xy 46.302864 -274.30391) (xy 46.37418 -274.278192) (xy 46.447825 -274.2602) (xy 46.522965 -274.250138)
			(xy 46.598749 -274.248119) (xy 46.674319 -274.254168) (xy 46.748817 -274.268215) (xy 46.8214 -274.290101)
			(xy 46.891246 -274.319578) (xy 46.957563 -274.356313) (xy 47.019599 -274.399888) (xy 47.076652 -274.44981)
			(xy 47.128076 -274.505514) (xy 47.173287 -274.566369) (xy 47.211774 -274.631684) (xy 47.2431 -274.70072)
			(xy 47.26691 -274.772695) (xy 47.282935 -274.846793) (xy 47.290994 -274.922174) (xy 47.291498 -274.96008)
			(xy 48.407577 -274.96008) (xy 48.411612 -274.884376) (xy 48.423671 -274.809531) (xy 48.443617 -274.73639)
			(xy 48.471224 -274.665785) (xy 48.50618 -274.598514) (xy 48.548088 -274.535339) (xy 48.596474 -274.476977)
			(xy 48.65079 -274.424089) (xy 48.710419 -274.377274) (xy 48.774687 -274.337062) (xy 48.842864 -274.30391)
			(xy 48.91418 -274.278192) (xy 48.987825 -274.2602) (xy 49.062965 -274.250138) (xy 49.138749 -274.248119)
			(xy 49.214319 -274.254168) (xy 49.288817 -274.268215) (xy 49.3614 -274.290101) (xy 49.431246 -274.319578)
			(xy 49.497563 -274.356313) (xy 49.559599 -274.399888) (xy 49.616652 -274.44981) (xy 49.668076 -274.505514)
			(xy 49.713287 -274.566369) (xy 49.751774 -274.631684) (xy 49.7831 -274.70072) (xy 49.80691 -274.772695)
			(xy 49.822935 -274.846793) (xy 49.830994 -274.922174) (xy 49.831498 -274.96008) (xy 50.947577 -274.96008)
			(xy 50.951612 -274.884376) (xy 50.963671 -274.809531) (xy 50.983617 -274.73639) (xy 51.011224 -274.665785)
			(xy 51.04618 -274.598514) (xy 51.088088 -274.535339) (xy 51.136474 -274.476977) (xy 51.19079 -274.424089)
			(xy 51.250419 -274.377274) (xy 51.314687 -274.337062) (xy 51.382864 -274.30391) (xy 51.45418 -274.278192)
			(xy 51.527825 -274.2602) (xy 51.602965 -274.250138) (xy 51.678749 -274.248119) (xy 51.754319 -274.254168)
			(xy 51.828817 -274.268215) (xy 51.9014 -274.290101) (xy 51.971246 -274.319578) (xy 52.037563 -274.356313)
			(xy 52.099599 -274.399888) (xy 52.156652 -274.44981) (xy 52.208076 -274.505514) (xy 52.253287 -274.566369)
			(xy 52.291774 -274.631684) (xy 52.3231 -274.70072) (xy 52.34691 -274.772695) (xy 52.362935 -274.846793)
			(xy 52.370994 -274.922174) (xy 52.371498 -274.96008) (xy 53.487577 -274.96008) (xy 53.491612 -274.884376)
			(xy 53.503671 -274.809531) (xy 53.523617 -274.73639) (xy 53.551224 -274.665785) (xy 53.58618 -274.598514)
			(xy 53.628088 -274.535339) (xy 53.676474 -274.476977) (xy 53.73079 -274.424089) (xy 53.790419 -274.377274)
			(xy 53.854687 -274.337062) (xy 53.922864 -274.30391) (xy 53.99418 -274.278192) (xy 54.067825 -274.2602)
			(xy 54.142965 -274.250138) (xy 54.218749 -274.248119) (xy 54.294319 -274.254168) (xy 54.368817 -274.268215)
			(xy 54.4414 -274.290101) (xy 54.511246 -274.319578) (xy 54.577563 -274.356313) (xy 54.639599 -274.399888)
			(xy 54.696652 -274.44981) (xy 54.748076 -274.505514) (xy 54.793287 -274.566369) (xy 54.831774 -274.631684)
			(xy 54.8631 -274.70072) (xy 54.88691 -274.772695) (xy 54.902935 -274.846793) (xy 54.910994 -274.922174)
			(xy 54.911498 -274.96008) (xy 56.027577 -274.96008) (xy 56.031612 -274.884376) (xy 56.043671 -274.809531)
			(xy 56.063617 -274.73639) (xy 56.091224 -274.665785) (xy 56.12618 -274.598514) (xy 56.168088 -274.535339)
			(xy 56.216474 -274.476977) (xy 56.27079 -274.424089) (xy 56.330419 -274.377274) (xy 56.394687 -274.337062)
			(xy 56.462864 -274.30391) (xy 56.53418 -274.278192) (xy 56.607825 -274.2602) (xy 56.682965 -274.250138)
			(xy 56.758749 -274.248119) (xy 56.834319 -274.254168) (xy 56.908817 -274.268215) (xy 56.9814 -274.290101)
			(xy 57.051246 -274.319578) (xy 57.117563 -274.356313) (xy 57.179599 -274.399888) (xy 57.236652 -274.44981)
			(xy 57.288076 -274.505514) (xy 57.333287 -274.566369) (xy 57.371774 -274.631684) (xy 57.4031 -274.70072)
			(xy 57.42691 -274.772695) (xy 57.442935 -274.846793) (xy 57.450994 -274.922174) (xy 57.451498 -274.96008)
			(xy 58.567577 -274.96008) (xy 58.571612 -274.884376) (xy 58.583671 -274.809531) (xy 58.603617 -274.73639)
			(xy 58.631224 -274.665785) (xy 58.66618 -274.598514) (xy 58.708088 -274.535339) (xy 58.756474 -274.476977)
			(xy 58.81079 -274.424089) (xy 58.870419 -274.377274) (xy 58.934687 -274.337062) (xy 59.002864 -274.30391)
			(xy 59.07418 -274.278192) (xy 59.147825 -274.2602) (xy 59.222965 -274.250138) (xy 59.298749 -274.248119)
			(xy 59.374319 -274.254168) (xy 59.448817 -274.268215) (xy 59.5214 -274.290101) (xy 59.591246 -274.319578)
			(xy 59.657563 -274.356313) (xy 59.719599 -274.399888) (xy 59.776652 -274.44981) (xy 59.828076 -274.505514)
			(xy 59.873287 -274.566369) (xy 59.911774 -274.631684) (xy 59.9431 -274.70072) (xy 59.96691 -274.772695)
			(xy 59.982935 -274.846793) (xy 59.990994 -274.922174) (xy 59.991498 -274.96008) (xy 61.107577 -274.96008)
			(xy 61.111612 -274.884376) (xy 61.123671 -274.809531) (xy 61.143617 -274.73639) (xy 61.171224 -274.665785)
			(xy 61.20618 -274.598514) (xy 61.248088 -274.535339) (xy 61.296474 -274.476977) (xy 61.35079 -274.424089)
			(xy 61.410419 -274.377274) (xy 61.474687 -274.337062) (xy 61.542864 -274.30391) (xy 61.61418 -274.278192)
			(xy 61.687825 -274.2602) (xy 61.762965 -274.250138) (xy 61.838749 -274.248119) (xy 61.914319 -274.254168)
			(xy 61.988817 -274.268215) (xy 62.0614 -274.290101) (xy 62.131246 -274.319578) (xy 62.197563 -274.356313)
			(xy 62.259599 -274.399888) (xy 62.316652 -274.44981) (xy 62.368076 -274.505514) (xy 62.413287 -274.566369)
			(xy 62.451774 -274.631684) (xy 62.4831 -274.70072) (xy 62.50691 -274.772695) (xy 62.522935 -274.846793)
			(xy 62.530994 -274.922174) (xy 62.531498 -274.96008) (xy 62.530994 -274.997986) (xy 62.522935 -275.073367)
			(xy 62.50691 -275.147465) (xy 62.4831 -275.21944) (xy 62.451774 -275.288476) (xy 62.413287 -275.353791)
			(xy 62.368076 -275.414646) (xy 62.316652 -275.47035) (xy 62.259599 -275.520272) (xy 62.197563 -275.563847)
			(xy 62.131246 -275.600582) (xy 62.0614 -275.630059) (xy 61.988817 -275.651945) (xy 61.914319 -275.665992)
			(xy 61.838749 -275.672041) (xy 61.762965 -275.670022) (xy 61.687825 -275.65996) (xy 61.61418 -275.641968)
			(xy 61.542864 -275.61625) (xy 61.474687 -275.583098) (xy 61.410419 -275.542886) (xy 61.35079 -275.496071)
			(xy 61.296474 -275.443183) (xy 61.248088 -275.384821) (xy 61.20618 -275.321646) (xy 61.171224 -275.254375)
			(xy 61.143617 -275.18377) (xy 61.123671 -275.110629) (xy 61.111612 -275.035784) (xy 61.107577 -274.96008)
			(xy 59.991498 -274.96008) (xy 59.990994 -274.997986) (xy 59.982935 -275.073367) (xy 59.96691 -275.147465)
			(xy 59.9431 -275.21944) (xy 59.911774 -275.288476) (xy 59.873287 -275.353791) (xy 59.828076 -275.414646)
			(xy 59.776652 -275.47035) (xy 59.719599 -275.520272) (xy 59.657563 -275.563847) (xy 59.591246 -275.600582)
			(xy 59.5214 -275.630059) (xy 59.448817 -275.651945) (xy 59.374319 -275.665992) (xy 59.298749 -275.672041)
			(xy 59.222965 -275.670022) (xy 59.147825 -275.65996) (xy 59.07418 -275.641968) (xy 59.002864 -275.61625)
			(xy 58.934687 -275.583098) (xy 58.870419 -275.542886) (xy 58.81079 -275.496071) (xy 58.756474 -275.443183)
			(xy 58.708088 -275.384821) (xy 58.66618 -275.321646) (xy 58.631224 -275.254375) (xy 58.603617 -275.18377)
			(xy 58.583671 -275.110629) (xy 58.571612 -275.035784) (xy 58.567577 -274.96008) (xy 57.451498 -274.96008)
			(xy 57.450994 -274.997986) (xy 57.442935 -275.073367) (xy 57.42691 -275.147465) (xy 57.4031 -275.21944)
			(xy 57.371774 -275.288476) (xy 57.333287 -275.353791) (xy 57.288076 -275.414646) (xy 57.236652 -275.47035)
			(xy 57.179599 -275.520272) (xy 57.117563 -275.563847) (xy 57.051246 -275.600582) (xy 56.9814 -275.630059)
			(xy 56.908817 -275.651945) (xy 56.834319 -275.665992) (xy 56.758749 -275.672041) (xy 56.682965 -275.670022)
			(xy 56.607825 -275.65996) (xy 56.53418 -275.641968) (xy 56.462864 -275.61625) (xy 56.394687 -275.583098)
			(xy 56.330419 -275.542886) (xy 56.27079 -275.496071) (xy 56.216474 -275.443183) (xy 56.168088 -275.384821)
			(xy 56.12618 -275.321646) (xy 56.091224 -275.254375) (xy 56.063617 -275.18377) (xy 56.043671 -275.110629)
			(xy 56.031612 -275.035784) (xy 56.027577 -274.96008) (xy 54.911498 -274.96008) (xy 54.910994 -274.997986)
			(xy 54.902935 -275.073367) (xy 54.88691 -275.147465) (xy 54.8631 -275.21944) (xy 54.831774 -275.288476)
			(xy 54.793287 -275.353791) (xy 54.748076 -275.414646) (xy 54.696652 -275.47035) (xy 54.639599 -275.520272)
			(xy 54.577563 -275.563847) (xy 54.511246 -275.600582) (xy 54.4414 -275.630059) (xy 54.368817 -275.651945)
			(xy 54.294319 -275.665992) (xy 54.218749 -275.672041) (xy 54.142965 -275.670022) (xy 54.067825 -275.65996)
			(xy 53.99418 -275.641968) (xy 53.922864 -275.61625) (xy 53.854687 -275.583098) (xy 53.790419 -275.542886)
			(xy 53.73079 -275.496071) (xy 53.676474 -275.443183) (xy 53.628088 -275.384821) (xy 53.58618 -275.321646)
			(xy 53.551224 -275.254375) (xy 53.523617 -275.18377) (xy 53.503671 -275.110629) (xy 53.491612 -275.035784)
			(xy 53.487577 -274.96008) (xy 52.371498 -274.96008) (xy 52.370994 -274.997986) (xy 52.362935 -275.073367)
			(xy 52.34691 -275.147465) (xy 52.3231 -275.21944) (xy 52.291774 -275.288476) (xy 52.253287 -275.353791)
			(xy 52.208076 -275.414646) (xy 52.156652 -275.47035) (xy 52.099599 -275.520272) (xy 52.037563 -275.563847)
			(xy 51.971246 -275.600582) (xy 51.9014 -275.630059) (xy 51.828817 -275.651945) (xy 51.754319 -275.665992)
			(xy 51.678749 -275.672041) (xy 51.602965 -275.670022) (xy 51.527825 -275.65996) (xy 51.45418 -275.641968)
			(xy 51.382864 -275.61625) (xy 51.314687 -275.583098) (xy 51.250419 -275.542886) (xy 51.19079 -275.496071)
			(xy 51.136474 -275.443183) (xy 51.088088 -275.384821) (xy 51.04618 -275.321646) (xy 51.011224 -275.254375)
			(xy 50.983617 -275.18377) (xy 50.963671 -275.110629) (xy 50.951612 -275.035784) (xy 50.947577 -274.96008)
			(xy 49.831498 -274.96008) (xy 49.830994 -274.997986) (xy 49.822935 -275.073367) (xy 49.80691 -275.147465)
			(xy 49.7831 -275.21944) (xy 49.751774 -275.288476) (xy 49.713287 -275.353791) (xy 49.668076 -275.414646)
			(xy 49.616652 -275.47035) (xy 49.559599 -275.520272) (xy 49.497563 -275.563847) (xy 49.431246 -275.600582)
			(xy 49.3614 -275.630059) (xy 49.288817 -275.651945) (xy 49.214319 -275.665992) (xy 49.138749 -275.672041)
			(xy 49.062965 -275.670022) (xy 48.987825 -275.65996) (xy 48.91418 -275.641968) (xy 48.842864 -275.61625)
			(xy 48.774687 -275.583098) (xy 48.710419 -275.542886) (xy 48.65079 -275.496071) (xy 48.596474 -275.443183)
			(xy 48.548088 -275.384821) (xy 48.50618 -275.321646) (xy 48.471224 -275.254375) (xy 48.443617 -275.18377)
			(xy 48.423671 -275.110629) (xy 48.411612 -275.035784) (xy 48.407577 -274.96008) (xy 47.291498 -274.96008)
			(xy 47.290994 -274.997986) (xy 47.282935 -275.073367) (xy 47.26691 -275.147465) (xy 47.2431 -275.21944)
			(xy 47.211774 -275.288476) (xy 47.173287 -275.353791) (xy 47.128076 -275.414646) (xy 47.076652 -275.47035)
			(xy 47.019599 -275.520272) (xy 46.957563 -275.563847) (xy 46.891246 -275.600582) (xy 46.8214 -275.630059)
			(xy 46.748817 -275.651945) (xy 46.674319 -275.665992) (xy 46.598749 -275.672041) (xy 46.522965 -275.670022)
			(xy 46.447825 -275.65996) (xy 46.37418 -275.641968) (xy 46.302864 -275.61625) (xy 46.234687 -275.583098)
			(xy 46.170419 -275.542886) (xy 46.11079 -275.496071) (xy 46.056474 -275.443183) (xy 46.008088 -275.384821)
			(xy 45.96618 -275.321646) (xy 45.931224 -275.254375) (xy 45.903617 -275.18377) (xy 45.883671 -275.110629)
			(xy 45.871612 -275.035784) (xy 45.867577 -274.96008) (xy 44.751498 -274.96008) (xy 44.750994 -274.997986)
			(xy 44.742935 -275.073367) (xy 44.72691 -275.147465) (xy 44.7031 -275.21944) (xy 44.671774 -275.288476)
			(xy 44.633287 -275.353791) (xy 44.588076 -275.414646) (xy 44.536652 -275.47035) (xy 44.479599 -275.520272)
			(xy 44.417563 -275.563847) (xy 44.351246 -275.600582) (xy 44.2814 -275.630059) (xy 44.208817 -275.651945)
			(xy 44.134319 -275.665992) (xy 44.058749 -275.672041) (xy 43.982965 -275.670022) (xy 43.907825 -275.65996)
			(xy 43.83418 -275.641968) (xy 43.762864 -275.61625) (xy 43.694687 -275.583098) (xy 43.630419 -275.542886)
			(xy 43.57079 -275.496071) (xy 43.516474 -275.443183) (xy 43.468088 -275.384821) (xy 43.42618 -275.321646)
			(xy 43.391224 -275.254375) (xy 43.363617 -275.18377) (xy 43.343671 -275.110629) (xy 43.331612 -275.035784)
			(xy 43.327577 -274.96008) (xy 42.500813 -274.96008) (xy 42.479042 -274.976857) (xy 42.381609 -275.041665)
			(xy 42.279905 -275.09954) (xy 42.174422 -275.150202) (xy 42.065671 -275.193404) (xy 41.954179 -275.228939)
			(xy 41.840485 -275.256634) (xy 41.725141 -275.276354) (xy 41.608704 -275.288005) (xy 41.491739 -275.29153)
			(xy 41.374812 -275.286912) (xy 41.258489 -275.274173) (xy 41.143334 -275.253375) (xy 41.029905 -275.224618)
			(xy 40.91875 -275.188042) (xy 40.810407 -275.143825) (xy 40.705403 -275.092179) (xy 40.604244 -275.033356)
			(xy 40.507421 -274.96764) (xy 40.415403 -274.895349) (xy 40.328636 -274.816834) (xy 40.247539 -274.732474)
			(xy 40.172506 -274.642679) (xy 40.103899 -274.547883) (xy 40.042051 -274.448544) (xy 39.987262 -274.345145)
			(xy 39.939796 -274.238186) (xy 39.899884 -274.128185) (xy 39.86772 -274.015674) (xy 39.843457 -273.901199)
			(xy 39.827215 -273.785313) (xy 39.819072 -273.668579) (xy 39.818564 -273.61007) (xy 17.114134 -273.61007)
			(xy 15.949252 -274.774914) (xy 24.175718 -274.774914) (xy 24.179789 -274.719292) (xy 24.191915 -274.664855)
			(xy 24.211838 -274.612764) (xy 24.239134 -274.564129) (xy 24.27322 -274.519986) (xy 24.313369 -274.481277)
			(xy 24.358727 -274.448826) (xy 24.408327 -274.423325) (xy 24.461111 -274.405318) (xy 24.515954 -274.395188)
			(xy 24.571688 -274.393151) (xy 24.627125 -274.399251) (xy 24.681082 -274.413357) (xy 24.732411 -274.435169)
			(xy 24.780017 -274.464223) (xy 24.822885 -274.499898) (xy 24.860102 -274.541435) (xy 24.890875 -274.587948)
			(xy 24.914547 -274.638445) (xy 24.930615 -274.691852) (xy 24.938735 -274.747028) (xy 24.939244 -274.774914)
			(xy 26.855672 -274.774914) (xy 26.859743 -274.719292) (xy 26.871869 -274.664855) (xy 26.891792 -274.612764)
			(xy 26.919088 -274.564129) (xy 26.953174 -274.519986) (xy 26.993323 -274.481277) (xy 27.038681 -274.448826)
			(xy 27.088281 -274.423325) (xy 27.141065 -274.405318) (xy 27.195908 -274.395188) (xy 27.251642 -274.393151)
			(xy 27.307079 -274.399251) (xy 27.361036 -274.413357) (xy 27.412365 -274.435169) (xy 27.459971 -274.464223)
			(xy 27.502839 -274.499898) (xy 27.540056 -274.541435) (xy 27.570829 -274.587948) (xy 27.594501 -274.638445)
			(xy 27.610569 -274.691852) (xy 27.618689 -274.747028) (xy 27.619198 -274.774914) (xy 27.618689 -274.8028)
			(xy 27.610569 -274.857976) (xy 27.594501 -274.911383) (xy 27.593574 -274.91336) (xy 29.519874 -274.91336)
			(xy 29.519874 -274.82646) (xy 29.527892 -274.739931) (xy 29.54386 -274.654511) (xy 29.567641 -274.570929)
			(xy 29.599033 -274.489897) (xy 29.637767 -274.412108) (xy 29.683514 -274.338224) (xy 29.735883 -274.268877)
			(xy 29.794427 -274.204657) (xy 29.858647 -274.146113) (xy 29.927994 -274.093744) (xy 30.001878 -274.047997)
			(xy 30.079667 -274.009263) (xy 30.160699 -273.977871) (xy 30.244281 -273.95409) (xy 30.329701 -273.938122)
			(xy 30.41623 -273.930104) (xy 30.50313 -273.930104) (xy 30.589659 -273.938122) (xy 30.675079 -273.95409)
			(xy 30.758661 -273.977871) (xy 30.839693 -274.009263) (xy 30.917482 -274.047997) (xy 30.991366 -274.093744)
			(xy 31.060713 -274.146113) (xy 31.124933 -274.204657) (xy 31.183477 -274.268877) (xy 31.235846 -274.338224)
			(xy 31.281593 -274.412108) (xy 31.320327 -274.489897) (xy 31.351719 -274.570929) (xy 31.3755 -274.654511)
			(xy 31.391468 -274.739931) (xy 31.399486 -274.82646) (xy 31.399988 -274.86991) (xy 31.399486 -274.91336)
			(xy 34.599874 -274.91336) (xy 34.599874 -274.82646) (xy 34.607892 -274.739931) (xy 34.62386 -274.654511)
			(xy 34.647641 -274.570929) (xy 34.679033 -274.489897) (xy 34.717767 -274.412108) (xy 34.763514 -274.338224)
			(xy 34.815883 -274.268877) (xy 34.874427 -274.204657) (xy 34.938647 -274.146113) (xy 35.007994 -274.093744)
			(xy 35.081878 -274.047997) (xy 35.159667 -274.009263) (xy 35.240699 -273.977871) (xy 35.324281 -273.95409)
			(xy 35.409701 -273.938122) (xy 35.49623 -273.930104) (xy 35.58313 -273.930104) (xy 35.669659 -273.938122)
			(xy 35.755079 -273.95409) (xy 35.838661 -273.977871) (xy 35.919693 -274.009263) (xy 35.997482 -274.047997)
			(xy 36.071366 -274.093744) (xy 36.140713 -274.146113) (xy 36.204933 -274.204657) (xy 36.263477 -274.268877)
			(xy 36.315846 -274.338224) (xy 36.361593 -274.412108) (xy 36.400327 -274.489897) (xy 36.431719 -274.570929)
			(xy 36.4555 -274.654511) (xy 36.471468 -274.739931) (xy 36.479486 -274.82646) (xy 36.479988 -274.86991)
			(xy 36.479486 -274.91336) (xy 36.471468 -274.999889) (xy 36.4555 -275.085309) (xy 36.431719 -275.168891)
			(xy 36.400327 -275.249923) (xy 36.361593 -275.327712) (xy 36.315846 -275.401596) (xy 36.263477 -275.470943)
			(xy 36.204933 -275.535163) (xy 36.140713 -275.593707) (xy 36.071366 -275.646076) (xy 35.997482 -275.691823)
			(xy 35.919693 -275.730557) (xy 35.838661 -275.761949) (xy 35.755079 -275.78573) (xy 35.669659 -275.801698)
			(xy 35.58313 -275.809716) (xy 35.49623 -275.809716) (xy 35.409701 -275.801698) (xy 35.324281 -275.78573)
			(xy 35.240699 -275.761949) (xy 35.159667 -275.730557) (xy 35.081878 -275.691823) (xy 35.007994 -275.646076)
			(xy 34.938647 -275.593707) (xy 34.874427 -275.535163) (xy 34.815883 -275.470943) (xy 34.763514 -275.401596)
			(xy 34.717767 -275.327712) (xy 34.679033 -275.249923) (xy 34.647641 -275.168891) (xy 34.62386 -275.085309)
			(xy 34.607892 -274.999889) (xy 34.599874 -274.91336) (xy 31.399486 -274.91336) (xy 31.391468 -274.999889)
			(xy 31.3755 -275.085309) (xy 31.351719 -275.168891) (xy 31.320327 -275.249923) (xy 31.281593 -275.327712)
			(xy 31.235846 -275.401596) (xy 31.183477 -275.470943) (xy 31.124933 -275.535163) (xy 31.060713 -275.593707)
			(xy 30.991366 -275.646076) (xy 30.917482 -275.691823) (xy 30.839693 -275.730557) (xy 30.758661 -275.761949)
			(xy 30.675079 -275.78573) (xy 30.589659 -275.801698) (xy 30.50313 -275.809716) (xy 30.41623 -275.809716)
			(xy 30.329701 -275.801698) (xy 30.244281 -275.78573) (xy 30.160699 -275.761949) (xy 30.079667 -275.730557)
			(xy 30.001878 -275.691823) (xy 29.927994 -275.646076) (xy 29.858647 -275.593707) (xy 29.794427 -275.535163)
			(xy 29.735883 -275.470943) (xy 29.683514 -275.401596) (xy 29.637767 -275.327712) (xy 29.599033 -275.249923)
			(xy 29.567641 -275.168891) (xy 29.54386 -275.085309) (xy 29.527892 -274.999889) (xy 29.519874 -274.91336)
			(xy 27.593574 -274.91336) (xy 27.570829 -274.96188) (xy 27.540056 -275.008393) (xy 27.502839 -275.04993)
			(xy 27.459971 -275.085605) (xy 27.412365 -275.114659) (xy 27.361036 -275.136471) (xy 27.307079 -275.150577)
			(xy 27.251642 -275.156677) (xy 27.195908 -275.15464) (xy 27.141065 -275.14451) (xy 27.088281 -275.126503)
			(xy 27.038681 -275.101002) (xy 26.993323 -275.068551) (xy 26.953174 -275.029842) (xy 26.919088 -274.985699)
			(xy 26.891792 -274.937064) (xy 26.871869 -274.884973) (xy 26.859743 -274.830536) (xy 26.855672 -274.774914)
			(xy 24.939244 -274.774914) (xy 24.938735 -274.8028) (xy 24.930615 -274.857976) (xy 24.914547 -274.911383)
			(xy 24.890875 -274.96188) (xy 24.860102 -275.008393) (xy 24.822885 -275.04993) (xy 24.780017 -275.085605)
			(xy 24.732411 -275.114659) (xy 24.681082 -275.136471) (xy 24.627125 -275.150577) (xy 24.571688 -275.156677)
			(xy 24.515954 -275.15464) (xy 24.461111 -275.14451) (xy 24.408327 -275.126503) (xy 24.358727 -275.101002)
			(xy 24.313369 -275.068551) (xy 24.27322 -275.029842) (xy 24.239134 -274.985699) (xy 24.211838 -274.937064)
			(xy 24.191915 -274.884973) (xy 24.179789 -274.830536) (xy 24.175718 -274.774914) (xy 15.949252 -274.774914)
			(xy 14.601992 -276.12213) (xy 24.243028 -276.12213) (xy 24.247099 -276.066508) (xy 24.259225 -276.012071)
			(xy 24.279148 -275.95998) (xy 24.306444 -275.911345) (xy 24.34053 -275.867202) (xy 24.380679 -275.828493)
			(xy 24.426037 -275.796042) (xy 24.475637 -275.770541) (xy 24.528421 -275.752534) (xy 24.583264 -275.742404)
			(xy 24.638998 -275.740367) (xy 24.694435 -275.746467) (xy 24.748392 -275.760573) (xy 24.799721 -275.782385)
			(xy 24.847327 -275.811439) (xy 24.890195 -275.847114) (xy 24.927412 -275.888651) (xy 24.958185 -275.935164)
			(xy 24.981857 -275.985661) (xy 24.997925 -276.039068) (xy 25.006045 -276.094244) (xy 25.006554 -276.12213)
			(xy 25.006045 -276.150016) (xy 24.997925 -276.205192) (xy 24.981857 -276.258599) (xy 24.958185 -276.309096)
			(xy 24.927412 -276.355609) (xy 24.890195 -276.397146) (xy 24.847327 -276.432821) (xy 24.799721 -276.461875)
			(xy 24.748392 -276.483687) (xy 24.694435 -276.497793) (xy 24.638998 -276.503893) (xy 24.583264 -276.501856)
			(xy 24.528421 -276.491726) (xy 24.475637 -276.473719) (xy 24.426037 -276.448218) (xy 24.380679 -276.415767)
			(xy 24.34053 -276.377058) (xy 24.306444 -276.332915) (xy 24.279148 -276.28428) (xy 24.259225 -276.232189)
			(xy 24.247099 -276.177752) (xy 24.243028 -276.12213) (xy 14.601992 -276.12213) (xy 13.405866 -277.318216)
			(xy 11.288522 -277.318216) (xy 11.269014 -277.321442) (xy 11.233193 -277.338132) (xy 11.218164 -277.350982)
			(xy 11.192002 -277.377144) (xy 24.242774 -277.377144) (xy 24.246845 -277.321522) (xy 24.258971 -277.267085)
			(xy 24.278894 -277.214994) (xy 24.30619 -277.166359) (xy 24.340276 -277.122216) (xy 24.380425 -277.083507)
			(xy 24.425783 -277.051056) (xy 24.475383 -277.025555) (xy 24.528167 -277.007548) (xy 24.58301 -276.997418)
			(xy 24.638744 -276.995381) (xy 24.694181 -277.001481) (xy 24.748138 -277.015587) (xy 24.799467 -277.037399)
			(xy 24.847073 -277.066453) (xy 24.889941 -277.102128) (xy 24.927158 -277.143665) (xy 24.957931 -277.190178)
			(xy 24.981603 -277.240675) (xy 24.997671 -277.294082) (xy 25.005791 -277.349258) (xy 25.0063 -277.377144)
			(xy 25.005791 -277.40503) (xy 24.997671 -277.460206) (xy 24.981603 -277.513613) (xy 24.957931 -277.56411)
			(xy 24.927158 -277.610623) (xy 24.889941 -277.65216) (xy 24.847073 -277.687835) (xy 24.799467 -277.716889)
			(xy 24.748138 -277.738701) (xy 24.724288 -277.744936) (xy 26.885136 -277.744936) (xy 26.889207 -277.689314)
			(xy 26.901333 -277.634877) (xy 26.921256 -277.582786) (xy 26.948552 -277.534151) (xy 26.982638 -277.490008)
			(xy 27.022787 -277.451299) (xy 27.068145 -277.418848) (xy 27.117745 -277.393347) (xy 27.170529 -277.37534)
			(xy 27.225372 -277.36521) (xy 27.281106 -277.363173) (xy 27.336543 -277.369273) (xy 27.3905 -277.383379)
			(xy 27.441829 -277.405191) (xy 27.489435 -277.434245) (xy 27.512404 -277.45336) (xy 29.519874 -277.45336)
			(xy 29.519874 -277.36646) (xy 29.527892 -277.279931) (xy 29.54386 -277.194511) (xy 29.567641 -277.110929)
			(xy 29.599033 -277.029897) (xy 29.637767 -276.952108) (xy 29.683514 -276.878224) (xy 29.735883 -276.808877)
			(xy 29.794427 -276.744657) (xy 29.858647 -276.686113) (xy 29.927994 -276.633744) (xy 30.001878 -276.587997)
			(xy 30.079667 -276.549263) (xy 30.160699 -276.517871) (xy 30.244281 -276.49409) (xy 30.329701 -276.478122)
			(xy 30.41623 -276.470104) (xy 30.50313 -276.470104) (xy 30.589659 -276.478122) (xy 30.675079 -276.49409)
			(xy 30.758661 -276.517871) (xy 30.839693 -276.549263) (xy 30.917482 -276.587997) (xy 30.991366 -276.633744)
			(xy 31.060713 -276.686113) (xy 31.124933 -276.744657) (xy 31.183477 -276.808877) (xy 31.235846 -276.878224)
			(xy 31.281593 -276.952108) (xy 31.320327 -277.029897) (xy 31.351719 -277.110929) (xy 31.3755 -277.194511)
			(xy 31.391468 -277.279931) (xy 31.399486 -277.36646) (xy 31.399988 -277.40991) (xy 31.399486 -277.45336)
			(xy 34.599874 -277.45336) (xy 34.599874 -277.36646) (xy 34.607892 -277.279931) (xy 34.62386 -277.194511)
			(xy 34.647641 -277.110929) (xy 34.679033 -277.029897) (xy 34.717767 -276.952108) (xy 34.763514 -276.878224)
			(xy 34.815883 -276.808877) (xy 34.874427 -276.744657) (xy 34.938647 -276.686113) (xy 35.007994 -276.633744)
			(xy 35.081878 -276.587997) (xy 35.159667 -276.549263) (xy 35.240699 -276.517871) (xy 35.324281 -276.49409)
			(xy 35.409701 -276.478122) (xy 35.49623 -276.470104) (xy 35.58313 -276.470104) (xy 35.669659 -276.478122)
			(xy 35.755079 -276.49409) (xy 35.838661 -276.517871) (xy 35.919693 -276.549263) (xy 35.997482 -276.587997)
			(xy 36.071366 -276.633744) (xy 36.140713 -276.686113) (xy 36.204933 -276.744657) (xy 36.263477 -276.808877)
			(xy 36.315846 -276.878224) (xy 36.361593 -276.952108) (xy 36.400327 -277.029897) (xy 36.431719 -277.110929)
			(xy 36.4555 -277.194511) (xy 36.471468 -277.279931) (xy 36.479486 -277.36646) (xy 36.479988 -277.40991)
			(xy 36.479486 -277.45336) (xy 36.471468 -277.539889) (xy 36.4555 -277.625309) (xy 36.431719 -277.708891)
			(xy 36.400327 -277.789923) (xy 36.361593 -277.867712) (xy 36.315846 -277.941596) (xy 36.263477 -278.010943)
			(xy 36.204933 -278.075163) (xy 36.140713 -278.133707) (xy 36.071366 -278.186076) (xy 35.997482 -278.231823)
			(xy 35.919693 -278.270557) (xy 35.838661 -278.301949) (xy 35.755079 -278.32573) (xy 35.669659 -278.341698)
			(xy 35.58313 -278.349716) (xy 35.49623 -278.349716) (xy 35.409701 -278.341698) (xy 35.324281 -278.32573)
			(xy 35.240699 -278.301949) (xy 35.159667 -278.270557) (xy 35.081878 -278.231823) (xy 35.007994 -278.186076)
			(xy 34.938647 -278.133707) (xy 34.874427 -278.075163) (xy 34.815883 -278.010943) (xy 34.763514 -277.941596)
			(xy 34.717767 -277.867712) (xy 34.679033 -277.789923) (xy 34.647641 -277.708891) (xy 34.62386 -277.625309)
			(xy 34.607892 -277.539889) (xy 34.599874 -277.45336) (xy 31.399486 -277.45336) (xy 31.391468 -277.539889)
			(xy 31.3755 -277.625309) (xy 31.351719 -277.708891) (xy 31.320327 -277.789923) (xy 31.281593 -277.867712)
			(xy 31.235846 -277.941596) (xy 31.183477 -278.010943) (xy 31.124933 -278.075163) (xy 31.060713 -278.133707)
			(xy 30.991366 -278.186076) (xy 30.917482 -278.231823) (xy 30.839693 -278.270557) (xy 30.758661 -278.301949)
			(xy 30.675079 -278.32573) (xy 30.589659 -278.341698) (xy 30.50313 -278.349716) (xy 30.41623 -278.349716)
			(xy 30.329701 -278.341698) (xy 30.244281 -278.32573) (xy 30.160699 -278.301949) (xy 30.079667 -278.270557)
			(xy 30.001878 -278.231823) (xy 29.927994 -278.186076) (xy 29.858647 -278.133707) (xy 29.794427 -278.075163)
			(xy 29.735883 -278.010943) (xy 29.683514 -277.941596) (xy 29.637767 -277.867712) (xy 29.599033 -277.789923)
			(xy 29.567641 -277.708891) (xy 29.54386 -277.625309) (xy 29.527892 -277.539889) (xy 29.519874 -277.45336)
			(xy 27.512404 -277.45336) (xy 27.532303 -277.46992) (xy 27.56952 -277.511457) (xy 27.600293 -277.55797)
			(xy 27.623965 -277.608467) (xy 27.640033 -277.661874) (xy 27.648153 -277.71705) (xy 27.648662 -277.744936)
			(xy 27.648153 -277.772822) (xy 27.640033 -277.827998) (xy 27.623965 -277.881405) (xy 27.600293 -277.931902)
			(xy 27.56952 -277.978415) (xy 27.532303 -278.019952) (xy 27.489435 -278.055627) (xy 27.441829 -278.084681)
			(xy 27.3905 -278.106493) (xy 27.336543 -278.120599) (xy 27.281106 -278.126699) (xy 27.225372 -278.124662)
			(xy 27.170529 -278.114532) (xy 27.117745 -278.096525) (xy 27.068145 -278.071024) (xy 27.022787 -278.038573)
			(xy 26.982638 -277.999864) (xy 26.948552 -277.955721) (xy 26.921256 -277.907086) (xy 26.901333 -277.854995)
			(xy 26.889207 -277.800558) (xy 26.885136 -277.744936) (xy 24.724288 -277.744936) (xy 24.694181 -277.752807)
			(xy 24.638744 -277.758907) (xy 24.58301 -277.75687) (xy 24.528167 -277.74674) (xy 24.475383 -277.728733)
			(xy 24.425783 -277.703232) (xy 24.380425 -277.670781) (xy 24.340276 -277.632072) (xy 24.30619 -277.587929)
			(xy 24.278894 -277.539294) (xy 24.258971 -277.487203) (xy 24.246845 -277.432766) (xy 24.242774 -277.377144)
			(xy 11.192002 -277.377144) (xy 10.082784 -278.486362) (xy 24.67559 -278.486362) (xy 24.679661 -278.43074)
			(xy 24.691787 -278.376303) (xy 24.71171 -278.324212) (xy 24.739006 -278.275577) (xy 24.773092 -278.231434)
			(xy 24.813241 -278.192725) (xy 24.858599 -278.160274) (xy 24.908199 -278.134773) (xy 24.960983 -278.116766)
			(xy 25.015826 -278.106636) (xy 25.07156 -278.104599) (xy 25.126997 -278.110699) (xy 25.180954 -278.124805)
			(xy 25.232283 -278.146617) (xy 25.279889 -278.175671) (xy 25.322757 -278.211346) (xy 25.359974 -278.252883)
			(xy 25.390747 -278.299396) (xy 25.414419 -278.349893) (xy 25.430487 -278.4033) (xy 25.438607 -278.458476)
			(xy 25.439116 -278.486362) (xy 25.438607 -278.514248) (xy 25.430487 -278.569424) (xy 25.414419 -278.622831)
			(xy 25.390747 -278.673328) (xy 25.359974 -278.719841) (xy 25.322757 -278.761378) (xy 25.279889 -278.797053)
			(xy 25.232283 -278.826107) (xy 25.180954 -278.847919) (xy 25.126997 -278.862025) (xy 25.07156 -278.868125)
			(xy 25.015826 -278.866088) (xy 24.960983 -278.855958) (xy 24.908199 -278.837951) (xy 24.858599 -278.81245)
			(xy 24.813241 -278.779999) (xy 24.773092 -278.74129) (xy 24.739006 -278.697147) (xy 24.71171 -278.648512)
			(xy 24.691787 -278.596421) (xy 24.679661 -278.541984) (xy 24.67559 -278.486362) (xy 10.082784 -278.486362)
			(xy 9.112504 -279.456642) (xy 9.102132 -279.467571) (xy 9.086384 -279.493248) (xy 9.077131 -279.521914)
			(xy 9.074892 -279.551952) (xy 9.076944 -279.566878) (xy 9.07923 -279.58161) (xy 9.083787 -279.617828)
			(xy 9.085559 -279.690805) (xy 9.07896 -279.763505) (xy 9.064074 -279.834971) (xy 9.041099 -279.90426)
			(xy 9.010336 -279.97046) (xy 8.996302 -279.99336) (xy 29.519874 -279.99336) (xy 29.519874 -279.90646)
			(xy 29.527892 -279.819931) (xy 29.54386 -279.734511) (xy 29.567641 -279.650929) (xy 29.599033 -279.569897)
			(xy 29.637767 -279.492108) (xy 29.683514 -279.418224) (xy 29.735883 -279.348877) (xy 29.794427 -279.284657)
			(xy 29.858647 -279.226113) (xy 29.927994 -279.173744) (xy 30.001878 -279.127997) (xy 30.079667 -279.089263)
			(xy 30.160699 -279.057871) (xy 30.244281 -279.03409) (xy 30.329701 -279.018122) (xy 30.41623 -279.010104)
			(xy 30.50313 -279.010104) (xy 30.589659 -279.018122) (xy 30.675079 -279.03409) (xy 30.758661 -279.057871)
			(xy 30.839693 -279.089263) (xy 30.917482 -279.127997) (xy 30.991366 -279.173744) (xy 31.060713 -279.226113)
			(xy 31.124933 -279.284657) (xy 31.183477 -279.348877) (xy 31.235846 -279.418224) (xy 31.281593 -279.492108)
			(xy 31.320327 -279.569897) (xy 31.351719 -279.650929) (xy 31.3755 -279.734511) (xy 31.391468 -279.819931)
			(xy 31.399486 -279.90646) (xy 31.399988 -279.94991) (xy 31.399486 -279.99336) (xy 34.599874 -279.99336)
			(xy 34.599874 -279.90646) (xy 34.607892 -279.819931) (xy 34.62386 -279.734511) (xy 34.647641 -279.650929)
			(xy 34.679033 -279.569897) (xy 34.717767 -279.492108) (xy 34.763514 -279.418224) (xy 34.815883 -279.348877)
			(xy 34.874427 -279.284657) (xy 34.938647 -279.226113) (xy 35.007994 -279.173744) (xy 35.081878 -279.127997)
			(xy 35.159667 -279.089263) (xy 35.240699 -279.057871) (xy 35.324281 -279.03409) (xy 35.409701 -279.018122)
			(xy 35.49623 -279.010104) (xy 35.58313 -279.010104) (xy 35.669659 -279.018122) (xy 35.755079 -279.03409)
			(xy 35.838661 -279.057871) (xy 35.919693 -279.089263) (xy 35.997482 -279.127997) (xy 36.071366 -279.173744)
			(xy 36.140713 -279.226113) (xy 36.204933 -279.284657) (xy 36.263477 -279.348877) (xy 36.315846 -279.418224)
			(xy 36.361593 -279.492108) (xy 36.400327 -279.569897) (xy 36.431719 -279.650929) (xy 36.434833 -279.661874)
			(xy 39.458898 -279.661874) (xy 39.462969 -279.606252) (xy 39.475095 -279.551815) (xy 39.495018 -279.499724)
			(xy 39.522314 -279.451089) (xy 39.5564 -279.406946) (xy 39.596549 -279.368237) (xy 39.641907 -279.335786)
			(xy 39.691507 -279.310285) (xy 39.744291 -279.292278) (xy 39.799134 -279.282148) (xy 39.854868 -279.280111)
			(xy 39.910305 -279.286211) (xy 39.964262 -279.300317) (xy 40.015591 -279.322129) (xy 40.063197 -279.351183)
			(xy 40.106065 -279.386858) (xy 40.143282 -279.428395) (xy 40.174055 -279.474908) (xy 40.197727 -279.525405)
			(xy 40.213795 -279.578812) (xy 40.221915 -279.633988) (xy 40.222424 -279.661874) (xy 40.221915 -279.68976)
			(xy 40.213795 -279.744936) (xy 40.197727 -279.798343) (xy 40.174055 -279.84884) (xy 40.143282 -279.895353)
			(xy 40.106065 -279.93689) (xy 40.063197 -279.972565) (xy 40.015591 -280.001619) (xy 39.964262 -280.023431)
			(xy 39.910305 -280.037537) (xy 39.854868 -280.043637) (xy 39.799134 -280.0416) (xy 39.744291 -280.03147)
			(xy 39.691507 -280.013463) (xy 39.641907 -279.987962) (xy 39.596549 -279.955511) (xy 39.5564 -279.916802)
			(xy 39.522314 -279.872659) (xy 39.495018 -279.824024) (xy 39.475095 -279.771933) (xy 39.462969 -279.717496)
			(xy 39.458898 -279.661874) (xy 36.434833 -279.661874) (xy 36.4555 -279.734511) (xy 36.471468 -279.819931)
			(xy 36.479486 -279.90646) (xy 36.479988 -279.94991) (xy 36.479486 -279.99336) (xy 36.471468 -280.079889)
			(xy 36.4555 -280.165309) (xy 36.431719 -280.248891) (xy 36.400327 -280.329923) (xy 36.361593 -280.407712)
			(xy 36.315846 -280.481596) (xy 36.263477 -280.550943) (xy 36.204933 -280.615163) (xy 36.140713 -280.673707)
			(xy 36.071366 -280.726076) (xy 35.997482 -280.771823) (xy 35.919693 -280.810557) (xy 35.838661 -280.841949)
			(xy 35.755079 -280.86573) (xy 35.669659 -280.881698) (xy 35.58313 -280.889716) (xy 35.49623 -280.889716)
			(xy 35.409701 -280.881698) (xy 35.324281 -280.86573) (xy 35.240699 -280.841949) (xy 35.159667 -280.810557)
			(xy 35.081878 -280.771823) (xy 35.007994 -280.726076) (xy 34.938647 -280.673707) (xy 34.874427 -280.615163)
			(xy 34.815883 -280.550943) (xy 34.763514 -280.481596) (xy 34.717767 -280.407712) (xy 34.679033 -280.329923)
			(xy 34.647641 -280.248891) (xy 34.62386 -280.165309) (xy 34.607892 -280.079889) (xy 34.599874 -279.99336)
			(xy 31.399486 -279.99336) (xy 31.391468 -280.079889) (xy 31.3755 -280.165309) (xy 31.351719 -280.248891)
			(xy 31.320327 -280.329923) (xy 31.281593 -280.407712) (xy 31.235846 -280.481596) (xy 31.183477 -280.550943)
			(xy 31.124933 -280.615163) (xy 31.060713 -280.673707) (xy 30.991366 -280.726076) (xy 30.917482 -280.771823)
			(xy 30.839693 -280.810557) (xy 30.758661 -280.841949) (xy 30.675079 -280.86573) (xy 30.589659 -280.881698)
			(xy 30.50313 -280.889716) (xy 30.41623 -280.889716) (xy 30.329701 -280.881698) (xy 30.244281 -280.86573)
			(xy 30.160699 -280.841949) (xy 30.079667 -280.810557) (xy 30.001878 -280.771823) (xy 29.927994 -280.726076)
			(xy 29.858647 -280.673707) (xy 29.794427 -280.615163) (xy 29.735883 -280.550943) (xy 29.683514 -280.481596)
			(xy 29.637767 -280.407712) (xy 29.599033 -280.329923) (xy 29.567641 -280.248891) (xy 29.54386 -280.165309)
			(xy 29.527892 -280.079889) (xy 29.519874 -279.99336) (xy 8.996302 -279.99336) (xy 8.972192 -280.032701)
			(xy 8.927168 -280.090161) (xy 8.875857 -280.142085) (xy 8.818935 -280.187788) (xy 8.757152 -280.226668)
			(xy 8.691321 -280.258214) (xy 8.622309 -280.28201) (xy 8.551025 -280.297743) (xy 8.478409 -280.305205)
			(xy 8.405415 -280.304298) (xy 8.333006 -280.295034) (xy 8.262135 -280.277536) (xy 8.193736 -280.252033)
			(xy 8.128709 -280.218861) (xy 8.098028 -280.199084) (xy 8.068422 -280.178814) (xy 8.013516 -280.132618)
			(xy 7.964163 -280.080533) (xy 7.920988 -280.023222) (xy 7.884543 -279.961412) (xy 7.855291 -279.895892)
			(xy 7.833604 -279.827494) (xy 7.819757 -279.757088) (xy 7.813927 -279.685572) (xy 7.816189 -279.613853)
			(xy 7.826513 -279.542846) (xy 7.844768 -279.473453) (xy 7.870721 -279.406557) (xy 7.904044 -279.34301)
			(xy 7.944311 -279.283619) (xy 7.99101 -279.229142) (xy 8.043547 -279.18027) (xy 8.101254 -279.137625)
			(xy 8.163397 -279.101751) (xy 8.229184 -279.073103) (xy 8.297779 -279.052047) (xy 8.368309 -279.038849)
			(xy 8.439876 -279.033678) (xy 8.511571 -279.0366) (xy 8.5471 -279.041606) (xy 8.553196 -279.042622)
			(xy 8.566404 -279.043384) (xy 8.584323 -279.043819) (xy 8.619261 -279.03589) (xy 8.650625 -279.018572)
			(xy 8.663686 -279.0063) (xy 10.526522 -277.143464) (xy 10.541163 -277.127131) (xy 10.565178 -277.09043)
			(xy 10.582545 -277.050155) (xy 10.592749 -277.007499) (xy 10.595489 -276.963725) (xy 10.590683 -276.920129)
			(xy 10.578474 -276.878003) (xy 10.559223 -276.838595) (xy 10.533499 -276.80307) (xy 10.502066 -276.772482)
			(xy 10.465854 -276.747736) (xy 10.425936 -276.729565) (xy 10.383493 -276.718508) (xy 10.361676 -276.716236)
			(xy 8.905494 -276.716236) (xy 8.888766 -276.716703) (xy 8.856444 -276.725333) (xy 8.827481 -276.742075)
			(xy 8.815324 -276.753574) (xy 8.80491 -276.764242) (xy 8.796274 -276.772878) (xy 8.78111 -276.788683)
			(xy 8.755905 -276.8245) (xy 8.737219 -276.86411) (xy 8.725607 -276.906339) (xy 8.721412 -276.949935)
			(xy 8.724761 -276.993603) (xy 8.735552 -277.036049) (xy 8.753467 -277.076015) (xy 8.777973 -277.112313)
			(xy 8.808344 -277.143869) (xy 8.825738 -277.15718) (xy 8.853956 -277.178473) (xy 8.905972 -277.226349)
			(xy 8.952355 -277.279701) (xy 8.992531 -277.33787) (xy 9.026004 -277.400137) (xy 9.052362 -277.465734)
			(xy 9.071279 -277.533851) (xy 9.08252 -277.603646) (xy 9.085948 -277.674258) (xy 9.08152 -277.744814)
			(xy 9.06929 -277.814443) (xy 9.04941 -277.882285) (xy 9.022125 -277.947502) (xy 8.987773 -278.009289)
			(xy 8.946776 -278.066882) (xy 8.899642 -278.119572) (xy 8.846953 -278.166706) (xy 8.78936 -278.207702)
			(xy 8.727573 -278.242055) (xy 8.662356 -278.26934) (xy 8.594514 -278.28922) (xy 8.524885 -278.30145)
			(xy 8.454329 -278.305878) (xy 8.383717 -278.302451) (xy 8.313922 -278.291209) (xy 8.245805 -278.272293)
			(xy 8.180208 -278.245935) (xy 8.11794 -278.212461) (xy 8.059771 -278.172285) (xy 8.006419 -278.125903)
			(xy 7.958543 -278.073887) (xy 7.937246 -278.045672) (xy 7.923927 -278.028286) (xy 7.892359 -277.997935)
			(xy 7.856055 -277.973444) (xy 7.81609 -277.95554) (xy 7.773647 -277.944751) (xy 7.729983 -277.941398)
			(xy 7.686391 -277.94558) (xy 7.64416 -277.957173) (xy 7.604543 -277.975833) (xy 7.56871 -278.001009)
			(xy 7.552944 -278.016208) (xy 7.112508 -278.456644) (xy 7.102136 -278.467572) (xy 7.086388 -278.49325)
			(xy 7.077135 -278.521915) (xy 7.074896 -278.551954) (xy 7.076948 -278.56688) (xy 7.082218 -278.602072)
			(xy 7.085821 -278.673142) (xy 7.081461 -278.74417) (xy 7.069193 -278.814266) (xy 7.049172 -278.882553)
			(xy 7.021648 -278.948176) (xy 6.986965 -279.010313) (xy 6.945558 -279.068187) (xy 6.897945 -279.121073)
			(xy 6.844721 -279.168309) (xy 6.786554 -279.209304) (xy 6.724172 -279.243544) (xy 6.658355 -279.270601)
			(xy 6.589927 -279.290135) (xy 6.519746 -279.301904) (xy 6.448689 -279.305759) (xy 6.377646 -279.301651)
			(xy 6.307506 -279.289633) (xy 6.239149 -279.269855) (xy 6.173428 -279.242564) (xy 6.111168 -279.208102)
			(xy 6.053147 -279.166901) (xy 6.000093 -279.119476) (xy 5.952668 -279.066421) (xy 5.911467 -279.0084)
			(xy 5.877005 -278.94614) (xy 5.849714 -278.880419) (xy 5.829936 -278.812061) (xy 5.817919 -278.741922)
			(xy 5.813811 -278.670879) (xy 5.817666 -278.599822) (xy 5.829435 -278.529641) (xy 5.84897 -278.461213)
			(xy 5.876027 -278.395396) (xy 5.910268 -278.333014) (xy 5.951262 -278.274847) (xy 5.998499 -278.221624)
			(xy 6.051385 -278.174011) (xy 6.109259 -278.132604) (xy 6.171396 -278.097921) (xy 6.237019 -278.070397)
			(xy 6.305306 -278.050376) (xy 6.375403 -278.038109) (xy 6.44643 -278.033749) (xy 6.517501 -278.037352)
			(xy 6.552692 -278.042624) (xy 6.567619 -278.044607) (xy 6.597638 -278.042325) (xy 6.626291 -278.033091)
			(xy 6.651994 -278.017416) (xy 6.662928 -278.007064) (xy 8.103362 -276.56663) (xy 8.118525 -276.550824)
			(xy 8.143728 -276.515005) (xy 8.162412 -276.475394) (xy 8.174024 -276.433165) (xy 8.178219 -276.38957)
			(xy 8.174872 -276.345901) (xy 8.164082 -276.303455) (xy 8.146171 -276.263488) (xy 8.121668 -276.227187)
			(xy 8.0913 -276.195629) (xy 8.073898 -276.182328) (xy 8.048056 -276.162877) (xy 8.000052 -276.119523)
			(xy 7.9567 -276.071516) (xy 7.937246 -276.045676) (xy 7.923927 -276.02829) (xy 7.892359 -275.997938)
			(xy 7.856055 -275.973447) (xy 7.81609 -275.955542) (xy 7.773647 -275.944754) (xy 7.729983 -275.941401)
			(xy 7.68639 -275.945582) (xy 7.64416 -275.957175) (xy 7.604542 -275.975836) (xy 7.56871 -276.001012)
			(xy 7.552944 -276.016212) (xy 7.112508 -276.456648) (xy 7.102136 -276.467577) (xy 7.086389 -276.493254)
			(xy 7.077137 -276.521919) (xy 7.074899 -276.551958) (xy 7.076948 -276.566884) (xy 7.082371 -276.603155)
			(xy 7.085832 -276.676414) (xy 7.080837 -276.749585) (xy 7.067451 -276.821695) (xy 7.045854 -276.891784)
			(xy 7.016332 -276.958921) (xy 6.979278 -277.022213) (xy 6.935184 -277.080819) (xy 6.884637 -277.133959)
			(xy 6.828308 -277.180927) (xy 6.766948 -277.221099) (xy 6.70137 -277.25394) (xy 6.632449 -277.279014)
			(xy 6.561099 -277.295987) (xy 6.488269 -277.304634) (xy 6.4516 -277.305262) (xy 6.417608 -277.304931)
			(xy 6.349993 -277.297894) (xy 6.283517 -277.283674) (xy 6.218939 -277.262435) (xy 6.156999 -277.23442)
			(xy 6.098407 -277.199949) (xy 6.070854 -277.18004) (xy 6.042328 -277.158236) (xy 5.989876 -277.109201)
			(xy 5.943284 -277.054567) (xy 5.903144 -276.995032) (xy 5.869968 -276.931352) (xy 5.844179 -276.86434)
			(xy 5.826105 -276.794849) (xy 5.815976 -276.723764) (xy 5.813921 -276.651991) (xy 5.819967 -276.580443)
			(xy 5.834036 -276.510032) (xy 5.84454 -276.475698) (xy 5.856814 -276.439261) (xy 5.888959 -276.369413)
			(xy 5.929297 -276.303954) (xy 5.977238 -276.24384) (xy 6.032082 -276.189949) (xy 6.062218 -276.166072)
			(xy 6.09229 -276.143617) (xy 6.156743 -276.105165) (xy 6.22528 -276.074579) (xy 6.296945 -276.052284)
			(xy 6.333744 -276.044914) (xy 6.369096 -276.038804) (xy 6.440656 -276.033651) (xy 6.512341 -276.036606)
			(xy 6.547866 -276.041612) (xy 6.554216 -276.042628) (xy 6.59384 -276.044914) (xy 6.644386 -276.02561)
			(xy 6.66369 -276.006306) (xy 7.255256 -275.41474) (xy 7.269897 -275.398406) (xy 7.293913 -275.361705)
			(xy 7.311281 -275.321429) (xy 7.321486 -275.278772) (xy 7.324226 -275.234997) (xy 7.319421 -275.191401)
			(xy 7.307212 -275.149274) (xy 7.28796 -275.109864) (xy 7.262237 -275.074338) (xy 7.230804 -275.043749)
			(xy 7.194591 -275.019002) (xy 7.154672 -275.00083) (xy 7.112228 -274.989772) (xy 7.09041 -274.987512)
			(xy 7.069328 -274.987512) (xy 7.054237 -274.987914) (xy 7.024889 -274.994952) (xy 6.998016 -275.008688)
			(xy 6.975122 -275.028354) (xy 6.96595 -275.040344) (xy 6.96595 -275.040598) (xy 6.946327 -275.067178)
			(xy 6.90242 -275.11655) (xy 6.87832 -275.13915) (xy 6.851473 -275.162988) (xy 6.793328 -275.20511)
			(xy 6.730807 -275.240412) (xy 6.664705 -275.268443) (xy 6.595866 -275.288845) (xy 6.525166 -275.30136)
			(xy 6.453506 -275.305828) (xy 6.381799 -275.302191) (xy 6.310959 -275.290496) (xy 6.241888 -275.270893)
			(xy 6.175466 -275.24363) (xy 6.11254 -275.209056) (xy 6.053911 -275.16761) (xy 6.000326 -275.119821)
			(xy 5.952468 -275.066298) (xy 5.910947 -275.007722) (xy 5.876292 -274.94484) (xy 5.848944 -274.878453)
			(xy 5.829252 -274.809407) (xy 5.817467 -274.738582) (xy 5.813738 -274.66688) (xy 5.818114 -274.595214)
			(xy 5.830538 -274.524498) (xy 5.840222 -274.489926) (xy 5.845389 -274.46739) (xy 5.848415 -274.421259)
			(xy 5.843049 -274.375341) (xy 5.829467 -274.33115) (xy 5.808118 -274.290145) (xy 5.779705 -274.253676)
			(xy 5.745166 -274.222946) (xy 5.705639 -274.19897) (xy 5.662428 -274.182536) (xy 5.616957 -274.174188)
			(xy 5.593842 -274.173696) (xy 4.895596 -274.173696) (xy 4.590796 -274.478496) (xy 4.572 -274.537424)
			(xy 4.577334 -274.567904) (xy 4.57835 -274.574508) (xy 4.583616 -274.613218) (xy 4.585768 -274.691312)
			(xy 4.578324 -274.76908) (xy 4.561398 -274.845347) (xy 4.548886 -274.882356) (xy 4.536059 -274.9169)
			(xy 4.503539 -274.983026) (xy 4.463592 -275.044949) (xy 4.416755 -275.101838) (xy 4.363654 -275.152931)
			(xy 4.305002 -275.197542) (xy 4.241586 -275.235073) (xy 4.174257 -275.265021) (xy 4.103916 -275.286984)
			(xy 4.06781 -275.294344) (xy 4.032592 -275.300493) (xy 3.961292 -275.30578) (xy 3.889849 -275.303034)
			(xy 3.819165 -275.292289) (xy 3.750133 -275.273683) (xy 3.683624 -275.247449) (xy 3.620478 -275.213918)
			(xy 3.561493 -275.173515) (xy 3.507413 -275.12675) (xy 3.458922 -275.074212) (xy 3.437382 -275.045678)
			(xy 3.424063 -275.028297) (xy 3.392496 -274.997955) (xy 3.356195 -274.973474) (xy 3.316235 -274.955579)
			(xy 3.273798 -274.944799) (xy 3.230141 -274.941454) (xy 3.186557 -274.945642) (xy 3.144337 -274.95724)
			(xy 3.10473 -274.975904) (xy 3.068908 -275.001082) (xy 3.05308 -275.016214) (xy 2.612644 -275.45665)
			(xy 2.602269 -275.467577) (xy 2.586519 -275.493254) (xy 2.577264 -275.52192) (xy 2.575026 -275.55196)
			(xy 2.577084 -275.566886) (xy 2.582343 -275.601957) (xy 2.585961 -275.672785) (xy 2.581671 -275.743575)
			(xy 2.569526 -275.813448) (xy 2.549677 -275.881533) (xy 2.52237 -275.946985) (xy 2.487945 -276.00899)
			(xy 2.446831 -276.066777) (xy 2.399539 -276.119626) (xy 2.346656 -276.166882) (xy 2.28884 -276.207955)
			(xy 2.226811 -276.242336) (xy 2.16134 -276.269596) (xy 2.09324 -276.289397) (xy 2.023359 -276.301493)
			(xy 1.952566 -276.305733) (xy 1.881741 -276.302065) (xy 1.811764 -276.290533) (xy 1.743507 -276.271282)
			(xy 1.677818 -276.244551) (xy 1.646428 -276.228048) (xy 1.639824 -276.224492) (xy 1.620357 -276.215008)
			(xy 1.579032 -276.202079) (xy 1.536113 -276.196345) (xy 1.492844 -276.197971) (xy 1.450477 -276.206911)
			(xy 1.410239 -276.222904) (xy 1.373295 -276.245489) (xy 1.340716 -276.274011) (xy 1.313445 -276.307644)
			(xy 1.292271 -276.345414) (xy 1.277808 -276.386227) (xy 1.270475 -276.428902) (xy 1.27 -276.450552)
			(xy 1.27 -276.705415) (xy 3.314946 -276.705415) (xy 3.314946 -276.634093) (xy 3.322932 -276.563219)
			(xy 3.338802 -276.493684) (xy 3.362359 -276.426364) (xy 3.393304 -276.362105) (xy 3.43125 -276.301714)
			(xy 3.475719 -276.245952) (xy 3.526152 -276.195519) (xy 3.581914 -276.15105) (xy 3.642305 -276.113104)
			(xy 3.706564 -276.082159) (xy 3.773884 -276.058602) (xy 3.843419 -276.042732) (xy 3.914293 -276.034746)
			(xy 3.985615 -276.034746) (xy 4.056489 -276.042732) (xy 4.126024 -276.058602) (xy 4.193344 -276.082159)
			(xy 4.257603 -276.113104) (xy 4.317994 -276.15105) (xy 4.373756 -276.195519) (xy 4.424189 -276.245952)
			(xy 4.468658 -276.301714) (xy 4.506604 -276.362105) (xy 4.537549 -276.426364) (xy 4.561106 -276.493684)
			(xy 4.576976 -276.563219) (xy 4.584962 -276.634093) (xy 4.585462 -276.669754) (xy 4.584962 -276.705415)
			(xy 4.576976 -276.776289) (xy 4.561106 -276.845824) (xy 4.537549 -276.913144) (xy 4.506604 -276.977403)
			(xy 4.468658 -277.037794) (xy 4.424189 -277.093556) (xy 4.373756 -277.143989) (xy 4.317994 -277.188458)
			(xy 4.257603 -277.226404) (xy 4.193344 -277.257349) (xy 4.126024 -277.280906) (xy 4.056489 -277.296776)
			(xy 3.985615 -277.304762) (xy 3.914293 -277.304762) (xy 3.843419 -277.296776) (xy 3.773884 -277.280906)
			(xy 3.706564 -277.257349) (xy 3.642305 -277.226404) (xy 3.581914 -277.188458) (xy 3.526152 -277.143989)
			(xy 3.475719 -277.093556) (xy 3.43125 -277.037794) (xy 3.393304 -276.977403) (xy 3.362359 -276.913144)
			(xy 3.338802 -276.845824) (xy 3.322932 -276.776289) (xy 3.314946 -276.705415) (xy 1.27 -276.705415)
			(xy 1.27 -276.888956) (xy 1.270438 -276.910606) (xy 1.27778 -276.953279) (xy 1.29225 -276.99409)
			(xy 1.313429 -277.031857) (xy 1.340704 -277.065487) (xy 1.373286 -277.094006) (xy 1.410231 -277.116588)
			(xy 1.45047 -277.132581) (xy 1.492837 -277.14152) (xy 1.536106 -277.143147) (xy 1.579026 -277.137415)
			(xy 1.620352 -277.12449) (xy 1.639824 -277.115016) (xy 1.671264 -277.097996) (xy 1.737191 -277.070331)
			(xy 1.805806 -277.050239) (xy 1.876242 -277.037975) (xy 1.94761 -277.033693) (xy 2.019007 -277.037447)
			(xy 2.089532 -277.049191) (xy 2.158294 -277.068775) (xy 2.224423 -277.095952) (xy 2.287084 -277.130379)
			(xy 2.345487 -277.171621) (xy 2.398891 -277.219156) (xy 2.446624 -277.272385) (xy 2.488081 -277.330634)
			(xy 2.52274 -277.393168) (xy 2.550161 -277.459196) (xy 2.569999 -277.527885) (xy 2.582003 -277.598366)
			(xy 2.586021 -277.669749) (xy 2.582003 -277.741132) (xy 2.569999 -277.811613) (xy 2.550162 -277.880302)
			(xy 2.52274 -277.94633) (xy 2.488082 -278.008864) (xy 2.446625 -278.067114) (xy 2.398893 -278.120343)
			(xy 2.345488 -278.167878) (xy 2.287086 -278.20912) (xy 2.224425 -278.243547) (xy 2.158295 -278.270725)
			(xy 2.089534 -278.290309) (xy 2.019009 -278.302052) (xy 1.947612 -278.305807) (xy 1.876244 -278.301525)
			(xy 1.805808 -278.289261) (xy 1.737193 -278.26917) (xy 1.671266 -278.241505) (xy 1.639824 -278.224488)
			(xy 1.620357 -278.215004) (xy 1.579032 -278.202076) (xy 1.536113 -278.196342) (xy 1.492843 -278.197968)
			(xy 1.450476 -278.206907) (xy 1.410238 -278.222901) (xy 1.373294 -278.245486) (xy 1.340715 -278.274007)
			(xy 1.313443 -278.30764) (xy 1.292269 -278.34541) (xy 1.277806 -278.386223) (xy 1.270472 -278.428898)
			(xy 1.27 -278.450548) (xy 1.27 -278.705411) (xy 3.314946 -278.705411) (xy 3.314946 -278.634089) (xy 3.322932 -278.563215)
			(xy 3.338802 -278.49368) (xy 3.362359 -278.42636) (xy 3.393304 -278.362101) (xy 3.43125 -278.30171)
			(xy 3.475719 -278.245948) (xy 3.526152 -278.195515) (xy 3.581914 -278.151046) (xy 3.642305 -278.1131)
			(xy 3.706564 -278.082155) (xy 3.773884 -278.058598) (xy 3.843419 -278.042728) (xy 3.914293 -278.034742)
			(xy 3.985615 -278.034742) (xy 4.056489 -278.042728) (xy 4.126024 -278.058598) (xy 4.193344 -278.082155)
			(xy 4.257603 -278.1131) (xy 4.317994 -278.151046) (xy 4.373756 -278.195515) (xy 4.424189 -278.245948)
			(xy 4.468658 -278.30171) (xy 4.506604 -278.362101) (xy 4.537549 -278.42636) (xy 4.561106 -278.49368)
			(xy 4.576976 -278.563215) (xy 4.584962 -278.634089) (xy 4.585462 -278.66975) (xy 4.584962 -278.705411)
			(xy 4.576976 -278.776285) (xy 4.561106 -278.84582) (xy 4.537549 -278.91314) (xy 4.506604 -278.977399)
			(xy 4.468658 -279.03779) (xy 4.424189 -279.093552) (xy 4.373756 -279.143985) (xy 4.317994 -279.188454)
			(xy 4.257603 -279.2264) (xy 4.193344 -279.257345) (xy 4.126024 -279.280902) (xy 4.056489 -279.296772)
			(xy 3.985615 -279.304758) (xy 3.914293 -279.304758) (xy 3.843419 -279.296772) (xy 3.773884 -279.280902)
			(xy 3.706564 -279.257345) (xy 3.642305 -279.2264) (xy 3.581914 -279.188454) (xy 3.526152 -279.143985)
			(xy 3.475719 -279.093552) (xy 3.43125 -279.03779) (xy 3.393304 -278.977399) (xy 3.362359 -278.91314)
			(xy 3.338802 -278.84582) (xy 3.322932 -278.776285) (xy 3.314946 -278.705411) (xy 1.27 -278.705411)
			(xy 1.27 -278.888952) (xy 1.270438 -278.910602) (xy 1.277779 -278.953276) (xy 1.292249 -278.994088)
			(xy 1.313428 -279.031855) (xy 1.340703 -279.065486) (xy 1.373285 -279.094005) (xy 1.41023 -279.116588)
			(xy 1.450469 -279.132581) (xy 1.492837 -279.14152) (xy 1.536107 -279.143147) (xy 1.579027 -279.137415)
			(xy 1.620353 -279.124489) (xy 1.639824 -279.115012) (xy 1.671264 -279.097992) (xy 1.737191 -279.070327)
			(xy 1.805807 -279.050235) (xy 1.876243 -279.037971) (xy 1.947612 -279.033689) (xy 2.019009 -279.037444)
			(xy 2.089535 -279.049188) (xy 2.158297 -279.068772) (xy 2.224426 -279.09595) (xy 2.287088 -279.130377)
			(xy 2.34549 -279.171619) (xy 2.398895 -279.219155) (xy 2.446628 -279.272384) (xy 2.488085 -279.330634)
			(xy 2.522744 -279.393168) (xy 2.550165 -279.459197) (xy 2.570003 -279.527886) (xy 2.582007 -279.598368)
			(xy 2.586025 -279.669751) (xy 2.582007 -279.741134) (xy 2.570002 -279.811616) (xy 2.550164 -279.880305)
			(xy 2.522743 -279.946334) (xy 2.488084 -280.008868) (xy 2.446627 -280.067117) (xy 2.398894 -280.120346)
			(xy 2.345489 -280.167882) (xy 2.287086 -280.209124) (xy 2.224424 -280.243551) (xy 2.158295 -280.270729)
			(xy 2.089533 -280.290313) (xy 2.019007 -280.302056) (xy 1.94761 -280.305811) (xy 1.876242 -280.301529)
			(xy 1.805805 -280.289264) (xy 1.73719 -280.269172) (xy 1.671263 -280.241507) (xy 1.639824 -280.224484)
			(xy 1.620357 -280.215) (xy 1.579031 -280.202072) (xy 1.536112 -280.196338) (xy 1.492843 -280.197964)
			(xy 1.450475 -280.206904) (xy 1.410237 -280.222897) (xy 1.373293 -280.245482) (xy 1.340713 -280.274004)
			(xy 1.313441 -280.307636) (xy 1.292267 -280.345406) (xy 1.277803 -280.386219) (xy 1.270469 -280.428894)
			(xy 1.27 -280.450544) (xy 1.27 -280.705407) (xy 3.314946 -280.705407) (xy 3.314946 -280.634085) (xy 3.322932 -280.563211)
			(xy 3.338802 -280.493676) (xy 3.362359 -280.426356) (xy 3.393304 -280.362097) (xy 3.43125 -280.301706)
			(xy 3.475719 -280.245944) (xy 3.526152 -280.195511) (xy 3.581914 -280.151042) (xy 3.642305 -280.113096)
			(xy 3.706564 -280.082151) (xy 3.773884 -280.058594) (xy 3.843419 -280.042724) (xy 3.914293 -280.034738)
			(xy 3.985615 -280.034738) (xy 4.056489 -280.042724) (xy 4.126024 -280.058594) (xy 4.193344 -280.082151)
			(xy 4.257603 -280.113096) (xy 4.317994 -280.151042) (xy 4.373756 -280.195511) (xy 4.424189 -280.245944)
			(xy 4.468658 -280.301706) (xy 4.506604 -280.362097) (xy 4.537549 -280.426356) (xy 4.561106 -280.493676)
			(xy 4.576976 -280.563211) (xy 4.584962 -280.634085) (xy 4.585462 -280.669746) (xy 4.584962 -280.705407)
			(xy 5.814814 -280.705407) (xy 5.814814 -280.634085) (xy 5.8228 -280.563211) (xy 5.83867 -280.493676)
			(xy 5.862227 -280.426356) (xy 5.893172 -280.362097) (xy 5.931118 -280.301706) (xy 5.975587 -280.245944)
			(xy 6.02602 -280.195511) (xy 6.081782 -280.151042) (xy 6.142173 -280.113096) (xy 6.206432 -280.082151)
			(xy 6.273752 -280.058594) (xy 6.343287 -280.042724) (xy 6.414161 -280.034738) (xy 6.485483 -280.034738)
			(xy 6.556357 -280.042724) (xy 6.625892 -280.058594) (xy 6.693212 -280.082151) (xy 6.757471 -280.113096)
			(xy 6.817862 -280.151042) (xy 6.873624 -280.195511) (xy 6.924057 -280.245944) (xy 6.968526 -280.301706)
			(xy 7.006472 -280.362097) (xy 7.037417 -280.426356) (xy 7.060974 -280.493676) (xy 7.076844 -280.563211)
			(xy 7.08483 -280.634085) (xy 7.08533 -280.669746) (xy 7.08483 -280.705407) (xy 7.076844 -280.776281)
			(xy 7.060974 -280.845816) (xy 7.054947 -280.86304) (xy 27.247848 -280.86304) (xy 27.251919 -280.807418)
			(xy 27.264045 -280.752981) (xy 27.283968 -280.70089) (xy 27.311264 -280.652255) (xy 27.34535 -280.608112)
			(xy 27.385499 -280.569403) (xy 27.430857 -280.536952) (xy 27.480457 -280.511451) (xy 27.533241 -280.493444)
			(xy 27.588084 -280.483314) (xy 27.643818 -280.481277) (xy 27.699255 -280.487377) (xy 27.753212 -280.501483)
			(xy 27.804541 -280.523295) (xy 27.852147 -280.552349) (xy 27.895015 -280.588024) (xy 27.932232 -280.629561)
			(xy 27.963005 -280.676074) (xy 27.986677 -280.726571) (xy 28.002745 -280.779978) (xy 28.010865 -280.835154)
			(xy 28.011374 -280.86304) (xy 28.010865 -280.890926) (xy 28.002745 -280.946102) (xy 27.986677 -280.999509)
			(xy 27.963005 -281.050006) (xy 27.932232 -281.096519) (xy 27.895015 -281.138056) (xy 27.891884 -281.140662)
			(xy 40.801542 -281.140662) (xy 40.805613 -281.08504) (xy 40.817739 -281.030603) (xy 40.837662 -280.978512)
			(xy 40.864958 -280.929877) (xy 40.899044 -280.885734) (xy 40.939193 -280.847025) (xy 40.984551 -280.814574)
			(xy 41.034151 -280.789073) (xy 41.086935 -280.771066) (xy 41.141778 -280.760936) (xy 41.197512 -280.758899)
			(xy 41.252949 -280.764999) (xy 41.306906 -280.779105) (xy 41.358235 -280.800917) (xy 41.405841 -280.829971)
			(xy 41.448709 -280.865646) (xy 41.485926 -280.907183) (xy 41.516699 -280.953696) (xy 41.540371 -281.004193)
			(xy 41.556439 -281.0576) (xy 41.564559 -281.112776) (xy 41.564813 -281.126692) (xy 87.019128 -281.126692)
			(xy 87.023199 -281.07107) (xy 87.035325 -281.016633) (xy 87.055248 -280.964542) (xy 87.082544 -280.915907)
			(xy 87.11663 -280.871764) (xy 87.156779 -280.833055) (xy 87.202137 -280.800604) (xy 87.251737 -280.775103)
			(xy 87.304521 -280.757096) (xy 87.359364 -280.746966) (xy 87.415098 -280.744929) (xy 87.470535 -280.751029)
			(xy 87.524492 -280.765135) (xy 87.575821 -280.786947) (xy 87.623427 -280.816001) (xy 87.666295 -280.851676)
			(xy 87.703512 -280.893213) (xy 87.734285 -280.939726) (xy 87.757957 -280.990223) (xy 87.774025 -281.04363)
			(xy 87.782145 -281.098806) (xy 87.782654 -281.126692) (xy 87.782145 -281.154578) (xy 87.774025 -281.209754)
			(xy 87.757957 -281.263161) (xy 87.734285 -281.313658) (xy 87.703512 -281.360171) (xy 87.666295 -281.401708)
			(xy 87.623427 -281.437383) (xy 87.575821 -281.466437) (xy 87.524492 -281.488249) (xy 87.470535 -281.502355)
			(xy 87.415098 -281.508455) (xy 87.359364 -281.506418) (xy 87.304521 -281.496288) (xy 87.251737 -281.478281)
			(xy 87.202137 -281.45278) (xy 87.156779 -281.420329) (xy 87.11663 -281.38162) (xy 87.082544 -281.337477)
			(xy 87.055248 -281.288842) (xy 87.035325 -281.236751) (xy 87.023199 -281.182314) (xy 87.019128 -281.126692)
			(xy 41.564813 -281.126692) (xy 41.565068 -281.140662) (xy 41.564559 -281.168548) (xy 41.556439 -281.223724)
			(xy 41.540371 -281.277131) (xy 41.516699 -281.327628) (xy 41.485926 -281.374141) (xy 41.448709 -281.415678)
			(xy 41.405841 -281.451353) (xy 41.358235 -281.480407) (xy 41.306906 -281.502219) (xy 41.252949 -281.516325)
			(xy 41.197512 -281.522425) (xy 41.141778 -281.520388) (xy 41.086935 -281.510258) (xy 41.034151 -281.492251)
			(xy 40.984551 -281.46675) (xy 40.939193 -281.434299) (xy 40.899044 -281.39559) (xy 40.864958 -281.351447)
			(xy 40.837662 -281.302812) (xy 40.817739 -281.250721) (xy 40.805613 -281.196284) (xy 40.801542 -281.140662)
			(xy 27.891884 -281.140662) (xy 27.852147 -281.173731) (xy 27.804541 -281.202785) (xy 27.753212 -281.224597)
			(xy 27.699255 -281.238703) (xy 27.643818 -281.244803) (xy 27.588084 -281.242766) (xy 27.533241 -281.232636)
			(xy 27.480457 -281.214629) (xy 27.430857 -281.189128) (xy 27.385499 -281.156677) (xy 27.34535 -281.117968)
			(xy 27.311264 -281.073825) (xy 27.283968 -281.02519) (xy 27.264045 -280.973099) (xy 27.251919 -280.918662)
			(xy 27.247848 -280.86304) (xy 7.054947 -280.86304) (xy 7.037417 -280.913136) (xy 7.006472 -280.977395)
			(xy 6.968526 -281.037786) (xy 6.924057 -281.093548) (xy 6.873624 -281.143981) (xy 6.817862 -281.18845)
			(xy 6.757471 -281.226396) (xy 6.693212 -281.257341) (xy 6.625892 -281.280898) (xy 6.556357 -281.296768)
			(xy 6.485483 -281.304754) (xy 6.414161 -281.304754) (xy 6.343287 -281.296768) (xy 6.273752 -281.280898)
			(xy 6.206432 -281.257341) (xy 6.142173 -281.226396) (xy 6.081782 -281.18845) (xy 6.02602 -281.143981)
			(xy 5.975587 -281.093548) (xy 5.931118 -281.037786) (xy 5.893172 -280.977395) (xy 5.862227 -280.913136)
			(xy 5.83867 -280.845816) (xy 5.8228 -280.776281) (xy 5.814814 -280.705407) (xy 4.584962 -280.705407)
			(xy 4.576976 -280.776281) (xy 4.561106 -280.845816) (xy 4.537549 -280.913136) (xy 4.506604 -280.977395)
			(xy 4.468658 -281.037786) (xy 4.424189 -281.093548) (xy 4.373756 -281.143981) (xy 4.317994 -281.18845)
			(xy 4.257603 -281.226396) (xy 4.193344 -281.257341) (xy 4.126024 -281.280898) (xy 4.056489 -281.296768)
			(xy 3.985615 -281.304754) (xy 3.914293 -281.304754) (xy 3.843419 -281.296768) (xy 3.773884 -281.280898)
			(xy 3.706564 -281.257341) (xy 3.642305 -281.226396) (xy 3.581914 -281.18845) (xy 3.526152 -281.143981)
			(xy 3.475719 -281.093548) (xy 3.43125 -281.037786) (xy 3.393304 -280.977395) (xy 3.362359 -280.913136)
			(xy 3.338802 -280.845816) (xy 3.322932 -280.776281) (xy 3.314946 -280.705407) (xy 1.27 -280.705407)
			(xy 1.27 -280.888948) (xy 1.270437 -280.910599) (xy 1.277778 -280.953273) (xy 1.292247 -280.994085)
			(xy 1.313426 -281.031853) (xy 1.340702 -281.065484) (xy 1.373284 -281.094004) (xy 1.410229 -281.116588)
			(xy 1.450469 -281.13258) (xy 1.492837 -281.14152) (xy 1.536108 -281.143147) (xy 1.579028 -281.137414)
			(xy 1.620355 -281.124489) (xy 1.639824 -281.115008) (xy 1.671264 -281.097988) (xy 1.737191 -281.070323)
			(xy 1.805806 -281.050232) (xy 1.876242 -281.037968) (xy 1.94761 -281.033686) (xy 2.019007 -281.037441)
			(xy 2.089532 -281.049184) (xy 2.158294 -281.068769) (xy 2.224423 -281.095946) (xy 2.287084 -281.130373)
			(xy 2.345486 -281.171615) (xy 2.398891 -281.219151) (xy 2.446623 -281.272379) (xy 2.488081 -281.330629)
			(xy 2.522739 -281.393163) (xy 2.55016 -281.459191) (xy 2.569998 -281.52788) (xy 2.582002 -281.598361)
			(xy 2.58602 -281.669744) (xy 2.584013 -281.705405) (xy 7.81481 -281.705405) (xy 7.81481 -281.634083)
			(xy 7.822796 -281.563209) (xy 7.838666 -281.493674) (xy 7.862223 -281.426354) (xy 7.893168 -281.362095)
			(xy 7.931114 -281.301704) (xy 7.975583 -281.245942) (xy 8.026016 -281.195509) (xy 8.081778 -281.15104)
			(xy 8.142169 -281.113094) (xy 8.206428 -281.082149) (xy 8.273748 -281.058592) (xy 8.343283 -281.042722)
			(xy 8.414157 -281.034736) (xy 8.485479 -281.034736) (xy 8.556353 -281.042722) (xy 8.625888 -281.058592)
			(xy 8.693208 -281.082149) (xy 8.757467 -281.113094) (xy 8.817858 -281.15104) (xy 8.87362 -281.195509)
			(xy 8.924053 -281.245942) (xy 8.968522 -281.301704) (xy 9.006468 -281.362095) (xy 9.037413 -281.426354)
			(xy 9.06097 -281.493674) (xy 9.07684 -281.563209) (xy 9.084826 -281.634083) (xy 9.085326 -281.669744)
			(xy 9.084826 -281.705405) (xy 9.07684 -281.776279) (xy 9.06097 -281.845814) (xy 9.037413 -281.913134)
			(xy 9.006468 -281.977393) (xy 8.968522 -282.037784) (xy 8.924053 -282.093546) (xy 8.87362 -282.143979)
			(xy 8.817858 -282.188448) (xy 8.757467 -282.226394) (xy 8.693208 -282.257339) (xy 8.625888 -282.280896)
			(xy 8.556353 -282.296766) (xy 8.485479 -282.304752) (xy 8.414157 -282.304752) (xy 8.343283 -282.296766)
			(xy 8.273748 -282.280896) (xy 8.206428 -282.257339) (xy 8.142169 -282.226394) (xy 8.081778 -282.188448)
			(xy 8.026016 -282.143979) (xy 7.975583 -282.093546) (xy 7.931114 -282.037784) (xy 7.893168 -281.977393)
			(xy 7.862223 -281.913134) (xy 7.838666 -281.845814) (xy 7.822796 -281.776279) (xy 7.81481 -281.705405)
			(xy 2.584013 -281.705405) (xy 2.582002 -281.741127) (xy 2.569998 -281.811608) (xy 2.55016 -281.880297)
			(xy 2.522739 -281.946325) (xy 2.488081 -282.008859) (xy 2.446623 -282.067109) (xy 2.398891 -282.120337)
			(xy 2.345486 -282.167873) (xy 2.287084 -282.209115) (xy 2.224423 -282.243542) (xy 2.158294 -282.270719)
			(xy 2.089532 -282.290304) (xy 2.019007 -282.302047) (xy 1.94761 -282.305802) (xy 1.876242 -282.30152)
			(xy 1.805806 -282.289256) (xy 1.737191 -282.269165) (xy 1.671264 -282.2415) (xy 1.639824 -282.22448)
			(xy 1.620357 -282.214996) (xy 1.579031 -282.202068) (xy 1.536112 -282.196334) (xy 1.492842 -282.197961)
			(xy 1.450475 -282.2069) (xy 1.410236 -282.222894) (xy 1.373292 -282.245478) (xy 1.340712 -282.274)
			(xy 1.31344 -282.307632) (xy 1.292265 -282.345402) (xy 1.2778 -282.386215) (xy 1.270465 -282.42889)
			(xy 1.27 -282.45054) (xy 1.27 -282.705403) (xy 3.314946 -282.705403) (xy 3.314946 -282.634081) (xy 3.322932 -282.563207)
			(xy 3.338802 -282.493672) (xy 3.362359 -282.426352) (xy 3.393304 -282.362093) (xy 3.43125 -282.301702)
			(xy 3.475719 -282.24594) (xy 3.526152 -282.195507) (xy 3.581914 -282.151038) (xy 3.642305 -282.113092)
			(xy 3.706564 -282.082147) (xy 3.773884 -282.05859) (xy 3.843419 -282.04272) (xy 3.914293 -282.034734)
			(xy 3.985615 -282.034734) (xy 4.056489 -282.04272) (xy 4.126024 -282.05859) (xy 4.193344 -282.082147)
			(xy 4.257603 -282.113092) (xy 4.317994 -282.151038) (xy 4.373756 -282.195507) (xy 4.424189 -282.24594)
			(xy 4.468658 -282.301702) (xy 4.506604 -282.362093) (xy 4.537549 -282.426352) (xy 4.561106 -282.493672)
			(xy 4.576976 -282.563207) (xy 4.584962 -282.634081) (xy 4.585462 -282.669742) (xy 4.584962 -282.705403)
			(xy 4.576976 -282.776277) (xy 4.561106 -282.845812) (xy 4.537549 -282.913132) (xy 4.506604 -282.977391)
			(xy 4.468658 -283.037782) (xy 4.424189 -283.093544) (xy 4.373756 -283.143977) (xy 4.317994 -283.188446)
			(xy 4.257603 -283.226392) (xy 4.193344 -283.257337) (xy 4.126024 -283.280894) (xy 4.056489 -283.296764)
			(xy 3.985615 -283.30475) (xy 3.914293 -283.30475) (xy 3.843419 -283.296764) (xy 3.773884 -283.280894)
			(xy 3.706564 -283.257337) (xy 3.642305 -283.226392) (xy 3.581914 -283.188446) (xy 3.526152 -283.143977)
			(xy 3.475719 -283.093544) (xy 3.43125 -283.037782) (xy 3.393304 -282.977391) (xy 3.362359 -282.913132)
			(xy 3.338802 -282.845812) (xy 3.322932 -282.776277) (xy 3.314946 -282.705403) (xy 1.27 -282.705403)
			(xy 1.27 -282.888944) (xy 1.270438 -282.910594) (xy 1.277779 -282.953268) (xy 1.292249 -282.994079)
			(xy 1.313428 -283.031846) (xy 1.340704 -283.065476) (xy 1.373285 -283.093995) (xy 1.410231 -283.116578)
			(xy 1.450469 -283.132571) (xy 1.492837 -283.14151) (xy 1.536107 -283.143137) (xy 1.579026 -283.137405)
			(xy 1.620352 -283.124479) (xy 1.639824 -283.115004) (xy 1.671264 -283.097984) (xy 1.737191 -283.070319)
			(xy 1.805806 -283.050227) (xy 1.876243 -283.037963) (xy 1.947611 -283.033681) (xy 2.019008 -283.037436)
			(xy 2.089533 -283.049179) (xy 2.158295 -283.068763) (xy 2.224425 -283.095941) (xy 2.287086 -283.130368)
			(xy 2.345488 -283.17161) (xy 2.398893 -283.219146) (xy 2.446626 -283.272374) (xy 2.488083 -283.330624)
			(xy 2.522742 -283.393158) (xy 2.550163 -283.459187) (xy 2.570001 -283.527875) (xy 2.582005 -283.598357)
			(xy 2.586023 -283.66974) (xy 2.582005 -283.741123) (xy 2.570001 -283.811605) (xy 2.550163 -283.880293)
			(xy 2.522742 -283.946322) (xy 2.488083 -284.008856) (xy 2.446626 -284.067106) (xy 2.398893 -284.120334)
			(xy 2.345488 -284.16787) (xy 2.287086 -284.209112) (xy 2.224425 -284.243539) (xy 2.158295 -284.270717)
			(xy 2.089533 -284.290301) (xy 2.019008 -284.302044) (xy 1.947611 -284.305799) (xy 1.876243 -284.301517)
			(xy 1.805806 -284.289253) (xy 1.737191 -284.269161) (xy 1.671264 -284.241496) (xy 1.639824 -284.224476)
			(xy 1.620357 -284.214992) (xy 1.579031 -284.202064) (xy 1.536112 -284.196331) (xy 1.492842 -284.197957)
			(xy 1.450474 -284.206897) (xy 1.410235 -284.22289) (xy 1.373291 -284.245475) (xy 1.340711 -284.273996)
			(xy 1.313438 -284.307628) (xy 1.292263 -284.345398) (xy 1.277798 -284.386211) (xy 1.270462 -284.428886)
			(xy 1.27 -284.450536) (xy 1.27 -284.88894) (xy 1.270438 -284.91059) (xy 1.277779 -284.953264) (xy 1.292248 -284.994076)
			(xy 1.313427 -285.031844) (xy 1.340702 -285.065475) (xy 1.373284 -285.093995) (xy 1.41023 -285.116578)
			(xy 1.450469 -285.13257) (xy 1.492837 -285.14151) (xy 1.536107 -285.143137) (xy 1.579027 -285.137405)
			(xy 1.620354 -285.124479) (xy 1.639824 -285.115) (xy 1.672623 -285.097274) (xy 1.741511 -285.068755)
			(xy 1.813263 -285.048492) (xy 1.886893 -285.036765) (xy 1.96139 -285.033735) (xy 2.035729 -285.039443)
			(xy 2.10889 -285.05381) (xy 2.179867 -285.07664) (xy 2.247684 -285.107619) (xy 2.311411 -285.14632)
			(xy 2.341118 -285.168848) (xy 2.364676 -285.187695) (xy 2.408499 -285.229167) (xy 2.448199 -285.274601)
			(xy 2.466086 -285.298896) (xy 2.475226 -285.310871) (xy 2.498062 -285.330508) (xy 2.52487 -285.344233)
			(xy 2.554151 -285.35128) (xy 2.56921 -285.351728) (xy 3.170174 -285.351728) (xy 3.192127 -285.351275)
			(xy 3.235381 -285.343745) (xy 3.276695 -285.328887) (xy 3.314839 -285.307146) (xy 3.348674 -285.279167)
			(xy 3.377193 -285.245786) (xy 3.399546 -285.207998) (xy 3.415066 -285.166927) (xy 3.423291 -285.1238)
			(xy 3.423975 -285.079901) (xy 3.417099 -285.036538) (xy 3.402867 -284.995004) (xy 3.392678 -284.975554)
			(xy 3.37675 -284.945584) (xy 3.350652 -284.882927) (xy 3.331377 -284.817847) (xy 3.319147 -284.751084)
			(xy 3.314099 -284.683397) (xy 3.316292 -284.615558) (xy 3.3257 -284.548339) (xy 3.333496 -284.515306)
			(xy 3.342528 -284.481254) (xy 3.367124 -284.415235) (xy 3.398873 -284.352342) (xy 3.437384 -284.293347)
			(xy 3.482185 -284.238975) (xy 3.532727 -284.189893) (xy 3.588388 -284.146703) (xy 3.648486 -284.109937)
			(xy 3.712282 -284.080044) (xy 3.745484 -284.068266) (xy 3.780793 -284.056804) (xy 3.853383 -284.041244)
			(xy 3.927293 -284.03426) (xy 4.001513 -284.035946) (xy 4.038346 -284.04058) (xy 4.041902 -284.041342)
			(xy 4.05003 -284.042612) (xy 4.067048 -284.043628) (xy 4.084879 -284.043994) (xy 4.119625 -284.036012)
			(xy 4.150816 -284.018746) (xy 4.163822 -284.006544) (xy 4.52755 -283.642816) (xy 4.966208 -283.204412)
			(xy 5.626862 -283.204412) (xy 5.649407 -283.202016) (xy 5.693192 -283.190274) (xy 5.734207 -283.170964)
			(xy 5.771155 -283.144697) (xy 5.802868 -283.112303) (xy 5.828345 -283.074807) (xy 5.84678 -283.033392)
			(xy 5.857592 -282.989367) (xy 5.860437 -282.944123) (xy 5.855227 -282.899091) (xy 5.849112 -282.87726)
			(xy 5.83796 -282.84346) (xy 5.822382 -282.774008) (xy 5.814661 -282.70325) (xy 5.814894 -282.632072)
			(xy 5.823079 -282.561366) (xy 5.839112 -282.492018) (xy 5.862794 -282.424895) (xy 5.893827 -282.360838)
			(xy 5.931822 -282.30065) (xy 5.976305 -282.245084) (xy 6.026718 -282.194836) (xy 6.082429 -282.150536)
			(xy 6.142742 -282.112737) (xy 6.2069 -282.081914) (xy 6.2741 -282.058453) (xy 6.343501 -282.042647)
			(xy 6.414233 -282.034694) (xy 6.485411 -282.034694) (xy 6.556143 -282.042647) (xy 6.625544 -282.058453)
			(xy 6.692744 -282.081914) (xy 6.756902 -282.112737) (xy 6.817215 -282.150536) (xy 6.872926 -282.194836)
			(xy 6.923339 -282.245084) (xy 6.967822 -282.30065) (xy 7.005817 -282.360838) (xy 7.03685 -282.424895)
			(xy 7.060532 -282.492018) (xy 7.076565 -282.561366) (xy 7.08475 -282.632072) (xy 7.084983 -282.70325)
			(xy 7.077262 -282.774008) (xy 7.061684 -282.84346) (xy 7.050532 -282.87726) (xy 7.04444 -282.899101)
			(xy 7.039203 -282.944136) (xy 7.042029 -282.989386) (xy 7.052827 -283.033419) (xy 7.071257 -283.074843)
			(xy 7.096735 -283.112345) (xy 7.128454 -283.14474) (xy 7.165411 -283.171003) (xy 7.206437 -283.190301)
			(xy 7.250233 -283.202025) (xy 7.272782 -283.204412) (xy 7.401814 -283.204412) (xy 7.504684 -283.307028)
			(xy 7.548372 -283.350716) (xy 7.564559 -283.364795) (xy 7.600724 -283.387868) (xy 7.640251 -283.404537)
			(xy 7.682016 -283.414328) (xy 7.724833 -283.416964) (xy 7.767484 -283.412368) (xy 7.808757 -283.400673)
			(xy 7.847478 -283.38221) (xy 7.882547 -283.357504) (xy 7.912967 -283.327257) (xy 7.925816 -283.310076)
			(xy 7.944467 -283.283617) (xy 7.986343 -283.234246) (xy 8.033021 -283.189388) (xy 8.084019 -283.14951)
			(xy 8.138808 -283.115023) (xy 8.167624 -283.100272) (xy 8.199441 -283.085042) (xy 8.26573 -283.060915)
			(xy 8.334283 -283.044278) (xy 8.404257 -283.035333) (xy 8.474791 -283.034192) (xy 8.545017 -283.040868)
			(xy 8.614073 -283.055279) (xy 8.681108 -283.077247) (xy 8.745298 -283.106504) (xy 8.805854 -283.142688)
			(xy 8.862031 -283.185355) (xy 8.913138 -283.23398) (xy 8.958547 -283.287964) (xy 8.997699 -283.346645)
			(xy 9.030112 -283.409301) (xy 9.049598 -283.460073) (xy 28.093141 -283.460073) (xy 28.093141 -283.396807)
			(xy 28.101399 -283.334083) (xy 28.117773 -283.272974) (xy 28.141984 -283.214524) (xy 28.173617 -283.159735)
			(xy 28.21213 -283.109543) (xy 28.256865 -283.064808) (xy 28.307057 -283.026295) (xy 28.361846 -282.994662)
			(xy 28.420296 -282.970451) (xy 28.481405 -282.954077) (xy 28.544129 -282.945819) (xy 28.607395 -282.945819)
			(xy 28.670119 -282.954077) (xy 28.731228 -282.970451) (xy 28.789678 -282.994662) (xy 28.844467 -283.026295)
			(xy 28.894659 -283.064808) (xy 28.917392 -283.08681) (xy 29.060902 -283.23032) (xy 29.369004 -283.23032)
			(xy 29.39199 -283.229782) (xy 29.437209 -283.221494) (xy 29.4802 -283.205207) (xy 29.51956 -283.181453)
			(xy 29.554005 -283.151006) (xy 29.582412 -283.11486) (xy 29.603853 -283.074194) (xy 29.61763 -283.030334)
			(xy 29.623292 -282.984712) (xy 29.620656 -282.938815) (xy 29.609807 -282.894141) (xy 29.600906 -282.872942)
			(xy 29.583621 -282.832985) (xy 29.555658 -282.750531) (xy 29.535436 -282.665846) (xy 29.52313 -282.579654)
			(xy 29.518844 -282.492694) (xy 29.522615 -282.405709) (xy 29.534411 -282.319446) (xy 29.554131 -282.234643)
			(xy 29.581606 -282.152025) (xy 29.616601 -282.072301) (xy 29.658815 -281.996154) (xy 29.707888 -281.924235)
			(xy 29.763399 -281.85716) (xy 29.824873 -281.795504) (xy 29.891783 -281.739795) (xy 29.963557 -281.690509)
			(xy 30.039579 -281.64807) (xy 30.119199 -281.61284) (xy 30.201734 -281.585121) (xy 30.286479 -281.56515)
			(xy 30.372707 -281.553099) (xy 30.45968 -281.54907) (xy 30.546653 -281.553099) (xy 30.632881 -281.56515)
			(xy 30.717626 -281.585121) (xy 30.800161 -281.61284) (xy 30.879781 -281.64807) (xy 30.955803 -281.690509)
			(xy 31.027577 -281.739795) (xy 31.094487 -281.795504) (xy 31.155961 -281.85716) (xy 31.211472 -281.924235)
			(xy 31.260545 -281.996154) (xy 31.302759 -282.072301) (xy 31.337754 -282.152025) (xy 31.365229 -282.234643)
			(xy 31.384949 -282.319446) (xy 31.396745 -282.405709) (xy 31.400516 -282.492694) (xy 31.398512 -282.53336)
			(xy 34.599874 -282.53336) (xy 34.599874 -282.44646) (xy 34.607892 -282.359931) (xy 34.62386 -282.274511)
			(xy 34.647641 -282.190929) (xy 34.679033 -282.109897) (xy 34.717767 -282.032108) (xy 34.763514 -281.958224)
			(xy 34.815883 -281.888877) (xy 34.874427 -281.824657) (xy 34.938647 -281.766113) (xy 35.007994 -281.713744)
			(xy 35.081878 -281.667997) (xy 35.159667 -281.629263) (xy 35.240699 -281.597871) (xy 35.324281 -281.57409)
			(xy 35.409701 -281.558122) (xy 35.49623 -281.550104) (xy 35.58313 -281.550104) (xy 35.669659 -281.558122)
			(xy 35.755079 -281.57409) (xy 35.838661 -281.597871) (xy 35.919693 -281.629263) (xy 35.997482 -281.667997)
			(xy 36.071366 -281.713744) (xy 36.140713 -281.766113) (xy 36.204933 -281.824657) (xy 36.216998 -281.837892)
			(xy 85.345268 -281.837892) (xy 85.349339 -281.78227) (xy 85.361465 -281.727833) (xy 85.381388 -281.675742)
			(xy 85.408684 -281.627107) (xy 85.44277 -281.582964) (xy 85.482919 -281.544255) (xy 85.528277 -281.511804)
			(xy 85.577877 -281.486303) (xy 85.630661 -281.468296) (xy 85.685504 -281.458166) (xy 85.741238 -281.456129)
			(xy 85.796675 -281.462229) (xy 85.850632 -281.476335) (xy 85.901961 -281.498147) (xy 85.949567 -281.527201)
			(xy 85.992435 -281.562876) (xy 86.029652 -281.604413) (xy 86.060425 -281.650926) (xy 86.084097 -281.701423)
			(xy 86.100165 -281.75483) (xy 86.108285 -281.810006) (xy 86.108794 -281.837892) (xy 86.108285 -281.865778)
			(xy 86.100165 -281.920954) (xy 86.084097 -281.974361) (xy 86.060425 -282.024858) (xy 86.029652 -282.071371)
			(xy 85.992435 -282.112908) (xy 85.949567 -282.148583) (xy 85.901961 -282.177637) (xy 85.850632 -282.199449)
			(xy 85.796675 -282.213555) (xy 85.741238 -282.219655) (xy 85.685504 -282.217618) (xy 85.630661 -282.207488)
			(xy 85.577877 -282.189481) (xy 85.528277 -282.16398) (xy 85.482919 -282.131529) (xy 85.44277 -282.09282)
			(xy 85.408684 -282.048677) (xy 85.381388 -282.000042) (xy 85.361465 -281.947951) (xy 85.349339 -281.893514)
			(xy 85.345268 -281.837892) (xy 36.216998 -281.837892) (xy 36.263477 -281.888877) (xy 36.315846 -281.958224)
			(xy 36.361593 -282.032108) (xy 36.400327 -282.109897) (xy 36.431719 -282.190929) (xy 36.4555 -282.274511)
			(xy 36.471468 -282.359931) (xy 36.479486 -282.44646) (xy 36.479988 -282.48991) (xy 36.479486 -282.53336)
			(xy 36.471468 -282.619889) (xy 36.4555 -282.705309) (xy 36.431719 -282.788891) (xy 36.400327 -282.869923)
			(xy 36.361593 -282.947712) (xy 36.315846 -283.021596) (xy 36.263477 -283.090943) (xy 36.204933 -283.155163)
			(xy 36.140713 -283.213707) (xy 36.071366 -283.266076) (xy 35.997482 -283.311823) (xy 35.919693 -283.350557)
			(xy 35.838661 -283.381949) (xy 35.755079 -283.40573) (xy 35.669659 -283.421698) (xy 35.58313 -283.429716)
			(xy 35.49623 -283.429716) (xy 35.409701 -283.421698) (xy 35.324281 -283.40573) (xy 35.240699 -283.381949)
			(xy 35.159667 -283.350557) (xy 35.081878 -283.311823) (xy 35.007994 -283.266076) (xy 34.938647 -283.213707)
			(xy 34.874427 -283.155163) (xy 34.815883 -283.090943) (xy 34.763514 -283.021596) (xy 34.717767 -282.947712)
			(xy 34.679033 -282.869923) (xy 34.647641 -282.788891) (xy 34.62386 -282.705309) (xy 34.607892 -282.619889)
			(xy 34.599874 -282.53336) (xy 31.398512 -282.53336) (xy 31.39623 -282.579654) (xy 31.383924 -282.665846)
			(xy 31.363702 -282.750531) (xy 31.335739 -282.832985) (xy 31.318454 -282.872942) (xy 31.309503 -282.894128)
			(xy 31.298627 -282.938812) (xy 31.295972 -282.984725) (xy 31.301624 -283.030365) (xy 31.315399 -283.074243)
			(xy 31.336846 -283.114925) (xy 31.365265 -283.151082) (xy 31.399728 -283.181534) (xy 31.439109 -283.205285)
			(xy 31.482122 -283.22156) (xy 31.527361 -283.229828) (xy 31.550356 -283.23032) (xy 32.213042 -283.23032)
			(xy 32.480977 -283.49829) (xy 41.410888 -283.49829) (xy 41.414959 -283.442668) (xy 41.427085 -283.388231)
			(xy 41.447008 -283.33614) (xy 41.474304 -283.287505) (xy 41.50839 -283.243362) (xy 41.548539 -283.204653)
			(xy 41.593897 -283.172202) (xy 41.643497 -283.146701) (xy 41.696281 -283.128694) (xy 41.751124 -283.118564)
			(xy 41.806858 -283.116527) (xy 41.862295 -283.122627) (xy 41.916252 -283.136733) (xy 41.967581 -283.158545)
			(xy 42.015187 -283.187599) (xy 42.058055 -283.223274) (xy 42.095272 -283.264811) (xy 42.126045 -283.311324)
			(xy 42.149717 -283.361821) (xy 42.165785 -283.415228) (xy 42.173905 -283.470404) (xy 42.174414 -283.49829)
			(xy 42.173905 -283.526176) (xy 42.165785 -283.581352) (xy 42.149717 -283.634759) (xy 42.126045 -283.685256)
			(xy 42.095272 -283.731769) (xy 42.058055 -283.773306) (xy 42.015187 -283.808981) (xy 41.967581 -283.838035)
			(xy 41.916252 -283.859847) (xy 41.862295 -283.873953) (xy 41.806858 -283.880053) (xy 41.751124 -283.878016)
			(xy 41.696281 -283.867886) (xy 41.643497 -283.849879) (xy 41.593897 -283.824378) (xy 41.548539 -283.791927)
			(xy 41.50839 -283.753218) (xy 41.474304 -283.709075) (xy 41.447008 -283.66044) (xy 41.427085 -283.608349)
			(xy 41.414959 -283.553912) (xy 41.410888 -283.49829) (xy 32.480977 -283.49829) (xy 34.166048 -285.18358)
			(xy 34.182495 -285.199418) (xy 34.220015 -285.225433) (xy 34.261579 -285.244327) (xy 34.305851 -285.255491)
			(xy 34.351404 -285.258565) (xy 34.396774 -285.253452) (xy 34.4405 -285.240316) (xy 34.481176 -285.219579)
			(xy 34.517493 -285.191909) (xy 34.548283 -285.158196) (xy 34.572553 -285.119524) (xy 34.589525 -285.077138)
			(xy 34.598651 -285.032403) (xy 34.599626 -285.00959) (xy 34.60107 -284.965856) (xy 34.611079 -284.878919)
			(xy 34.629122 -284.793289) (xy 34.655043 -284.709705) (xy 34.688618 -284.628891) (xy 34.729556 -284.551547)
			(xy 34.777503 -284.47834) (xy 34.832045 -284.409906) (xy 34.892709 -284.346834) (xy 34.958971 -284.289672)
			(xy 35.030257 -284.238914) (xy 35.105951 -284.194998) (xy 35.185397 -284.158306) (xy 35.26791 -284.129153)
			(xy 35.352773 -284.107793) (xy 35.439255 -284.09441) (xy 35.526606 -284.089121) (xy 35.61407 -284.09197)
			(xy 35.700891 -284.102933) (xy 35.786318 -284.121915) (xy 35.869612 -284.148753) (xy 35.950052 -284.183213)
			(xy 36.026942 -284.224998) (xy 36.099618 -284.273747) (xy 36.16745 -284.329037) (xy 36.229851 -284.39039)
			(xy 36.286282 -284.457275) (xy 36.336254 -284.529115) (xy 36.379336 -284.605286) (xy 36.415154 -284.685131)
			(xy 36.443398 -284.767959) (xy 36.463825 -284.853052) (xy 36.476257 -284.939675) (xy 36.480587 -285.027079)
			(xy 36.476777 -285.114506) (xy 36.464861 -285.201202) (xy 36.454394 -285.245979) (xy 47.75199 -285.245979)
			(xy 47.75199 -285.164869) (xy 47.75994 -285.08415) (xy 47.775763 -285.004599) (xy 47.799308 -284.926983)
			(xy 47.830347 -284.852047) (xy 47.868582 -284.780515) (xy 47.913644 -284.713075) (xy 47.965099 -284.650376)
			(xy 48.022452 -284.593023) (xy 48.085151 -284.541568) (xy 48.152591 -284.496506) (xy 48.224123 -284.458271)
			(xy 48.299059 -284.427232) (xy 48.376675 -284.403687) (xy 48.456226 -284.387864) (xy 48.536945 -284.379914)
			(xy 48.618055 -284.379914) (xy 48.698774 -284.387864) (xy 48.778325 -284.403687) (xy 48.855941 -284.427232)
			(xy 48.930877 -284.458271) (xy 49.002409 -284.496506) (xy 49.069849 -284.541568) (xy 49.132548 -284.593023)
			(xy 49.189901 -284.650376) (xy 49.241356 -284.713075) (xy 49.286418 -284.780515) (xy 49.324653 -284.852047)
			(xy 49.355692 -284.926983) (xy 49.379237 -285.004599) (xy 49.39506 -285.08415) (xy 49.40301 -285.164869)
			(xy 49.403508 -285.205424) (xy 49.40301 -285.245979) (xy 51.25211 -285.245979) (xy 51.25211 -285.164869)
			(xy 51.26006 -285.08415) (xy 51.275883 -285.004599) (xy 51.299428 -284.926983) (xy 51.330467 -284.852047)
			(xy 51.368702 -284.780515) (xy 51.413764 -284.713075) (xy 51.465219 -284.650376) (xy 51.522572 -284.593023)
			(xy 51.585271 -284.541568) (xy 51.652711 -284.496506) (xy 51.724243 -284.458271) (xy 51.799179 -284.427232)
			(xy 51.876795 -284.403687) (xy 51.956346 -284.387864) (xy 52.037065 -284.379914) (xy 52.118175 -284.379914)
			(xy 52.198894 -284.387864) (xy 52.278445 -284.403687) (xy 52.356061 -284.427232) (xy 52.430997 -284.458271)
			(xy 52.502529 -284.496506) (xy 52.569969 -284.541568) (xy 52.632668 -284.593023) (xy 52.690021 -284.650376)
			(xy 52.741476 -284.713075) (xy 52.770732 -284.75686) (xy 83.181188 -284.75686) (xy 83.185259 -284.701238)
			(xy 83.197385 -284.646801) (xy 83.217308 -284.59471) (xy 83.244604 -284.546075) (xy 83.27869 -284.501932)
			(xy 83.318839 -284.463223) (xy 83.364197 -284.430772) (xy 83.413797 -284.405271) (xy 83.466581 -284.387264)
			(xy 83.521424 -284.377134) (xy 83.577158 -284.375097) (xy 83.632595 -284.381197) (xy 83.686552 -284.395303)
			(xy 83.737881 -284.417115) (xy 83.785487 -284.446169) (xy 83.828355 -284.481844) (xy 83.865572 -284.523381)
			(xy 83.896345 -284.569894) (xy 83.920017 -284.620391) (xy 83.936085 -284.673798) (xy 83.944205 -284.728974)
			(xy 83.944714 -284.75686) (xy 83.944205 -284.784746) (xy 83.936085 -284.839922) (xy 83.920017 -284.893329)
			(xy 83.896345 -284.943826) (xy 83.865572 -284.990339) (xy 83.828355 -285.031876) (xy 83.785487 -285.067551)
			(xy 83.737881 -285.096605) (xy 83.686552 -285.118417) (xy 83.632595 -285.132523) (xy 83.577158 -285.138623)
			(xy 83.521424 -285.136586) (xy 83.466581 -285.126456) (xy 83.413797 -285.108449) (xy 83.364197 -285.082948)
			(xy 83.318839 -285.050497) (xy 83.27869 -285.011788) (xy 83.244604 -284.967645) (xy 83.217308 -284.91901)
			(xy 83.197385 -284.866919) (xy 83.185259 -284.812482) (xy 83.181188 -284.75686) (xy 52.770732 -284.75686)
			(xy 52.786538 -284.780515) (xy 52.824773 -284.852047) (xy 52.855812 -284.926983) (xy 52.879357 -285.004599)
			(xy 52.89518 -285.08415) (xy 52.90313 -285.164869) (xy 52.903628 -285.205424) (xy 52.90313 -285.245979)
			(xy 52.89518 -285.326698) (xy 52.879357 -285.406249) (xy 52.855812 -285.483865) (xy 52.824773 -285.558801)
			(xy 52.786538 -285.630333) (xy 52.741476 -285.697773) (xy 52.690021 -285.760472) (xy 52.632668 -285.817825)
			(xy 52.569969 -285.86928) (xy 52.502529 -285.914342) (xy 52.430997 -285.952577) (xy 52.356061 -285.983616)
			(xy 52.278445 -286.007161) (xy 52.198894 -286.022984) (xy 52.118175 -286.030934) (xy 52.037065 -286.030934)
			(xy 51.956346 -286.022984) (xy 51.876795 -286.007161) (xy 51.799179 -285.983616) (xy 51.724243 -285.952577)
			(xy 51.652711 -285.914342) (xy 51.585271 -285.86928) (xy 51.522572 -285.817825) (xy 51.465219 -285.760472)
			(xy 51.413764 -285.697773) (xy 51.368702 -285.630333) (xy 51.330467 -285.558801) (xy 51.299428 -285.483865)
			(xy 51.275883 -285.406249) (xy 51.26006 -285.326698) (xy 51.25211 -285.245979) (xy 49.40301 -285.245979)
			(xy 49.39506 -285.326698) (xy 49.379237 -285.406249) (xy 49.355692 -285.483865) (xy 49.324653 -285.558801)
			(xy 49.286418 -285.630333) (xy 49.241356 -285.697773) (xy 49.189901 -285.760472) (xy 49.132548 -285.817825)
			(xy 49.069849 -285.86928) (xy 49.002409 -285.914342) (xy 48.930877 -285.952577) (xy 48.855941 -285.983616)
			(xy 48.778325 -286.007161) (xy 48.698774 -286.022984) (xy 48.618055 -286.030934) (xy 48.536945 -286.030934)
			(xy 48.456226 -286.022984) (xy 48.376675 -286.007161) (xy 48.299059 -285.983616) (xy 48.224123 -285.952577)
			(xy 48.152591 -285.914342) (xy 48.085151 -285.86928) (xy 48.022452 -285.817825) (xy 47.965099 -285.760472)
			(xy 47.913644 -285.697773) (xy 47.868582 -285.630333) (xy 47.830347 -285.558801) (xy 47.799308 -285.483865)
			(xy 47.775763 -285.406249) (xy 47.75994 -285.326698) (xy 47.75199 -285.245979) (xy 36.454394 -285.245979)
			(xy 36.444942 -285.286415) (xy 36.417191 -285.36941) (xy 36.399978 -285.40964) (xy 36.391151 -285.430836)
			(xy 36.380461 -285.475486) (xy 36.377964 -285.52133) (xy 36.38374 -285.566877) (xy 36.397603 -285.610646)
			(xy 36.419101 -285.651213) (xy 36.447535 -285.68726) (xy 36.481981 -285.717615) (xy 36.521318 -285.741289)
			(xy 36.564267 -285.757514) (xy 36.609432 -285.765762) (xy 36.632388 -285.766256) (xy 37.486844 -285.766256)
			(xy 37.942012 -285.311088) (xy 40.571166 -285.311088) (xy 41.357733 -286.097472) (xy 82.563714 -286.097472)
			(xy 82.567785 -286.04185) (xy 82.579911 -285.987413) (xy 82.599834 -285.935322) (xy 82.62713 -285.886687)
			(xy 82.661216 -285.842544) (xy 82.701365 -285.803835) (xy 82.746723 -285.771384) (xy 82.796323 -285.745883)
			(xy 82.849107 -285.727876) (xy 82.90395 -285.717746) (xy 82.959684 -285.715709) (xy 83.015121 -285.721809)
			(xy 83.069078 -285.735915) (xy 83.120407 -285.757727) (xy 83.168013 -285.786781) (xy 83.210881 -285.822456)
			(xy 83.248098 -285.863993) (xy 83.278871 -285.910506) (xy 83.302543 -285.961003) (xy 83.318611 -286.01441)
			(xy 83.326731 -286.069586) (xy 83.32724 -286.097472) (xy 83.326731 -286.125358) (xy 83.318611 -286.180534)
			(xy 83.302543 -286.233941) (xy 83.278871 -286.284438) (xy 83.248098 -286.330951) (xy 83.210881 -286.372488)
			(xy 83.168013 -286.408163) (xy 83.120407 -286.437217) (xy 83.069078 -286.459029) (xy 83.015121 -286.473135)
			(xy 82.959684 -286.479235) (xy 82.90395 -286.477198) (xy 82.849107 -286.467068) (xy 82.796323 -286.449061)
			(xy 82.746723 -286.42356) (xy 82.701365 -286.391109) (xy 82.661216 -286.3524) (xy 82.62713 -286.308257)
			(xy 82.599834 -286.259622) (xy 82.579911 -286.207531) (xy 82.567785 -286.153094) (xy 82.563714 -286.097472)
			(xy 41.357733 -286.097472) (xy 41.660572 -286.40024) (xy 51.563524 -286.40024) (xy 51.873142 -286.709866)
			(xy 86.877404 -286.709866) (xy 86.881424 -286.519215) (xy 86.893478 -286.328902) (xy 86.913544 -286.139267)
			(xy 86.941587 -285.950646) (xy 86.977556 -285.763376) (xy 87.021388 -285.577788) (xy 87.073005 -285.394213)
			(xy 87.132315 -285.212977) (xy 87.199213 -285.034402) (xy 87.273579 -284.858807) (xy 87.355281 -284.686502)
			(xy 87.444175 -284.517795) (xy 87.540101 -284.352985) (xy 87.64289 -284.192366) (xy 87.752359 -284.036223)
			(xy 87.868313 -283.884834) (xy 87.990547 -283.738467) (xy 88.118841 -283.597383) (xy 88.252969 -283.461834)
			(xy 88.392693 -283.332059) (xy 88.537763 -283.208289) (xy 88.687921 -283.090746) (xy 88.842902 -282.979637)
			(xy 89.002429 -282.87516) (xy 89.166218 -282.777501) (xy 89.333978 -282.686834) (xy 89.505412 -282.60332)
			(xy 89.680214 -282.527107) (xy 89.858073 -282.458331) (xy 90.038674 -282.397113) (xy 90.221694 -282.343564)
			(xy 90.40681 -282.297778) (xy 90.593691 -282.259836) (xy 90.782006 -282.229807) (xy 90.971419 -282.207742)
			(xy 91.161593 -282.193683) (xy 91.352192 -282.187653) (xy 91.542875 -282.189663) (xy 91.733304 -282.19971)
			(xy 91.92314 -282.217776) (xy 92.112046 -282.243829) (xy 92.299685 -282.277822) (xy 92.485725 -282.319695)
			(xy 92.669834 -282.369374) (xy 92.851685 -282.42677) (xy 93.030955 -282.491781) (xy 93.207325 -282.564292)
			(xy 93.380481 -282.644173) (xy 93.550116 -282.731283) (xy 93.715928 -282.825467) (xy 93.877622 -282.926558)
			(xy 94.03491 -283.034374) (xy 94.187513 -283.148726) (xy 94.335161 -283.269409) (xy 94.477589 -283.39621)
			(xy 94.614545 -283.528901) (xy 94.745786 -283.667249) (xy 94.871078 -283.811006) (xy 94.990198 -283.959917)
			(xy 95.102934 -284.113718) (xy 95.209087 -284.272134) (xy 95.308467 -284.434885) (xy 95.400897 -284.60168)
			(xy 95.486214 -284.772224) (xy 95.564266 -284.946212) (xy 95.634913 -285.123337) (xy 95.698031 -285.303282)
			(xy 95.753507 -285.485728) (xy 95.801242 -285.670351) (xy 95.841152 -285.856821) (xy 95.873165 -286.044809)
			(xy 95.897225 -286.233979) (xy 95.913288 -286.423995) (xy 95.921327 -286.614519) (xy 95.92183 -286.709866)
			(xy 95.921327 -286.805213) (xy 95.913288 -286.995737) (xy 95.897225 -287.185753) (xy 95.873165 -287.374923)
			(xy 95.841152 -287.562911) (xy 95.801242 -287.749381) (xy 95.753507 -287.934004) (xy 95.698031 -288.11645)
			(xy 95.634913 -288.296395) (xy 95.564266 -288.47352) (xy 95.486214 -288.647508) (xy 95.400897 -288.818052)
			(xy 95.308467 -288.984847) (xy 95.209087 -289.147598) (xy 95.102934 -289.306014) (xy 94.990198 -289.459815)
			(xy 94.871078 -289.608726) (xy 94.745786 -289.752483) (xy 94.614545 -289.890831) (xy 94.477589 -290.023522)
			(xy 94.335161 -290.150323) (xy 94.187513 -290.271006) (xy 94.03491 -290.385358) (xy 93.877622 -290.493174)
			(xy 93.715928 -290.594265) (xy 93.550116 -290.688449) (xy 93.380481 -290.775559) (xy 93.207325 -290.85544)
			(xy 93.030955 -290.927951) (xy 92.851685 -290.992962) (xy 92.669834 -291.050358) (xy 92.485725 -291.100037)
			(xy 92.299685 -291.14191) (xy 92.112046 -291.175903) (xy 91.92314 -291.201956) (xy 91.733304 -291.220022)
			(xy 91.542875 -291.230069) (xy 91.352192 -291.232079) (xy 91.161593 -291.226049) (xy 90.971419 -291.21199)
			(xy 90.782006 -291.189925) (xy 90.593691 -291.159896) (xy 90.40681 -291.121954) (xy 90.221694 -291.076168)
			(xy 90.038674 -291.022619) (xy 89.858073 -290.961401) (xy 89.680214 -290.892625) (xy 89.505412 -290.816412)
			(xy 89.333978 -290.732898) (xy 89.166218 -290.642231) (xy 89.002429 -290.544572) (xy 88.842902 -290.440095)
			(xy 88.687921 -290.328986) (xy 88.537763 -290.211443) (xy 88.392693 -290.087673) (xy 88.252969 -289.957898)
			(xy 88.118841 -289.822349) (xy 87.990547 -289.681265) (xy 87.868313 -289.534898) (xy 87.752359 -289.383509)
			(xy 87.64289 -289.227366) (xy 87.540101 -289.066747) (xy 87.444175 -288.901937) (xy 87.355281 -288.73323)
			(xy 87.273579 -288.560925) (xy 87.199213 -288.38533) (xy 87.132315 -288.206755) (xy 87.073005 -288.025519)
			(xy 87.021388 -287.841944) (xy 86.977556 -287.656356) (xy 86.941587 -287.469086) (xy 86.913544 -287.280465)
			(xy 86.893478 -287.09083) (xy 86.881424 -286.900517) (xy 86.877404 -286.709866) (xy 51.873142 -286.709866)
			(xy 52.474343 -287.311084) (xy 72.817734 -287.311084) (xy 72.821805 -287.255462) (xy 72.833931 -287.201025)
			(xy 72.853854 -287.148934) (xy 72.88115 -287.100299) (xy 72.915236 -287.056156) (xy 72.955385 -287.017447)
			(xy 73.000743 -286.984996) (xy 73.050343 -286.959495) (xy 73.103127 -286.941488) (xy 73.15797 -286.931358)
			(xy 73.213704 -286.929321) (xy 73.269141 -286.935421) (xy 73.323098 -286.949527) (xy 73.374427 -286.971339)
			(xy 73.422033 -287.000393) (xy 73.464901 -287.036068) (xy 73.502118 -287.077605) (xy 73.532891 -287.124118)
			(xy 73.556563 -287.174615) (xy 73.572631 -287.228022) (xy 73.580751 -287.283198) (xy 73.58126 -287.311084)
			(xy 73.963274 -287.311084) (xy 73.967345 -287.255462) (xy 73.979471 -287.201025) (xy 73.999394 -287.148934)
			(xy 74.02669 -287.100299) (xy 74.060776 -287.056156) (xy 74.100925 -287.017447) (xy 74.146283 -286.984996)
			(xy 74.195883 -286.959495) (xy 74.248667 -286.941488) (xy 74.30351 -286.931358) (xy 74.359244 -286.929321)
			(xy 74.414681 -286.935421) (xy 74.468638 -286.949527) (xy 74.519967 -286.971339) (xy 74.567573 -287.000393)
			(xy 74.610441 -287.036068) (xy 74.647658 -287.077605) (xy 74.678431 -287.124118) (xy 74.702103 -287.174615)
			(xy 74.718171 -287.228022) (xy 74.726291 -287.283198) (xy 74.7268 -287.311084) (xy 74.726291 -287.33897)
			(xy 74.718171 -287.394146) (xy 74.702103 -287.447553) (xy 74.678431 -287.49805) (xy 74.647658 -287.544563)
			(xy 74.610441 -287.5861) (xy 74.567573 -287.621775) (xy 74.519967 -287.650829) (xy 74.468638 -287.672641)
			(xy 74.414681 -287.686747) (xy 74.359244 -287.692847) (xy 74.30351 -287.69081) (xy 74.248667 -287.68068)
			(xy 74.195883 -287.662673) (xy 74.146283 -287.637172) (xy 74.100925 -287.604721) (xy 74.060776 -287.566012)
			(xy 74.02669 -287.521869) (xy 73.999394 -287.473234) (xy 73.979471 -287.421143) (xy 73.967345 -287.366706)
			(xy 73.963274 -287.311084) (xy 73.58126 -287.311084) (xy 73.580751 -287.33897) (xy 73.572631 -287.394146)
			(xy 73.556563 -287.447553) (xy 73.532891 -287.49805) (xy 73.502118 -287.544563) (xy 73.464901 -287.5861)
			(xy 73.422033 -287.621775) (xy 73.374427 -287.650829) (xy 73.323098 -287.672641) (xy 73.269141 -287.686747)
			(xy 73.213704 -287.692847) (xy 73.15797 -287.69081) (xy 73.103127 -287.68068) (xy 73.050343 -287.662673)
			(xy 73.000743 -287.637172) (xy 72.955385 -287.604721) (xy 72.915236 -287.566012) (xy 72.88115 -287.521869)
			(xy 72.853854 -287.473234) (xy 72.833931 -287.421143) (xy 72.821805 -287.366706) (xy 72.817734 -287.311084)
			(xy 52.474343 -287.311084) (xy 53.318869 -288.155634) (xy 71.489314 -288.155634) (xy 71.493385 -288.100012)
			(xy 71.505511 -288.045575) (xy 71.525434 -287.993484) (xy 71.55273 -287.944849) (xy 71.586816 -287.900706)
			(xy 71.626965 -287.861997) (xy 71.672323 -287.829546) (xy 71.721923 -287.804045) (xy 71.774707 -287.786038)
			(xy 71.82955 -287.775908) (xy 71.885284 -287.773871) (xy 71.940721 -287.779971) (xy 71.994678 -287.794077)
			(xy 72.046007 -287.815889) (xy 72.093613 -287.844943) (xy 72.136481 -287.880618) (xy 72.173698 -287.922155)
			(xy 72.204471 -287.968668) (xy 72.228143 -288.019165) (xy 72.244211 -288.072572) (xy 72.252331 -288.127748)
			(xy 72.25284 -288.155634) (xy 72.252331 -288.18352) (xy 72.244211 -288.238696) (xy 72.228143 -288.292103)
			(xy 72.204471 -288.3426) (xy 72.173698 -288.389113) (xy 72.136481 -288.43065) (xy 72.093613 -288.466325)
			(xy 72.046007 -288.495379) (xy 71.994678 -288.517191) (xy 71.940721 -288.531297) (xy 71.885284 -288.537397)
			(xy 71.82955 -288.53536) (xy 71.774707 -288.52523) (xy 71.721923 -288.507223) (xy 71.672323 -288.481722)
			(xy 71.626965 -288.449271) (xy 71.586816 -288.410562) (xy 71.55273 -288.366419) (xy 71.525434 -288.317784)
			(xy 71.505511 -288.265693) (xy 71.493385 -288.211256) (xy 71.489314 -288.155634) (xy 53.318869 -288.155634)
			(xy 60.580778 -295.417748) (xy 60.592921 -295.429106) (xy 60.621714 -295.445708) (xy 60.653822 -295.454296)
			(xy 60.67044 -295.454832) (xy 78.407006 -295.454832) (xy 78.423637 -295.454231) (xy 78.455752 -295.445559)
			(xy 78.484536 -295.428885) (xy 78.496668 -295.417494) (xy 79.040228 -294.873934) (xy 79.062961 -294.851932)
			(xy 79.113153 -294.813419) (xy 79.167942 -294.781786) (xy 79.226392 -294.757575) (xy 79.287501 -294.741201)
			(xy 79.350225 -294.732943) (xy 79.413491 -294.732943) (xy 79.476215 -294.741201) (xy 79.537324 -294.757575)
			(xy 79.595774 -294.781786) (xy 79.650563 -294.813419) (xy 79.700755 -294.851932) (xy 79.74549 -294.896667)
			(xy 79.784003 -294.946859) (xy 79.815636 -295.001648) (xy 79.839847 -295.060098) (xy 79.856221 -295.121207)
			(xy 79.864479 -295.183931) (xy 79.864479 -295.215564) (xy 82.370166 -295.215564) (xy 82.374237 -295.159942)
			(xy 82.386363 -295.105505) (xy 82.406286 -295.053414) (xy 82.433582 -295.004779) (xy 82.467668 -294.960636)
			(xy 82.507817 -294.921927) (xy 82.553175 -294.889476) (xy 82.602775 -294.863975) (xy 82.655559 -294.845968)
			(xy 82.710402 -294.835838) (xy 82.766136 -294.833801) (xy 82.821573 -294.839901) (xy 82.87553 -294.854007)
			(xy 82.926859 -294.875819) (xy 82.974465 -294.904873) (xy 83.017333 -294.940548) (xy 83.05455 -294.982085)
			(xy 83.085323 -295.028598) (xy 83.108995 -295.079095) (xy 83.125063 -295.132502) (xy 83.133183 -295.187678)
			(xy 83.133692 -295.215564) (xy 83.133183 -295.24345) (xy 83.125063 -295.298626) (xy 83.108995 -295.352033)
			(xy 83.085323 -295.40253) (xy 83.05455 -295.449043) (xy 83.017333 -295.49058) (xy 82.974465 -295.526255)
			(xy 82.926859 -295.555309) (xy 82.87553 -295.577121) (xy 82.821573 -295.591227) (xy 82.766136 -295.597327)
			(xy 82.710402 -295.59529) (xy 82.655559 -295.58516) (xy 82.602775 -295.567153) (xy 82.553175 -295.541652)
			(xy 82.507817 -295.509201) (xy 82.467668 -295.470492) (xy 82.433582 -295.426349) (xy 82.406286 -295.377714)
			(xy 82.386363 -295.325623) (xy 82.374237 -295.271186) (xy 82.370166 -295.215564) (xy 79.864479 -295.215564)
			(xy 79.864479 -295.247197) (xy 79.856221 -295.309921) (xy 79.839847 -295.37103) (xy 79.815636 -295.42948)
			(xy 79.784003 -295.484269) (xy 79.74549 -295.534461) (xy 79.723488 -295.557194) (xy 78.838298 -296.442384)
			(xy 78.82684 -296.454518) (xy 78.810136 -296.483397) (xy 78.801489 -296.515619) (xy 78.801489 -296.548981)
			(xy 78.810136 -296.581203) (xy 78.82684 -296.610082) (xy 78.838298 -296.622216) (xy 79.766922 -297.550586)
			(xy 79.788924 -297.573319) (xy 79.827437 -297.623511) (xy 79.85907 -297.6783) (xy 79.883281 -297.73675)
			(xy 79.899655 -297.797859) (xy 79.907913 -297.860583) (xy 79.907913 -297.923849) (xy 79.899655 -297.986573)
			(xy 79.883281 -298.047682) (xy 79.85907 -298.106132) (xy 79.827437 -298.160921) (xy 79.788924 -298.211113)
			(xy 79.744189 -298.255848) (xy 79.693997 -298.294361) (xy 79.639208 -298.325994) (xy 79.580758 -298.350205)
			(xy 79.519649 -298.366579) (xy 79.456925 -298.374837) (xy 79.393659 -298.374837) (xy 79.330935 -298.366579)
			(xy 79.269826 -298.350205) (xy 79.211376 -298.325994) (xy 79.156587 -298.294361) (xy 79.106395 -298.255848)
			(xy 79.083662 -298.233846) (xy 78.291182 -297.441366) (xy 78.279091 -297.42992) (xy 78.250296 -297.413224)
			(xy 78.218161 -297.404551) (xy 78.20152 -297.404028) (xy 59.810142 -297.404028) (xy 50.832766 -288.426652)
			(xy 41.21404 -288.426652) (xy 40.992044 -288.204656) (xy 40.979912 -288.193195) (xy 40.951033 -288.176486)
			(xy 40.91881 -288.167835) (xy 40.885446 -288.167835) (xy 40.853223 -288.176486) (xy 40.824344 -288.193195)
			(xy 40.812212 -288.204656) (xy 40.7797 -288.237168) (xy 40.771572 -288.328354) (xy 40.79748 -288.3662)
			(xy 40.812561 -288.389004) (xy 40.836792 -288.438011) (xy 40.85378 -288.489975) (xy 40.863177 -288.543831)
			(xy 40.864791 -288.598477) (xy 40.858587 -288.652795) (xy 40.844695 -288.70567) (xy 40.823397 -288.756021)
			(xy 40.79513 -288.802817) (xy 40.760473 -288.845098) (xy 40.720136 -288.882) (xy 40.674945 -288.912766)
			(xy 40.625825 -288.936767) (xy 40.573781 -288.953511) (xy 40.519881 -288.962654) (xy 40.465228 -288.964011)
			(xy 40.410941 -288.957552) (xy 40.358131 -288.943411) (xy 40.307881 -288.921877) (xy 40.261219 -288.89339)
			(xy 40.219101 -288.858535) (xy 40.182389 -288.818025) (xy 40.151835 -288.772689) (xy 40.128066 -288.723457)
			(xy 40.111567 -288.671336) (xy 40.102677 -288.617393) (xy 40.101577 -288.562734) (xy 40.108291 -288.508478)
			(xy 40.12268 -288.455735) (xy 40.144451 -288.405587) (xy 40.173156 -288.359059) (xy 40.208209 -288.317105)
			(xy 40.248892 -288.280584) (xy 40.29437 -288.250244) (xy 40.343714 -288.226707) (xy 40.395912 -288.210453)
			(xy 40.42283 -288.205672) (xy 40.445758 -288.201566) (xy 40.489647 -288.185972) (xy 40.529962 -288.162647)
			(xy 40.565355 -288.132368) (xy 40.594642 -288.096151) (xy 40.616842 -288.055205) (xy 40.631214 -288.010901)
			(xy 40.637277 -287.96472) (xy 40.634828 -287.918208) (xy 40.623948 -287.872919) (xy 40.605003 -287.83037)
			(xy 40.578625 -287.791982) (xy 40.56253 -287.775142) (xy 39.906194 -287.11906) (xy 39.885116 -287.097367)
			(xy 39.848013 -287.049594) (xy 39.81717 -286.997561) (xy 39.79307 -286.942081) (xy 39.776092 -286.884024)
			(xy 39.7665 -286.824302) (xy 39.764446 -286.763849) (xy 39.769961 -286.703612) (xy 39.78296 -286.644538)
			(xy 39.792656 -286.615886) (xy 39.799556 -286.594893) (xy 39.806951 -286.551334) (xy 39.806697 -286.507152)
			(xy 39.798802 -286.463681) (xy 39.783505 -286.422231) (xy 39.761267 -286.384053) (xy 39.732758 -286.350299)
			(xy 39.698839 -286.321987) (xy 39.660533 -286.29997) (xy 39.618996 -286.284914) (xy 39.575479 -286.277271)
			(xy 39.553388 -286.276796) (xy 38.342316 -286.276796) (xy 37.887148 -286.731964) (xy 36.581588 -286.731964)
			(xy 36.559547 -286.732464) (xy 36.51613 -286.740089) (xy 36.47468 -286.755093) (xy 36.436441 -286.777023)
			(xy 36.40256 -286.805224) (xy 36.374053 -286.838847) (xy 36.351775 -286.876886) (xy 36.336396 -286.918197)
			(xy 36.328376 -286.961543) (xy 36.327955 -287.005623) (xy 36.335148 -287.049114) (xy 36.349737 -287.090712)
			(xy 36.3601 -287.11017) (xy 36.380944 -287.148367) (xy 36.416289 -287.227887) (xy 36.444137 -287.310333)
			(xy 36.46425 -287.394999) (xy 36.476455 -287.48116) (xy 36.480648 -287.568081) (xy 36.476793 -287.655018)
			(xy 36.464923 -287.741226) (xy 36.44514 -287.82597) (xy 36.417612 -287.908523) (xy 36.382576 -287.98818)
			(xy 36.340331 -288.06426) (xy 36.291238 -288.136112) (xy 36.235717 -288.203121) (xy 36.174243 -288.264715)
			(xy 36.107342 -288.320366) (xy 36.035585 -288.369598) (xy 35.959588 -288.411991) (xy 35.879999 -288.447182)
			(xy 35.797499 -288.47487) (xy 35.712794 -288.494818) (xy 35.626609 -288.506855) (xy 35.53968 -288.510879)
			(xy 35.452751 -288.506855) (xy 35.366566 -288.494818) (xy 35.281861 -288.47487) (xy 35.199361 -288.447182)
			(xy 35.119772 -288.411991) (xy 35.043775 -288.369598) (xy 34.972018 -288.320366) (xy 34.905117 -288.264715)
			(xy 34.843643 -288.203121) (xy 34.788122 -288.136112) (xy 34.739029 -288.06426) (xy 34.696784 -287.98818)
			(xy 34.661748 -287.908523) (xy 34.63422 -287.82597) (xy 34.614437 -287.741226) (xy 34.602567 -287.655018)
			(xy 34.598712 -287.568081) (xy 34.602905 -287.48116) (xy 34.61511 -287.394999) (xy 34.635223 -287.310333)
			(xy 34.663071 -287.227887) (xy 34.698416 -287.148367) (xy 34.71926 -287.11017) (xy 34.72963 -287.090709)
			(xy 34.744244 -287.049109) (xy 34.751456 -287.005611) (xy 34.75105 -286.96152) (xy 34.743038 -286.918162)
			(xy 34.72766 -286.876839) (xy 34.705379 -286.838791) (xy 34.676862 -286.805161) (xy 34.642968 -286.776959)
			(xy 34.604714 -286.755033) (xy 34.563249 -286.740041) (xy 34.519818 -286.732434) (xy 34.497772 -286.731964)
			(xy 34.34842 -286.731964) (xy 31.812738 -284.196536) (xy 31.503874 -284.196536) (xy 31.481879 -284.196965)
			(xy 31.43855 -284.204562) (xy 31.397176 -284.219506) (xy 31.358994 -284.241352) (xy 31.325144 -284.269447)
			(xy 31.296638 -284.302952) (xy 31.274327 -284.340864) (xy 31.258879 -284.382053) (xy 31.250754 -284.425286)
			(xy 31.250195 -284.469273) (xy 31.257219 -284.512698) (xy 31.271616 -284.554266) (xy 31.281878 -284.573726)
			(xy 31.302503 -284.611931) (xy 31.337449 -284.691415) (xy 31.364918 -284.773783) (xy 31.384677 -284.858333)
			(xy 31.396556 -284.944344) (xy 31.400454 -285.031084) (xy 31.396339 -285.117814) (xy 31.384246 -285.203795)
			(xy 31.364277 -285.288295) (xy 31.336602 -285.370594) (xy 31.301458 -285.449991) (xy 31.259143 -285.52581)
			(xy 31.210018 -285.597404) (xy 31.154502 -285.664165) (xy 31.093068 -285.725523) (xy 31.026238 -285.780956)
			(xy 30.954582 -285.829991) (xy 30.87871 -285.872211) (xy 30.79927 -285.907256) (xy 30.716936 -285.934828)
			(xy 30.632411 -285.954692) (xy 30.546415 -285.966678) (xy 30.45968 -285.970685) (xy 30.372945 -285.966678)
			(xy 30.286949 -285.954692) (xy 30.202424 -285.934828) (xy 30.12009 -285.907256) (xy 30.04065 -285.872211)
			(xy 29.964778 -285.829991) (xy 29.893122 -285.780956) (xy 29.826292 -285.725523) (xy 29.764858 -285.664165)
			(xy 29.709342 -285.597404) (xy 29.660217 -285.52581) (xy 29.617902 -285.449991) (xy 29.582758 -285.370594)
			(xy 29.555083 -285.288295) (xy 29.535114 -285.203795) (xy 29.523021 -285.117814) (xy 29.518906 -285.031084)
			(xy 29.522804 -284.944344) (xy 29.534683 -284.858333) (xy 29.554442 -284.773783) (xy 29.581911 -284.691415)
			(xy 29.616857 -284.611931) (xy 29.637482 -284.573726) (xy 29.647771 -284.554274) (xy 29.6622 -284.512706)
			(xy 29.669248 -284.469273) (xy 29.668705 -284.425275) (xy 29.660587 -284.382029) (xy 29.645138 -284.340829)
			(xy 29.622819 -284.302909) (xy 29.594298 -284.269402) (xy 29.56043 -284.241312) (xy 29.522227 -284.21948)
			(xy 29.480833 -284.204558) (xy 29.437487 -284.196994) (xy 29.415486 -284.196536) (xy 28.660598 -284.196536)
			(xy 28.234132 -283.77007) (xy 28.21213 -283.747337) (xy 28.173617 -283.697145) (xy 28.141984 -283.642356)
			(xy 28.117773 -283.583906) (xy 28.101399 -283.522797) (xy 28.093141 -283.460073) (xy 9.049598 -283.460073)
			(xy 9.055388 -283.47516) (xy 9.073217 -283.543413) (xy 9.083378 -283.61322) (xy 9.085747 -283.683724)
			(xy 9.080294 -283.754056) (xy 9.067088 -283.823351) (xy 9.057132 -283.857192) (xy 9.051231 -283.877957)
			(xy 9.04571 -283.920766) (xy 9.047503 -283.963893) (xy 9.056556 -284.006097) (xy 9.072611 -284.046164)
			(xy 9.086501 -284.068774) (xy 26.32659 -284.068774) (xy 26.330661 -284.013152) (xy 26.342787 -283.958715)
			(xy 26.36271 -283.906624) (xy 26.390006 -283.857989) (xy 26.424092 -283.813846) (xy 26.464241 -283.775137)
			(xy 26.509599 -283.742686) (xy 26.559199 -283.717185) (xy 26.611983 -283.699178) (xy 26.666826 -283.689048)
			(xy 26.72256 -283.687011) (xy 26.777997 -283.693111) (xy 26.831954 -283.707217) (xy 26.883283 -283.729029)
			(xy 26.930889 -283.758083) (xy 26.973757 -283.793758) (xy 27.010974 -283.835295) (xy 27.041747 -283.881808)
			(xy 27.065419 -283.932305) (xy 27.081487 -283.985712) (xy 27.089607 -284.040888) (xy 27.090116 -284.068774)
			(xy 27.089607 -284.09666) (xy 27.081487 -284.151836) (xy 27.065419 -284.205243) (xy 27.041747 -284.25574)
			(xy 27.010974 -284.302253) (xy 26.973757 -284.34379) (xy 26.930889 -284.379465) (xy 26.883283 -284.408519)
			(xy 26.831954 -284.430331) (xy 26.777997 -284.444437) (xy 26.72256 -284.450537) (xy 26.666826 -284.4485)
			(xy 26.611983 -284.43837) (xy 26.559199 -284.420363) (xy 26.509599 -284.394862) (xy 26.464241 -284.362411)
			(xy 26.424092 -284.323702) (xy 26.390006 -284.279559) (xy 26.36271 -284.230924) (xy 26.342787 -284.178833)
			(xy 26.330661 -284.124396) (xy 26.32659 -284.068774) (xy 9.086501 -284.068774) (xy 9.095205 -284.082942)
			(xy 9.123689 -284.115374) (xy 9.157244 -284.142526) (xy 9.194903 -284.163618) (xy 9.235586 -284.178043)
			(xy 9.278121 -284.185387) (xy 9.299702 -284.185868) (xy 9.525 -284.185868) (xy 10.026396 -284.687264)
			(xy 21.130514 -284.687264) (xy 22.426676 -285.983426) (xy 26.461718 -285.983426) (xy 26.465789 -285.927804)
			(xy 26.477915 -285.873367) (xy 26.497838 -285.821276) (xy 26.525134 -285.772641) (xy 26.55922 -285.728498)
			(xy 26.599369 -285.689789) (xy 26.644727 -285.657338) (xy 26.694327 -285.631837) (xy 26.747111 -285.61383)
			(xy 26.801954 -285.6037) (xy 26.857688 -285.601663) (xy 26.913125 -285.607763) (xy 26.967082 -285.621869)
			(xy 27.018411 -285.643681) (xy 27.066017 -285.672735) (xy 27.108885 -285.70841) (xy 27.146102 -285.749947)
			(xy 27.176875 -285.79646) (xy 27.200547 -285.846957) (xy 27.216615 -285.900364) (xy 27.224735 -285.95554)
			(xy 27.225244 -285.983426) (xy 27.224735 -286.011312) (xy 27.216615 -286.066488) (xy 27.200547 -286.119895)
			(xy 27.176875 -286.170392) (xy 27.146102 -286.216905) (xy 27.108885 -286.258442) (xy 27.066017 -286.294117)
			(xy 27.018411 -286.323171) (xy 26.967082 -286.344983) (xy 26.913125 -286.359089) (xy 26.857688 -286.365189)
			(xy 26.801954 -286.363152) (xy 26.747111 -286.353022) (xy 26.694327 -286.335015) (xy 26.644727 -286.309514)
			(xy 26.599369 -286.277063) (xy 26.55922 -286.238354) (xy 26.525134 -286.194211) (xy 26.497838 -286.145576)
			(xy 26.477915 -286.093485) (xy 26.465789 -286.039048) (xy 26.461718 -285.983426) (xy 22.426676 -285.983426)
			(xy 23.281894 -286.838644) (xy 27.168854 -286.838644) (xy 27.172925 -286.783022) (xy 27.185051 -286.728585)
			(xy 27.204974 -286.676494) (xy 27.23227 -286.627859) (xy 27.266356 -286.583716) (xy 27.306505 -286.545007)
			(xy 27.351863 -286.512556) (xy 27.401463 -286.487055) (xy 27.454247 -286.469048) (xy 27.50909 -286.458918)
			(xy 27.564824 -286.456881) (xy 27.620261 -286.462981) (xy 27.674218 -286.477087) (xy 27.725547 -286.498899)
			(xy 27.773153 -286.527953) (xy 27.816021 -286.563628) (xy 27.853238 -286.605165) (xy 27.884011 -286.651678)
			(xy 27.907683 -286.702175) (xy 27.923751 -286.755582) (xy 27.931871 -286.810758) (xy 27.93238 -286.838644)
			(xy 27.931871 -286.86653) (xy 27.923751 -286.921706) (xy 27.907683 -286.975113) (xy 27.884011 -287.02561)
			(xy 27.853238 -287.072123) (xy 27.816021 -287.11366) (xy 27.773153 -287.149335) (xy 27.725547 -287.178389)
			(xy 27.674218 -287.200201) (xy 27.620261 -287.214307) (xy 27.564824 -287.220407) (xy 27.50909 -287.21837)
			(xy 27.454247 -287.20824) (xy 27.401463 -287.190233) (xy 27.351863 -287.164732) (xy 27.306505 -287.132281)
			(xy 27.266356 -287.093572) (xy 27.23227 -287.049429) (xy 27.204974 -287.000794) (xy 27.185051 -286.948703)
			(xy 27.172925 -286.894266) (xy 27.168854 -286.838644) (xy 23.281894 -286.838644) (xy 24.05661 -287.61336)
			(xy 29.519874 -287.61336) (xy 29.519874 -287.52646) (xy 29.527892 -287.439931) (xy 29.54386 -287.354511)
			(xy 29.567641 -287.270929) (xy 29.599033 -287.189897) (xy 29.637767 -287.112108) (xy 29.683514 -287.038224)
			(xy 29.735883 -286.968877) (xy 29.794427 -286.904657) (xy 29.858647 -286.846113) (xy 29.927994 -286.793744)
			(xy 30.001878 -286.747997) (xy 30.079667 -286.709263) (xy 30.160699 -286.677871) (xy 30.244281 -286.65409)
			(xy 30.329701 -286.638122) (xy 30.41623 -286.630104) (xy 30.50313 -286.630104) (xy 30.589659 -286.638122)
			(xy 30.675079 -286.65409) (xy 30.758661 -286.677871) (xy 30.839693 -286.709263) (xy 30.917482 -286.747997)
			(xy 30.991366 -286.793744) (xy 31.060713 -286.846113) (xy 31.124933 -286.904657) (xy 31.183477 -286.968877)
			(xy 31.235846 -287.038224) (xy 31.281593 -287.112108) (xy 31.320327 -287.189897) (xy 31.351719 -287.270929)
			(xy 31.3755 -287.354511) (xy 31.391468 -287.439931) (xy 31.399486 -287.52646) (xy 31.399988 -287.56991)
			(xy 31.399486 -287.61336) (xy 31.391468 -287.699889) (xy 31.3755 -287.785309) (xy 31.351719 -287.868891)
			(xy 31.320327 -287.949923) (xy 31.281593 -288.027712) (xy 31.235846 -288.101596) (xy 31.183477 -288.170943)
			(xy 31.124933 -288.235163) (xy 31.060713 -288.293707) (xy 30.991366 -288.346076) (xy 30.917482 -288.391823)
			(xy 30.839693 -288.430557) (xy 30.758661 -288.461949) (xy 30.675079 -288.48573) (xy 30.589659 -288.501698)
			(xy 30.50313 -288.509716) (xy 30.41623 -288.509716) (xy 30.329701 -288.501698) (xy 30.244281 -288.48573)
			(xy 30.160699 -288.461949) (xy 30.079667 -288.430557) (xy 30.001878 -288.391823) (xy 29.927994 -288.346076)
			(xy 29.858647 -288.293707) (xy 29.794427 -288.235163) (xy 29.735883 -288.170943) (xy 29.683514 -288.101596)
			(xy 29.637767 -288.027712) (xy 29.599033 -287.949923) (xy 29.567641 -287.868891) (xy 29.54386 -287.785309)
			(xy 29.527892 -287.699889) (xy 29.519874 -287.61336) (xy 24.05661 -287.61336) (xy 26.59661 -290.15336)
			(xy 29.519874 -290.15336) (xy 29.519874 -290.06646) (xy 29.527892 -289.979931) (xy 29.54386 -289.894511)
			(xy 29.567641 -289.810929) (xy 29.599033 -289.729897) (xy 29.637767 -289.652108) (xy 29.683514 -289.578224)
			(xy 29.735883 -289.508877) (xy 29.794427 -289.444657) (xy 29.858647 -289.386113) (xy 29.927994 -289.333744)
			(xy 30.001878 -289.287997) (xy 30.079667 -289.249263) (xy 30.160699 -289.217871) (xy 30.244281 -289.19409)
			(xy 30.329701 -289.178122) (xy 30.41623 -289.170104) (xy 30.50313 -289.170104) (xy 30.589659 -289.178122)
			(xy 30.675079 -289.19409) (xy 30.758661 -289.217871) (xy 30.839693 -289.249263) (xy 30.917482 -289.287997)
			(xy 30.991366 -289.333744) (xy 31.060713 -289.386113) (xy 31.124933 -289.444657) (xy 31.183477 -289.508877)
			(xy 31.235846 -289.578224) (xy 31.281593 -289.652108) (xy 31.320327 -289.729897) (xy 31.351719 -289.810929)
			(xy 31.3755 -289.894511) (xy 31.391468 -289.979931) (xy 31.399486 -290.06646) (xy 31.399988 -290.10991)
			(xy 31.399486 -290.15336) (xy 34.599874 -290.15336) (xy 34.599874 -290.06646) (xy 34.607892 -289.979931)
			(xy 34.62386 -289.894511) (xy 34.647641 -289.810929) (xy 34.679033 -289.729897) (xy 34.717767 -289.652108)
			(xy 34.763514 -289.578224) (xy 34.815883 -289.508877) (xy 34.874427 -289.444657) (xy 34.938647 -289.386113)
			(xy 35.007994 -289.333744) (xy 35.081878 -289.287997) (xy 35.159667 -289.249263) (xy 35.240699 -289.217871)
			(xy 35.324281 -289.19409) (xy 35.409701 -289.178122) (xy 35.49623 -289.170104) (xy 35.58313 -289.170104)
			(xy 35.669659 -289.178122) (xy 35.755079 -289.19409) (xy 35.838661 -289.217871) (xy 35.919693 -289.249263)
			(xy 35.997482 -289.287997) (xy 36.071366 -289.333744) (xy 36.140713 -289.386113) (xy 36.204933 -289.444657)
			(xy 36.263477 -289.508877) (xy 36.315846 -289.578224) (xy 36.361593 -289.652108) (xy 36.400327 -289.729897)
			(xy 36.431719 -289.810929) (xy 36.4555 -289.894511) (xy 36.471468 -289.979931) (xy 36.479486 -290.06646)
			(xy 36.479988 -290.10991) (xy 36.479486 -290.15336) (xy 36.471468 -290.239889) (xy 36.4555 -290.325309)
			(xy 36.431719 -290.408891) (xy 36.400327 -290.489923) (xy 36.361593 -290.567712) (xy 36.315846 -290.641596)
			(xy 36.263477 -290.710943) (xy 36.204933 -290.775163) (xy 36.140713 -290.833707) (xy 36.071366 -290.886076)
			(xy 35.997482 -290.931823) (xy 35.919693 -290.970557) (xy 35.838661 -291.001949) (xy 35.755079 -291.02573)
			(xy 35.669659 -291.041698) (xy 35.58313 -291.049716) (xy 35.49623 -291.049716) (xy 35.409701 -291.041698)
			(xy 35.324281 -291.02573) (xy 35.240699 -291.001949) (xy 35.159667 -290.970557) (xy 35.081878 -290.931823)
			(xy 35.007994 -290.886076) (xy 34.938647 -290.833707) (xy 34.874427 -290.775163) (xy 34.815883 -290.710943)
			(xy 34.763514 -290.641596) (xy 34.717767 -290.567712) (xy 34.679033 -290.489923) (xy 34.647641 -290.408891)
			(xy 34.62386 -290.325309) (xy 34.607892 -290.239889) (xy 34.599874 -290.15336) (xy 31.399486 -290.15336)
			(xy 31.391468 -290.239889) (xy 31.3755 -290.325309) (xy 31.351719 -290.408891) (xy 31.320327 -290.489923)
			(xy 31.281593 -290.567712) (xy 31.235846 -290.641596) (xy 31.183477 -290.710943) (xy 31.124933 -290.775163)
			(xy 31.060713 -290.833707) (xy 30.991366 -290.886076) (xy 30.917482 -290.931823) (xy 30.839693 -290.970557)
			(xy 30.758661 -291.001949) (xy 30.675079 -291.02573) (xy 30.589659 -291.041698) (xy 30.50313 -291.049716)
			(xy 30.41623 -291.049716) (xy 30.329701 -291.041698) (xy 30.244281 -291.02573) (xy 30.160699 -291.001949)
			(xy 30.079667 -290.970557) (xy 30.001878 -290.931823) (xy 29.927994 -290.886076) (xy 29.858647 -290.833707)
			(xy 29.794427 -290.775163) (xy 29.735883 -290.710943) (xy 29.683514 -290.641596) (xy 29.637767 -290.567712)
			(xy 29.599033 -290.489923) (xy 29.567641 -290.408891) (xy 29.54386 -290.325309) (xy 29.527892 -290.239889)
			(xy 29.519874 -290.15336) (xy 26.59661 -290.15336) (xy 28.912312 -292.469062) (xy 28.912312 -292.69336)
			(xy 29.519874 -292.69336) (xy 29.519874 -292.60646) (xy 29.527892 -292.519931) (xy 29.54386 -292.434511)
			(xy 29.567641 -292.350929) (xy 29.599033 -292.269897) (xy 29.637767 -292.192108) (xy 29.683514 -292.118224)
			(xy 29.735883 -292.048877) (xy 29.794427 -291.984657) (xy 29.858647 -291.926113) (xy 29.927994 -291.873744)
			(xy 30.001878 -291.827997) (xy 30.079667 -291.789263) (xy 30.160699 -291.757871) (xy 30.244281 -291.73409)
			(xy 30.329701 -291.718122) (xy 30.41623 -291.710104) (xy 30.50313 -291.710104) (xy 30.589659 -291.718122)
			(xy 30.675079 -291.73409) (xy 30.758661 -291.757871) (xy 30.839693 -291.789263) (xy 30.917482 -291.827997)
			(xy 30.991366 -291.873744) (xy 31.060713 -291.926113) (xy 31.124933 -291.984657) (xy 31.183477 -292.048877)
			(xy 31.235846 -292.118224) (xy 31.281593 -292.192108) (xy 31.320327 -292.269897) (xy 31.351719 -292.350929)
			(xy 31.3755 -292.434511) (xy 31.391468 -292.519931) (xy 31.399486 -292.60646) (xy 31.399988 -292.64991)
			(xy 31.399486 -292.69336) (xy 34.599874 -292.69336) (xy 34.599874 -292.60646) (xy 34.607892 -292.519931)
			(xy 34.62386 -292.434511) (xy 34.647641 -292.350929) (xy 34.679033 -292.269897) (xy 34.717767 -292.192108)
			(xy 34.763514 -292.118224) (xy 34.815883 -292.048877) (xy 34.874427 -291.984657) (xy 34.938647 -291.926113)
			(xy 35.007994 -291.873744) (xy 35.081878 -291.827997) (xy 35.159667 -291.789263) (xy 35.240699 -291.757871)
			(xy 35.324281 -291.73409) (xy 35.409701 -291.718122) (xy 35.49623 -291.710104) (xy 35.58313 -291.710104)
			(xy 35.669659 -291.718122) (xy 35.755079 -291.73409) (xy 35.838661 -291.757871) (xy 35.919693 -291.789263)
			(xy 35.997482 -291.827997) (xy 36.071366 -291.873744) (xy 36.140713 -291.926113) (xy 36.204933 -291.984657)
			(xy 36.263477 -292.048877) (xy 36.315846 -292.118224) (xy 36.361593 -292.192108) (xy 36.400327 -292.269897)
			(xy 36.431719 -292.350929) (xy 36.4555 -292.434511) (xy 36.471468 -292.519931) (xy 36.479486 -292.60646)
			(xy 36.479988 -292.64991) (xy 36.479486 -292.69336) (xy 36.471468 -292.779889) (xy 36.4555 -292.865309)
			(xy 36.431719 -292.948891) (xy 36.400327 -293.029923) (xy 36.361593 -293.107712) (xy 36.315846 -293.181596)
			(xy 36.263477 -293.250943) (xy 36.204933 -293.315163) (xy 36.140713 -293.373707) (xy 36.071366 -293.426076)
			(xy 35.997482 -293.471823) (xy 35.919693 -293.510557) (xy 35.838661 -293.541949) (xy 35.755079 -293.56573)
			(xy 35.669659 -293.581698) (xy 35.58313 -293.589716) (xy 35.49623 -293.589716) (xy 35.409701 -293.581698)
			(xy 35.324281 -293.56573) (xy 35.240699 -293.541949) (xy 35.159667 -293.510557) (xy 35.081878 -293.471823)
			(xy 35.007994 -293.426076) (xy 34.938647 -293.373707) (xy 34.874427 -293.315163) (xy 34.815883 -293.250943)
			(xy 34.763514 -293.181596) (xy 34.717767 -293.107712) (xy 34.679033 -293.029923) (xy 34.647641 -292.948891)
			(xy 34.62386 -292.865309) (xy 34.607892 -292.779889) (xy 34.599874 -292.69336) (xy 31.399486 -292.69336)
			(xy 31.391468 -292.779889) (xy 31.3755 -292.865309) (xy 31.351719 -292.948891) (xy 31.320327 -293.029923)
			(xy 31.281593 -293.107712) (xy 31.235846 -293.181596) (xy 31.183477 -293.250943) (xy 31.124933 -293.315163)
			(xy 31.060713 -293.373707) (xy 30.991366 -293.426076) (xy 30.917482 -293.471823) (xy 30.839693 -293.510557)
			(xy 30.758661 -293.541949) (xy 30.675079 -293.56573) (xy 30.589659 -293.581698) (xy 30.50313 -293.589716)
			(xy 30.41623 -293.589716) (xy 30.329701 -293.581698) (xy 30.244281 -293.56573) (xy 30.160699 -293.541949)
			(xy 30.079667 -293.510557) (xy 30.001878 -293.471823) (xy 29.927994 -293.426076) (xy 29.858647 -293.373707)
			(xy 29.794427 -293.315163) (xy 29.735883 -293.250943) (xy 29.683514 -293.181596) (xy 29.637767 -293.107712)
			(xy 29.599033 -293.029923) (xy 29.567641 -292.948891) (xy 29.54386 -292.865309) (xy 29.527892 -292.779889)
			(xy 29.519874 -292.69336) (xy 28.912312 -292.69336) (xy 28.912312 -295.23336) (xy 29.519874 -295.23336)
			(xy 29.519874 -295.14646) (xy 29.527892 -295.059931) (xy 29.54386 -294.974511) (xy 29.567641 -294.890929)
			(xy 29.599033 -294.809897) (xy 29.637767 -294.732108) (xy 29.683514 -294.658224) (xy 29.735883 -294.588877)
			(xy 29.794427 -294.524657) (xy 29.858647 -294.466113) (xy 29.927994 -294.413744) (xy 30.001878 -294.367997)
			(xy 30.079667 -294.329263) (xy 30.160699 -294.297871) (xy 30.244281 -294.27409) (xy 30.329701 -294.258122)
			(xy 30.41623 -294.250104) (xy 30.50313 -294.250104) (xy 30.589659 -294.258122) (xy 30.675079 -294.27409)
			(xy 30.758661 -294.297871) (xy 30.839693 -294.329263) (xy 30.917482 -294.367997) (xy 30.991366 -294.413744)
			(xy 31.060713 -294.466113) (xy 31.124933 -294.524657) (xy 31.183477 -294.588877) (xy 31.235846 -294.658224)
			(xy 31.281593 -294.732108) (xy 31.320327 -294.809897) (xy 31.351719 -294.890929) (xy 31.3755 -294.974511)
			(xy 31.391468 -295.059931) (xy 31.399486 -295.14646) (xy 31.399988 -295.18991) (xy 31.399486 -295.23336)
			(xy 34.599874 -295.23336) (xy 34.599874 -295.14646) (xy 34.607892 -295.059931) (xy 34.62386 -294.974511)
			(xy 34.647641 -294.890929) (xy 34.679033 -294.809897) (xy 34.717767 -294.732108) (xy 34.763514 -294.658224)
			(xy 34.815883 -294.588877) (xy 34.874427 -294.524657) (xy 34.938647 -294.466113) (xy 35.007994 -294.413744)
			(xy 35.081878 -294.367997) (xy 35.159667 -294.329263) (xy 35.240699 -294.297871) (xy 35.324281 -294.27409)
			(xy 35.409701 -294.258122) (xy 35.49623 -294.250104) (xy 35.58313 -294.250104) (xy 35.669659 -294.258122)
			(xy 35.755079 -294.27409) (xy 35.838661 -294.297871) (xy 35.919693 -294.329263) (xy 35.997482 -294.367997)
			(xy 36.071366 -294.413744) (xy 36.140713 -294.466113) (xy 36.204933 -294.524657) (xy 36.263477 -294.588877)
			(xy 36.315846 -294.658224) (xy 36.361593 -294.732108) (xy 36.400327 -294.809897) (xy 36.431719 -294.890929)
			(xy 36.4555 -294.974511) (xy 36.471468 -295.059931) (xy 36.479486 -295.14646) (xy 36.479988 -295.18991)
			(xy 36.479486 -295.23336) (xy 36.471468 -295.319889) (xy 36.4555 -295.405309) (xy 36.431719 -295.488891)
			(xy 36.400327 -295.569923) (xy 36.361593 -295.647712) (xy 36.315846 -295.721596) (xy 36.263477 -295.790943)
			(xy 36.204933 -295.855163) (xy 36.140713 -295.913707) (xy 36.071366 -295.966076) (xy 35.997482 -296.011823)
			(xy 35.919693 -296.050557) (xy 35.838661 -296.081949) (xy 35.755079 -296.10573) (xy 35.669659 -296.121698)
			(xy 35.58313 -296.129716) (xy 35.49623 -296.129716) (xy 35.409701 -296.121698) (xy 35.324281 -296.10573)
			(xy 35.240699 -296.081949) (xy 35.159667 -296.050557) (xy 35.081878 -296.011823) (xy 35.007994 -295.966076)
			(xy 34.938647 -295.913707) (xy 34.874427 -295.855163) (xy 34.815883 -295.790943) (xy 34.763514 -295.721596)
			(xy 34.717767 -295.647712) (xy 34.679033 -295.569923) (xy 34.647641 -295.488891) (xy 34.62386 -295.405309)
			(xy 34.607892 -295.319889) (xy 34.599874 -295.23336) (xy 31.399486 -295.23336) (xy 31.391468 -295.319889)
			(xy 31.3755 -295.405309) (xy 31.351719 -295.488891) (xy 31.320327 -295.569923) (xy 31.281593 -295.647712)
			(xy 31.235846 -295.721596) (xy 31.183477 -295.790943) (xy 31.124933 -295.855163) (xy 31.060713 -295.913707)
			(xy 30.991366 -295.966076) (xy 30.917482 -296.011823) (xy 30.839693 -296.050557) (xy 30.758661 -296.081949)
			(xy 30.675079 -296.10573) (xy 30.589659 -296.121698) (xy 30.50313 -296.129716) (xy 30.41623 -296.129716)
			(xy 30.329701 -296.121698) (xy 30.244281 -296.10573) (xy 30.160699 -296.081949) (xy 30.079667 -296.050557)
			(xy 30.001878 -296.011823) (xy 29.927994 -295.966076) (xy 29.858647 -295.913707) (xy 29.794427 -295.855163)
			(xy 29.735883 -295.790943) (xy 29.683514 -295.721596) (xy 29.637767 -295.647712) (xy 29.599033 -295.569923)
			(xy 29.567641 -295.488891) (xy 29.54386 -295.405309) (xy 29.527892 -295.319889) (xy 29.519874 -295.23336)
			(xy 28.912312 -295.23336) (xy 28.912312 -297.77336) (xy 29.519874 -297.77336) (xy 29.519874 -297.68646)
			(xy 29.527892 -297.599931) (xy 29.54386 -297.514511) (xy 29.567641 -297.430929) (xy 29.599033 -297.349897)
			(xy 29.637767 -297.272108) (xy 29.683514 -297.198224) (xy 29.735883 -297.128877) (xy 29.794427 -297.064657)
			(xy 29.858647 -297.006113) (xy 29.927994 -296.953744) (xy 30.001878 -296.907997) (xy 30.079667 -296.869263)
			(xy 30.160699 -296.837871) (xy 30.244281 -296.81409) (xy 30.329701 -296.798122) (xy 30.41623 -296.790104)
			(xy 30.50313 -296.790104) (xy 30.589659 -296.798122) (xy 30.675079 -296.81409) (xy 30.758661 -296.837871)
			(xy 30.839693 -296.869263) (xy 30.917482 -296.907997) (xy 30.991366 -296.953744) (xy 31.060713 -297.006113)
			(xy 31.124933 -297.064657) (xy 31.183477 -297.128877) (xy 31.235846 -297.198224) (xy 31.281593 -297.272108)
			(xy 31.320327 -297.349897) (xy 31.351719 -297.430929) (xy 31.3755 -297.514511) (xy 31.391468 -297.599931)
			(xy 31.399486 -297.68646) (xy 31.399988 -297.72991) (xy 31.399486 -297.77336) (xy 34.599874 -297.77336)
			(xy 34.599874 -297.68646) (xy 34.607892 -297.599931) (xy 34.62386 -297.514511) (xy 34.647641 -297.430929)
			(xy 34.679033 -297.349897) (xy 34.717767 -297.272108) (xy 34.763514 -297.198224) (xy 34.815883 -297.128877)
			(xy 34.874427 -297.064657) (xy 34.938647 -297.006113) (xy 35.007994 -296.953744) (xy 35.081878 -296.907997)
			(xy 35.159667 -296.869263) (xy 35.240699 -296.837871) (xy 35.324281 -296.81409) (xy 35.409701 -296.798122)
			(xy 35.49623 -296.790104) (xy 35.58313 -296.790104) (xy 35.669659 -296.798122) (xy 35.755079 -296.81409)
			(xy 35.838661 -296.837871) (xy 35.919693 -296.869263) (xy 35.997482 -296.907997) (xy 36.041741 -296.935401)
			(xy 38.511584 -296.935401) (xy 38.515472 -296.881047) (xy 38.527056 -296.827799) (xy 38.5461 -296.776741)
			(xy 38.572216 -296.728914) (xy 38.604874 -296.68529) (xy 38.643408 -296.646759) (xy 38.687034 -296.614104)
			(xy 38.734862 -296.58799) (xy 38.785921 -296.568949) (xy 38.83917 -296.557368) (xy 38.893525 -296.553484)
			(xy 38.947879 -296.557375) (xy 39.001126 -296.568963) (xy 39.052182 -296.58801) (xy 39.100008 -296.61413)
			(xy 39.122096 -296.63009) (xy 39.141108 -296.643686) (xy 39.182991 -296.664418) (xy 39.227959 -296.677144)
			(xy 39.274496 -296.681434) (xy 39.321033 -296.677144) (xy 39.366001 -296.664418) (xy 39.407884 -296.643686)
			(xy 39.426896 -296.63009) (xy 39.448986 -296.614132) (xy 39.496812 -296.588011) (xy 39.547868 -296.568963)
			(xy 39.601116 -296.557375) (xy 39.655471 -296.553483) (xy 39.709826 -296.557366) (xy 39.763076 -296.568946)
			(xy 39.814135 -296.587987) (xy 39.861965 -296.614101) (xy 39.905591 -296.646756) (xy 39.944126 -296.685288)
			(xy 39.976784 -296.728912) (xy 40.002901 -296.776739) (xy 40.021946 -296.827797) (xy 40.03353 -296.881046)
			(xy 40.037417 -296.935401) (xy 40.398277 -296.935401) (xy 40.402165 -296.881045) (xy 40.413749 -296.827795)
			(xy 40.432794 -296.776736) (xy 40.458912 -296.728908) (xy 40.491571 -296.685283) (xy 40.530106 -296.646751)
			(xy 40.573733 -296.614095) (xy 40.621564 -296.587981) (xy 40.672624 -296.56894) (xy 40.725875 -296.55736)
			(xy 40.780231 -296.553477) (xy 40.834587 -296.557369) (xy 40.887836 -296.568958) (xy 40.938893 -296.588007)
			(xy 40.986719 -296.614129) (xy 41.008808 -296.63009) (xy 41.02782 -296.643686) (xy 41.069703 -296.664418)
			(xy 41.114671 -296.677144) (xy 41.161208 -296.681434) (xy 41.207745 -296.677144) (xy 41.252713 -296.664418)
			(xy 41.294596 -296.643686) (xy 41.313608 -296.63009) (xy 41.335698 -296.614133) (xy 41.383523 -296.588014)
			(xy 41.434578 -296.568967) (xy 41.487824 -296.557381) (xy 41.542178 -296.55349) (xy 41.596532 -296.557374)
			(xy 41.649779 -296.568955) (xy 41.700837 -296.587996) (xy 41.748665 -296.614109) (xy 41.792289 -296.646764)
			(xy 41.830822 -296.685295) (xy 41.863479 -296.728918) (xy 41.889596 -296.776744) (xy 41.908639 -296.827801)
			(xy 41.920223 -296.881048) (xy 41.92411 -296.935401) (xy 41.920222 -296.989755) (xy 41.908639 -297.043002)
			(xy 41.889595 -297.094058) (xy 41.863478 -297.141884) (xy 41.830821 -297.185507) (xy 41.792287 -297.224038)
			(xy 41.748663 -297.256692) (xy 41.700835 -297.282805) (xy 41.649777 -297.301846) (xy 41.596529 -297.313426)
			(xy 41.542175 -297.31731) (xy 41.487822 -297.313419) (xy 41.434576 -297.301832) (xy 41.383521 -297.282785)
			(xy 41.335696 -297.256665) (xy 41.313608 -297.240706) (xy 41.294596 -297.22711) (xy 41.252713 -297.206378)
			(xy 41.207745 -297.193652) (xy 41.161208 -297.189362) (xy 41.114671 -297.193652) (xy 41.069703 -297.206378)
			(xy 41.02782 -297.22711) (xy 41.008808 -297.240706) (xy 40.986722 -297.256669) (xy 40.938895 -297.282792)
			(xy 40.887838 -297.301841) (xy 40.83459 -297.31343) (xy 40.780234 -297.317323) (xy 40.725877 -297.31344)
			(xy 40.672627 -297.30186) (xy 40.621566 -297.28282) (xy 40.573735 -297.256706) (xy 40.530108 -297.224051)
			(xy 40.491572 -297.185518) (xy 40.458913 -297.141894) (xy 40.432795 -297.094066) (xy 40.41375 -297.043007)
			(xy 40.402165 -296.989757) (xy 40.398277 -296.935401) (xy 40.037417 -296.935401) (xy 40.033529 -296.989756)
			(xy 40.021945 -297.043005) (xy 40.0029 -297.094063) (xy 39.976783 -297.14189) (xy 39.944124 -297.185514)
			(xy 39.905589 -297.224045) (xy 39.861963 -297.2567) (xy 39.814133 -297.282814) (xy 39.763074 -297.301854)
			(xy 39.709824 -297.313434) (xy 39.655468 -297.317317) (xy 39.601114 -297.313425) (xy 39.547866 -297.301837)
			(xy 39.49681 -297.282788) (xy 39.448984 -297.256666) (xy 39.426896 -297.240706) (xy 39.407884 -297.22711)
			(xy 39.366001 -297.206378) (xy 39.321033 -297.193652) (xy 39.274496 -297.189362) (xy 39.227959 -297.193652)
			(xy 39.182991 -297.206378) (xy 39.141108 -297.22711) (xy 39.122096 -297.240706) (xy 39.10001 -297.256668)
			(xy 39.052184 -297.282789) (xy 39.001128 -297.301837) (xy 38.947881 -297.313424) (xy 38.893527 -297.317316)
			(xy 38.839172 -297.313432) (xy 38.785923 -297.301852) (xy 38.734865 -297.282811) (xy 38.687036 -297.256697)
			(xy 38.64341 -297.224043) (xy 38.604876 -297.185511) (xy 38.572218 -297.141888) (xy 38.546101 -297.094061)
			(xy 38.527056 -297.043004) (xy 38.515472 -296.989756) (xy 38.511584 -296.935401) (xy 36.041741 -296.935401)
			(xy 36.071366 -296.953744) (xy 36.140713 -297.006113) (xy 36.204933 -297.064657) (xy 36.263477 -297.128877)
			(xy 36.315846 -297.198224) (xy 36.361593 -297.272108) (xy 36.400327 -297.349897) (xy 36.431719 -297.430929)
			(xy 36.4555 -297.514511) (xy 36.471468 -297.599931) (xy 36.479486 -297.68646) (xy 36.479988 -297.72991)
			(xy 36.479486 -297.77336) (xy 36.471468 -297.859889) (xy 36.4555 -297.945309) (xy 36.431719 -298.028891)
			(xy 36.400327 -298.109923) (xy 36.361593 -298.187712) (xy 36.315846 -298.261596) (xy 36.263477 -298.330943)
			(xy 36.204933 -298.395163) (xy 36.140713 -298.453707) (xy 36.071366 -298.506076) (xy 35.997482 -298.551823)
			(xy 35.919693 -298.590557) (xy 35.838661 -298.621949) (xy 35.755079 -298.64573) (xy 35.669659 -298.661698)
			(xy 35.58313 -298.669716) (xy 35.49623 -298.669716) (xy 35.409701 -298.661698) (xy 35.324281 -298.64573)
			(xy 35.240699 -298.621949) (xy 35.159667 -298.590557) (xy 35.081878 -298.551823) (xy 35.007994 -298.506076)
			(xy 34.938647 -298.453707) (xy 34.874427 -298.395163) (xy 34.815883 -298.330943) (xy 34.763514 -298.261596)
			(xy 34.717767 -298.187712) (xy 34.679033 -298.109923) (xy 34.647641 -298.028891) (xy 34.62386 -297.945309)
			(xy 34.607892 -297.859889) (xy 34.599874 -297.77336) (xy 31.399486 -297.77336) (xy 31.391468 -297.859889)
			(xy 31.3755 -297.945309) (xy 31.351719 -298.028891) (xy 31.320327 -298.109923) (xy 31.281593 -298.187712)
			(xy 31.235846 -298.261596) (xy 31.183477 -298.330943) (xy 31.124933 -298.395163) (xy 31.060713 -298.453707)
			(xy 30.991366 -298.506076) (xy 30.917482 -298.551823) (xy 30.839693 -298.590557) (xy 30.758661 -298.621949)
			(xy 30.675079 -298.64573) (xy 30.589659 -298.661698) (xy 30.50313 -298.669716) (xy 30.41623 -298.669716)
			(xy 30.329701 -298.661698) (xy 30.244281 -298.64573) (xy 30.160699 -298.621949) (xy 30.079667 -298.590557)
			(xy 30.001878 -298.551823) (xy 29.927994 -298.506076) (xy 29.858647 -298.453707) (xy 29.794427 -298.395163)
			(xy 29.735883 -298.330943) (xy 29.683514 -298.261596) (xy 29.637767 -298.187712) (xy 29.599033 -298.109923)
			(xy 29.567641 -298.028891) (xy 29.54386 -297.945309) (xy 29.527892 -297.859889) (xy 29.519874 -297.77336)
			(xy 28.912312 -297.77336) (xy 28.912312 -298.768986) (xy 38.511605 -298.768986) (xy 38.515495 -298.714634)
			(xy 38.52708 -298.661389) (xy 38.546125 -298.610336) (xy 38.572242 -298.562512) (xy 38.6049 -298.518892)
			(xy 38.643434 -298.480364) (xy 38.687058 -298.447713) (xy 38.734885 -298.421602) (xy 38.785942 -298.402565)
			(xy 38.839188 -298.390987) (xy 38.89354 -298.387105) (xy 38.947891 -298.390998) (xy 39.001135 -298.402587)
			(xy 39.052188 -298.421636) (xy 39.10001 -298.447756) (xy 39.122096 -298.463716) (xy 39.141108 -298.477312)
			(xy 39.182991 -298.498044) (xy 39.227959 -298.51077) (xy 39.274496 -298.51506) (xy 39.321033 -298.51077)
			(xy 39.366001 -298.498044) (xy 39.407884 -298.477312) (xy 39.426896 -298.463716) (xy 39.448962 -298.447723)
			(xy 39.496789 -298.421599) (xy 39.547847 -298.402547) (xy 39.601098 -298.390956) (xy 39.655455 -298.387062)
			(xy 39.709814 -298.390943) (xy 39.763067 -298.402522) (xy 39.81413 -298.421562) (xy 39.861963 -298.447675)
			(xy 39.905593 -298.48033) (xy 39.944131 -298.518862) (xy 39.976793 -298.562487) (xy 40.002914 -298.610317)
			(xy 40.021961 -298.661376) (xy 40.033548 -298.714628) (xy 40.037438 -298.768986) (xy 40.398298 -298.768986)
			(xy 40.402188 -298.714632) (xy 40.413773 -298.661386) (xy 40.432819 -298.610331) (xy 40.458938 -298.562506)
			(xy 40.491597 -298.518885) (xy 40.530132 -298.480357) (xy 40.573758 -298.447705) (xy 40.621587 -298.421594)
			(xy 40.672645 -298.402556) (xy 40.725893 -298.390979) (xy 40.780247 -298.387098) (xy 40.8346 -298.390992)
			(xy 40.887845 -298.402583) (xy 40.938899 -298.421633) (xy 40.986721 -298.447755) (xy 41.008808 -298.463716)
			(xy 41.02782 -298.477312) (xy 41.069703 -298.498044) (xy 41.114671 -298.51077) (xy 41.161208 -298.51506)
			(xy 41.207745 -298.51077) (xy 41.252713 -298.498044) (xy 41.294596 -298.477312) (xy 41.313608 -298.463716)
			(xy 41.335673 -298.447724) (xy 41.3835 -298.421602) (xy 41.434557 -298.402552) (xy 41.487806 -298.390962)
			(xy 41.542162 -298.387069) (xy 41.596519 -298.390951) (xy 41.64977 -298.40253) (xy 41.700831 -298.42157)
			(xy 41.748663 -298.447683) (xy 41.792291 -298.480338) (xy 41.830828 -298.518869) (xy 41.863488 -298.562493)
			(xy 41.889608 -298.610321) (xy 41.908655 -298.66138) (xy 41.920241 -298.714629) (xy 41.924131 -298.768986)
			(xy 42.639273 -298.768986) (xy 42.643163 -298.714627) (xy 42.65475 -298.661375) (xy 42.673799 -298.610315)
			(xy 42.699921 -298.562485) (xy 42.732585 -298.518861) (xy 42.771125 -298.480329) (xy 42.814757 -298.447675)
			(xy 42.862592 -298.421564) (xy 42.913657 -298.402526) (xy 42.966911 -298.390951) (xy 43.021271 -298.387073)
			(xy 43.075629 -298.390971) (xy 43.128879 -298.402566) (xy 43.179937 -298.421623) (xy 43.227762 -298.447752)
			(xy 43.24985 -298.463716) (xy 43.268862 -298.477312) (xy 43.310745 -298.498044) (xy 43.355713 -298.51077)
			(xy 43.40225 -298.51506) (xy 43.448787 -298.51077) (xy 43.493755 -298.498044) (xy 43.535638 -298.477312)
			(xy 43.55465 -298.463716) (xy 43.576717 -298.447719) (xy 43.624547 -298.421588) (xy 43.67561 -298.402529)
			(xy 43.728865 -298.390933) (xy 43.783229 -298.387034) (xy 43.837594 -298.390913) (xy 43.890854 -298.40249)
			(xy 43.941924 -298.421529) (xy 43.989764 -298.447643) (xy 44.0334 -298.4803) (xy 44.071944 -298.518835)
			(xy 44.104611 -298.562464) (xy 44.130736 -298.610299) (xy 44.149786 -298.661364) (xy 44.161375 -298.714621)
			(xy 44.165266 -298.768986) (xy 44.543282 -298.768986) (xy 44.547172 -298.714629) (xy 44.558759 -298.661379)
			(xy 44.577807 -298.610321) (xy 44.603927 -298.562493) (xy 44.636589 -298.51887) (xy 44.675128 -298.48034)
			(xy 44.718757 -298.447686) (xy 44.76659 -298.421575) (xy 44.817652 -298.402538) (xy 44.870904 -298.390962)
			(xy 44.925262 -298.387082) (xy 44.979618 -298.390979) (xy 45.032866 -298.402573) (xy 45.083922 -298.421626)
			(xy 45.131747 -298.447753) (xy 45.153834 -298.463716) (xy 45.172846 -298.477312) (xy 45.214729 -298.498044)
			(xy 45.259697 -298.51077) (xy 45.306234 -298.51506) (xy 45.352771 -298.51077) (xy 45.397739 -298.498044)
			(xy 45.439622 -298.477312) (xy 45.458634 -298.463716) (xy 45.480699 -298.447727) (xy 45.528523 -298.421608)
			(xy 45.579578 -298.402562) (xy 45.632824 -298.390975) (xy 45.687177 -298.387085) (xy 45.74153 -298.390969)
			(xy 45.794777 -298.402549) (xy 45.845835 -298.421589) (xy 45.893662 -298.447702) (xy 45.937287 -298.480355)
			(xy 45.97582 -298.518885) (xy 46.008478 -298.562506) (xy 46.034595 -298.610331) (xy 46.053641 -298.661387)
			(xy 46.065226 -298.714633) (xy 46.069115 -298.768986) (xy 46.06523 -298.823339) (xy 46.053649 -298.876586)
			(xy 46.034607 -298.927642) (xy 46.008494 -298.97547) (xy 45.975839 -299.019093) (xy 45.937309 -299.057626)
			(xy 45.893686 -299.090283) (xy 45.845861 -299.116399) (xy 45.794805 -299.135443) (xy 45.741559 -299.147027)
			(xy 45.687206 -299.150915) (xy 45.632853 -299.147029) (xy 45.579606 -299.135446) (xy 45.52855 -299.116404)
			(xy 45.480723 -299.090289) (xy 45.458634 -299.074332) (xy 45.439622 -299.060736) (xy 45.397739 -299.040004)
			(xy 45.352771 -299.027278) (xy 45.306234 -299.022988) (xy 45.259697 -299.027278) (xy 45.214729 -299.040004)
			(xy 45.172846 -299.060736) (xy 45.153834 -299.074332) (xy 45.131723 -299.090262) (xy 45.083896 -299.116385)
			(xy 45.032839 -299.135436) (xy 44.979589 -299.147025) (xy 44.925233 -299.150918) (xy 44.870876 -299.147034)
			(xy 44.817625 -299.135454) (xy 44.766564 -299.116413) (xy 44.718733 -299.090298) (xy 44.675106 -299.057642)
			(xy 44.636571 -299.019108) (xy 44.603912 -298.975483) (xy 44.577795 -298.927653) (xy 44.558751 -298.876593)
			(xy 44.547168 -298.823343) (xy 44.543282 -298.768986) (xy 44.165266 -298.768986) (xy 44.161379 -298.82335)
			(xy 44.149795 -298.876608) (xy 44.130748 -298.927675) (xy 44.104627 -298.975511) (xy 44.071963 -299.019143)
			(xy 44.033422 -299.057681) (xy 43.989788 -299.090342) (xy 43.94195 -299.116459) (xy 43.890882 -299.135502)
			(xy 43.837623 -299.147083) (xy 43.783258 -299.150966) (xy 43.728894 -299.147071) (xy 43.675638 -299.135479)
			(xy 43.624573 -299.116424) (xy 43.576741 -299.090296) (xy 43.55465 -299.074332) (xy 43.535638 -299.060736)
			(xy 43.493755 -299.040004) (xy 43.448787 -299.027278) (xy 43.40225 -299.022988) (xy 43.355713 -299.027278)
			(xy 43.310745 -299.040004) (xy 43.268862 -299.060736) (xy 43.24985 -299.074332) (xy 43.227738 -299.090264)
			(xy 43.179911 -299.116389) (xy 43.128852 -299.135442) (xy 43.075601 -299.147033) (xy 43.021242 -299.150927)
			(xy 42.966883 -299.147045) (xy 42.913629 -299.135466) (xy 42.862566 -299.116424) (xy 42.814733 -299.090309)
			(xy 42.771103 -299.057652) (xy 42.732566 -299.019118) (xy 42.699906 -298.975491) (xy 42.673787 -298.927659)
			(xy 42.654742 -298.876597) (xy 42.643159 -298.823345) (xy 42.639273 -298.768986) (xy 41.924131 -298.768986)
			(xy 41.920245 -298.823342) (xy 41.908663 -298.876593) (xy 41.88962 -298.927653) (xy 41.863504 -298.975483)
			(xy 41.830847 -299.019109) (xy 41.792313 -299.057643) (xy 41.748687 -299.090301) (xy 41.700857 -299.116418)
			(xy 41.649798 -299.135461) (xy 41.596548 -299.147044) (xy 41.542191 -299.150931) (xy 41.487834 -299.147042)
			(xy 41.434585 -299.135456) (xy 41.383526 -299.11641) (xy 41.335698 -299.090291) (xy 41.313608 -299.074332)
			(xy 41.294596 -299.060736) (xy 41.252713 -299.040004) (xy 41.207745 -299.027278) (xy 41.161208 -299.022988)
			(xy 41.114671 -299.027278) (xy 41.069703 -299.040004) (xy 41.02782 -299.060736) (xy 41.008808 -299.074332)
			(xy 40.986697 -299.09026) (xy 40.938872 -299.116379) (xy 40.887817 -299.135426) (xy 40.834571 -299.147012)
			(xy 40.780218 -299.150902) (xy 40.725865 -299.147017) (xy 40.672618 -299.135436) (xy 40.621561 -299.116394)
			(xy 40.573733 -299.09028) (xy 40.53011 -299.057625) (xy 40.491578 -299.019093) (xy 40.458922 -298.97547)
			(xy 40.432807 -298.927643) (xy 40.413765 -298.876586) (xy 40.402183 -298.823339) (xy 40.398298 -298.768986)
			(xy 40.037438 -298.768986) (xy 40.033552 -298.823344) (xy 40.021969 -298.876596) (xy 40.002926 -298.927657)
			(xy 39.976809 -298.975489) (xy 39.94415 -299.019116) (xy 39.905615 -299.057651) (xy 39.861987 -299.090309)
			(xy 39.814156 -299.116426) (xy 39.763094 -299.13547) (xy 39.709842 -299.147052) (xy 39.655484 -299.150938)
			(xy 39.601126 -299.147048) (xy 39.547875 -299.135461) (xy 39.496815 -299.116413) (xy 39.448986 -299.090292)
			(xy 39.426896 -299.074332) (xy 39.407884 -299.060736) (xy 39.366001 -299.040004) (xy 39.321033 -299.027278)
			(xy 39.274496 -299.022988) (xy 39.227959 -299.027278) (xy 39.182991 -299.040004) (xy 39.141108 -299.060736)
			(xy 39.122096 -299.074332) (xy 39.099985 -299.090259) (xy 39.052162 -299.116376) (xy 39.001108 -299.135421)
			(xy 38.947863 -299.147006) (xy 38.893511 -299.150895) (xy 38.83916 -299.147009) (xy 38.785914 -299.135427)
			(xy 38.734859 -299.116386) (xy 38.687034 -299.090272) (xy 38.643412 -299.057617) (xy 38.604881 -299.019086)
			(xy 38.572227 -298.975464) (xy 38.546113 -298.927638) (xy 38.527072 -298.876583) (xy 38.515491 -298.823337)
			(xy 38.511605 -298.768986) (xy 28.912312 -298.768986) (xy 28.912312 -300.31336) (xy 29.519874 -300.31336)
			(xy 29.519874 -300.22646) (xy 29.527892 -300.139931) (xy 29.54386 -300.054511) (xy 29.567641 -299.970929)
			(xy 29.599033 -299.889897) (xy 29.637767 -299.812108) (xy 29.683514 -299.738224) (xy 29.735883 -299.668877)
			(xy 29.794427 -299.604657) (xy 29.858647 -299.546113) (xy 29.927994 -299.493744) (xy 30.001878 -299.447997)
			(xy 30.079667 -299.409263) (xy 30.160699 -299.377871) (xy 30.244281 -299.35409) (xy 30.329701 -299.338122)
			(xy 30.41623 -299.330104) (xy 30.50313 -299.330104) (xy 30.589659 -299.338122) (xy 30.675079 -299.35409)
			(xy 30.758661 -299.377871) (xy 30.839693 -299.409263) (xy 30.917482 -299.447997) (xy 30.991366 -299.493744)
			(xy 31.060713 -299.546113) (xy 31.124933 -299.604657) (xy 31.183477 -299.668877) (xy 31.235846 -299.738224)
			(xy 31.281593 -299.812108) (xy 31.320327 -299.889897) (xy 31.351719 -299.970929) (xy 31.3755 -300.054511)
			(xy 31.391468 -300.139931) (xy 31.399486 -300.22646) (xy 31.399988 -300.26991) (xy 31.399486 -300.31336)
			(xy 34.599874 -300.31336) (xy 34.599874 -300.22646) (xy 34.607892 -300.139931) (xy 34.62386 -300.054511)
			(xy 34.647641 -299.970929) (xy 34.679033 -299.889897) (xy 34.717767 -299.812108) (xy 34.763514 -299.738224)
			(xy 34.815883 -299.668877) (xy 34.874427 -299.604657) (xy 34.938647 -299.546113) (xy 35.007994 -299.493744)
			(xy 35.081878 -299.447997) (xy 35.159667 -299.409263) (xy 35.240699 -299.377871) (xy 35.324281 -299.35409)
			(xy 35.409701 -299.338122) (xy 35.49623 -299.330104) (xy 35.58313 -299.330104) (xy 35.669659 -299.338122)
			(xy 35.755079 -299.35409) (xy 35.838661 -299.377871) (xy 35.919693 -299.409263) (xy 35.997482 -299.447997)
			(xy 36.071366 -299.493744) (xy 36.140713 -299.546113) (xy 36.204933 -299.604657) (xy 36.263477 -299.668877)
			(xy 36.271585 -299.679614) (xy 97.869246 -299.679614) (xy 97.873317 -299.623992) (xy 97.885443 -299.569555)
			(xy 97.905366 -299.517464) (xy 97.932662 -299.468829) (xy 97.966748 -299.424686) (xy 98.006897 -299.385977)
			(xy 98.052255 -299.353526) (xy 98.101855 -299.328025) (xy 98.154639 -299.310018) (xy 98.209482 -299.299888)
			(xy 98.265216 -299.297851) (xy 98.320653 -299.303951) (xy 98.37461 -299.318057) (xy 98.425939 -299.339869)
			(xy 98.473545 -299.368923) (xy 98.516413 -299.404598) (xy 98.55363 -299.446135) (xy 98.584403 -299.492648)
			(xy 98.608075 -299.543145) (xy 98.624143 -299.596552) (xy 98.632263 -299.651728) (xy 98.632772 -299.679614)
			(xy 98.632263 -299.7075) (xy 98.624143 -299.762676) (xy 98.608075 -299.816083) (xy 98.584403 -299.86658)
			(xy 98.55363 -299.913093) (xy 98.516413 -299.95463) (xy 98.473545 -299.990305) (xy 98.425939 -300.019359)
			(xy 98.37461 -300.041171) (xy 98.320653 -300.055277) (xy 98.265216 -300.061377) (xy 98.209482 -300.05934)
			(xy 98.154639 -300.04921) (xy 98.101855 -300.031203) (xy 98.052255 -300.005702) (xy 98.006897 -299.973251)
			(xy 97.966748 -299.934542) (xy 97.932662 -299.890399) (xy 97.905366 -299.841764) (xy 97.885443 -299.789673)
			(xy 97.873317 -299.735236) (xy 97.869246 -299.679614) (xy 36.271585 -299.679614) (xy 36.315846 -299.738224)
			(xy 36.361593 -299.812108) (xy 36.400327 -299.889897) (xy 36.431719 -299.970929) (xy 36.4555 -300.054511)
			(xy 36.471468 -300.139931) (xy 36.479486 -300.22646) (xy 36.479988 -300.26991) (xy 36.479486 -300.31336)
			(xy 36.471468 -300.399889) (xy 36.4555 -300.485309) (xy 36.431719 -300.568891) (xy 36.400327 -300.649923)
			(xy 36.390318 -300.670024) (xy 38.511554 -300.670024) (xy 38.515438 -300.615665) (xy 38.52702 -300.562412)
			(xy 38.546063 -300.511349) (xy 38.572179 -300.463517) (xy 38.604836 -300.419888) (xy 38.643371 -300.381351)
			(xy 38.686998 -300.348691) (xy 38.734829 -300.322572) (xy 38.785891 -300.303526) (xy 38.839143 -300.291942)
			(xy 38.893502 -300.288054) (xy 38.947861 -300.291942) (xy 39.001113 -300.303527) (xy 39.052174 -300.322573)
			(xy 39.100005 -300.348692) (xy 39.122096 -300.364652) (xy 39.141108 -300.378248) (xy 39.182991 -300.39898)
			(xy 39.227959 -300.411706) (xy 39.274496 -300.415996) (xy 39.321033 -300.411706) (xy 39.366001 -300.39898)
			(xy 39.407884 -300.378248) (xy 39.426896 -300.364652) (xy 39.449022 -300.348746) (xy 39.496845 -300.32263)
			(xy 39.547899 -300.303586) (xy 39.601143 -300.292001) (xy 39.655494 -300.288113) (xy 39.709845 -300.292)
			(xy 39.763089 -300.303582) (xy 39.814143 -300.322624) (xy 39.861968 -300.348739) (xy 39.905588 -300.381394)
			(xy 39.944118 -300.419925) (xy 39.976771 -300.463547) (xy 40.002883 -300.511373) (xy 40.021923 -300.562428)
			(xy 40.033503 -300.615673) (xy 40.037387 -300.670024) (xy 40.398247 -300.670024) (xy 40.402131 -300.615663)
			(xy 40.413713 -300.562409) (xy 40.432757 -300.511345) (xy 40.458874 -300.463511) (xy 40.491533 -300.419881)
			(xy 40.530069 -300.381343) (xy 40.573698 -300.348682) (xy 40.621531 -300.322563) (xy 40.672594 -300.303518)
			(xy 40.725848 -300.291934) (xy 40.780209 -300.288047) (xy 40.834569 -300.291936) (xy 40.887823 -300.303523)
			(xy 40.938885 -300.32257) (xy 40.986717 -300.348691) (xy 41.008808 -300.364652) (xy 41.02782 -300.378248)
			(xy 41.069703 -300.39898) (xy 41.114671 -300.411706) (xy 41.161208 -300.415996) (xy 41.207745 -300.411706)
			(xy 41.252713 -300.39898) (xy 41.294596 -300.378248) (xy 41.313608 -300.364652) (xy 41.335733 -300.348747)
			(xy 41.383556 -300.322632) (xy 41.434608 -300.30359) (xy 41.487851 -300.292008) (xy 41.542201 -300.28812)
			(xy 41.59655 -300.292008) (xy 41.649793 -300.30359) (xy 41.700845 -300.322633) (xy 41.748667 -300.348747)
			(xy 41.792286 -300.381402) (xy 41.830814 -300.419932) (xy 41.863466 -300.463553) (xy 41.889577 -300.511377)
			(xy 41.908616 -300.562431) (xy 41.920196 -300.615674) (xy 41.92408 -300.670024) (xy 42.639221 -300.670024)
			(xy 42.643107 -300.615657) (xy 42.65469 -300.562397) (xy 42.673737 -300.511328) (xy 42.699857 -300.46349)
			(xy 42.732521 -300.419856) (xy 42.771062 -300.381315) (xy 42.814697 -300.348653) (xy 42.862536 -300.322533)
			(xy 42.913606 -300.303488) (xy 42.966866 -300.291906) (xy 43.021232 -300.288021) (xy 43.075598 -300.291915)
			(xy 43.128857 -300.303506) (xy 43.179923 -300.32256) (xy 43.227758 -300.348688) (xy 43.24985 -300.364652)
			(xy 43.268862 -300.378248) (xy 43.310745 -300.39898) (xy 43.355713 -300.411706) (xy 43.40225 -300.415996)
			(xy 43.448787 -300.411706) (xy 43.493755 -300.39898) (xy 43.535638 -300.378248) (xy 43.55465 -300.364652)
			(xy 43.576777 -300.348742) (xy 43.624603 -300.322618) (xy 43.675661 -300.303568) (xy 43.728911 -300.291978)
			(xy 43.783268 -300.288086) (xy 43.837625 -300.291969) (xy 43.890876 -300.303549) (xy 43.941937 -300.322591)
			(xy 43.989769 -300.348707) (xy 44.033396 -300.381364) (xy 44.071931 -300.419898) (xy 44.104589 -300.463524)
			(xy 44.130705 -300.511355) (xy 44.149748 -300.562415) (xy 44.16133 -300.615667) (xy 44.165214 -300.670024)
			(xy 44.543231 -300.670024) (xy 44.547116 -300.61566) (xy 44.558699 -300.562402) (xy 44.577744 -300.511334)
			(xy 44.603864 -300.463498) (xy 44.636526 -300.419865) (xy 44.675065 -300.381326) (xy 44.718697 -300.348664)
			(xy 44.766534 -300.322545) (xy 44.817601 -300.303499) (xy 44.870859 -300.291916) (xy 44.925223 -300.288031)
			(xy 44.979587 -300.291923) (xy 45.032844 -300.303513) (xy 45.083909 -300.322564) (xy 45.131742 -300.348689)
			(xy 45.153834 -300.364652) (xy 45.172846 -300.378248) (xy 45.214729 -300.39898) (xy 45.259697 -300.411706)
			(xy 45.306234 -300.415996) (xy 45.352771 -300.411706) (xy 45.397739 -300.39898) (xy 45.439622 -300.378248)
			(xy 45.458634 -300.364652) (xy 45.480759 -300.348749) (xy 45.52858 -300.322639) (xy 45.57963 -300.3036)
			(xy 45.632869 -300.292021) (xy 45.687215 -300.288136) (xy 45.741561 -300.292025) (xy 45.7948 -300.303609)
			(xy 45.845848 -300.322652) (xy 45.893667 -300.348765) (xy 45.937282 -300.381419) (xy 45.975807 -300.419947)
			(xy 46.008456 -300.463566) (xy 46.034565 -300.511388) (xy 46.053602 -300.562438) (xy 46.065181 -300.615678)
			(xy 46.069064 -300.670024) (xy 46.065174 -300.724369) (xy 46.055126 -300.770544) (xy 96.970086 -300.770544)
			(xy 96.974157 -300.714922) (xy 96.986283 -300.660485) (xy 97.006206 -300.608394) (xy 97.033502 -300.559759)
			(xy 97.067588 -300.515616) (xy 97.107737 -300.476907) (xy 97.153095 -300.444456) (xy 97.202695 -300.418955)
			(xy 97.255479 -300.400948) (xy 97.310322 -300.390818) (xy 97.366056 -300.388781) (xy 97.421493 -300.394881)
			(xy 97.47545 -300.408987) (xy 97.526779 -300.430799) (xy 97.574385 -300.459853) (xy 97.617253 -300.495528)
			(xy 97.65447 -300.537065) (xy 97.685243 -300.583578) (xy 97.708915 -300.634075) (xy 97.724983 -300.687482)
			(xy 97.733103 -300.742658) (xy 97.733612 -300.770544) (xy 97.733103 -300.79843) (xy 97.724983 -300.853606)
			(xy 97.708915 -300.907013) (xy 97.685243 -300.95751) (xy 97.65447 -301.004023) (xy 97.617253 -301.04556)
			(xy 97.574385 -301.081235) (xy 97.526779 -301.110289) (xy 97.47545 -301.132101) (xy 97.421493 -301.146207)
			(xy 97.366056 -301.152307) (xy 97.310322 -301.15027) (xy 97.255479 -301.14014) (xy 97.202695 -301.122133)
			(xy 97.153095 -301.096632) (xy 97.107737 -301.064181) (xy 97.067588 -301.025472) (xy 97.033502 -300.981329)
			(xy 97.006206 -300.932694) (xy 96.986283 -300.880603) (xy 96.974157 -300.826166) (xy 96.970086 -300.770544)
			(xy 46.055126 -300.770544) (xy 46.053589 -300.777608) (xy 46.034545 -300.828656) (xy 46.00843 -300.876474)
			(xy 45.975775 -300.920089) (xy 45.937246 -300.958612) (xy 45.893626 -300.991261) (xy 45.845805 -301.017368)
			(xy 45.794754 -301.036405) (xy 45.741513 -301.047982) (xy 45.687167 -301.051864) (xy 45.632822 -301.047973)
			(xy 45.579584 -301.036386) (xy 45.528536 -301.017341) (xy 45.480718 -300.991225) (xy 45.458634 -300.975268)
			(xy 45.439622 -300.961672) (xy 45.397739 -300.94094) (xy 45.352771 -300.928214) (xy 45.306234 -300.923924)
			(xy 45.259697 -300.928214) (xy 45.214729 -300.94094) (xy 45.172846 -300.961672) (xy 45.153834 -300.975268)
			(xy 45.131783 -300.991285) (xy 45.083952 -301.017416) (xy 45.03289 -301.036474) (xy 44.979635 -301.04807)
			(xy 44.925271 -301.051969) (xy 44.870907 -301.048091) (xy 44.817647 -301.036514) (xy 44.766578 -301.017475)
			(xy 44.718738 -300.991362) (xy 44.675101 -300.958705) (xy 44.636557 -300.920171) (xy 44.60389 -300.876543)
			(xy 44.577764 -300.828709) (xy 44.558713 -300.777644) (xy 44.547123 -300.724388) (xy 44.543231 -300.670024)
			(xy 44.165214 -300.670024) (xy 44.161323 -300.724381) (xy 44.149735 -300.777631) (xy 44.130685 -300.828689)
			(xy 44.104563 -300.876516) (xy 44.071899 -300.920138) (xy 44.033359 -300.958668) (xy 43.989728 -300.991319)
			(xy 43.941894 -301.017429) (xy 43.89083 -301.036464) (xy 43.837578 -301.048038) (xy 43.78322 -301.051914)
			(xy 43.728863 -301.048015) (xy 43.675615 -301.036419) (xy 43.62456 -301.017362) (xy 43.576736 -300.991232)
			(xy 43.55465 -300.975268) (xy 43.535638 -300.961672) (xy 43.493755 -300.94094) (xy 43.448787 -300.928214)
			(xy 43.40225 -300.923924) (xy 43.355713 -300.928214) (xy 43.310745 -300.94094) (xy 43.268862 -300.961672)
			(xy 43.24985 -300.975268) (xy 43.227798 -300.991286) (xy 43.179967 -301.01742) (xy 43.128903 -301.03648)
			(xy 43.075646 -301.048078) (xy 43.021281 -301.051979) (xy 42.966913 -301.048101) (xy 42.913652 -301.036525)
			(xy 42.86258 -301.017487) (xy 42.814737 -300.991373) (xy 42.771099 -300.958716) (xy 42.732552 -300.92018)
			(xy 42.699883 -300.876551) (xy 42.673757 -300.828715) (xy 42.654704 -300.777649) (xy 42.643114 -300.72439)
			(xy 42.639221 -300.670024) (xy 41.92408 -300.670024) (xy 41.920189 -300.724373) (xy 41.908603 -300.777615)
			(xy 41.889557 -300.828666) (xy 41.86344 -300.876487) (xy 41.830783 -300.920104) (xy 41.79225 -300.95863)
			(xy 41.748627 -300.991279) (xy 41.700801 -301.017387) (xy 41.649746 -301.036423) (xy 41.596502 -301.047999)
			(xy 41.542153 -301.05188) (xy 41.487804 -301.047986) (xy 41.434562 -301.036396) (xy 41.383512 -301.017348)
			(xy 41.335693 -300.991227) (xy 41.313608 -300.975268) (xy 41.294596 -300.961672) (xy 41.252713 -300.94094)
			(xy 41.207745 -300.928214) (xy 41.161208 -300.923924) (xy 41.114671 -300.928214) (xy 41.069703 -300.94094)
			(xy 41.02782 -300.961672) (xy 41.008808 -300.975268) (xy 40.986757 -300.991283) (xy 40.938929 -301.01741)
			(xy 40.887869 -301.036464) (xy 40.834617 -301.048057) (xy 40.780257 -301.051953) (xy 40.725895 -301.048073)
			(xy 40.67264 -301.036496) (xy 40.621574 -301.017457) (xy 40.573738 -300.991344) (xy 40.530105 -300.958688)
			(xy 40.491564 -300.920156) (xy 40.4589 -300.87653) (xy 40.432777 -300.828699) (xy 40.413727 -300.777637)
			(xy 40.402138 -300.724384) (xy 40.398247 -300.670024) (xy 40.037387 -300.670024) (xy 40.033496 -300.724375)
			(xy 40.021909 -300.777618) (xy 40.002863 -300.828671) (xy 39.976745 -300.876493) (xy 39.944086 -300.920111)
			(xy 39.905552 -300.958637) (xy 39.861927 -300.991287) (xy 39.8141 -301.017396) (xy 39.763043 -301.036432)
			(xy 39.709797 -301.048007) (xy 39.655446 -301.051887) (xy 39.601095 -301.047992) (xy 39.547853 -301.036401)
			(xy 39.496802 -301.017351) (xy 39.448981 -300.991228) (xy 39.426896 -300.975268) (xy 39.407884 -300.961672)
			(xy 39.366001 -300.94094) (xy 39.321033 -300.928214) (xy 39.274496 -300.923924) (xy 39.227959 -300.928214)
			(xy 39.182991 -300.94094) (xy 39.141108 -300.961672) (xy 39.122096 -300.975268) (xy 39.100045 -300.991282)
			(xy 39.052218 -301.017407) (xy 39.001159 -301.036459) (xy 38.947908 -301.048051) (xy 38.89355 -301.051946)
			(xy 38.83919 -301.048065) (xy 38.785937 -301.036487) (xy 38.734873 -301.017448) (xy 38.687038 -300.991335)
			(xy 38.643407 -300.958681) (xy 38.604868 -300.920149) (xy 38.572205 -300.876524) (xy 38.546082 -300.828694)
			(xy 38.527033 -300.777634) (xy 38.515445 -300.724383) (xy 38.511554 -300.670024) (xy 36.390318 -300.670024)
			(xy 36.361593 -300.727712) (xy 36.315846 -300.801596) (xy 36.263477 -300.870943) (xy 36.204933 -300.935163)
			(xy 36.140713 -300.993707) (xy 36.071366 -301.046076) (xy 35.997482 -301.091823) (xy 35.919693 -301.130557)
			(xy 35.838661 -301.161949) (xy 35.755079 -301.18573) (xy 35.669659 -301.201698) (xy 35.58313 -301.209716)
			(xy 35.49623 -301.209716) (xy 35.409701 -301.201698) (xy 35.324281 -301.18573) (xy 35.240699 -301.161949)
			(xy 35.159667 -301.130557) (xy 35.081878 -301.091823) (xy 35.007994 -301.046076) (xy 34.938647 -300.993707)
			(xy 34.874427 -300.935163) (xy 34.815883 -300.870943) (xy 34.763514 -300.801596) (xy 34.717767 -300.727712)
			(xy 34.679033 -300.649923) (xy 34.647641 -300.568891) (xy 34.62386 -300.485309) (xy 34.607892 -300.399889)
			(xy 34.599874 -300.31336) (xy 31.399486 -300.31336) (xy 31.391468 -300.399889) (xy 31.3755 -300.485309)
			(xy 31.351719 -300.568891) (xy 31.320327 -300.649923) (xy 31.281593 -300.727712) (xy 31.235846 -300.801596)
			(xy 31.183477 -300.870943) (xy 31.124933 -300.935163) (xy 31.060713 -300.993707) (xy 30.991366 -301.046076)
			(xy 30.917482 -301.091823) (xy 30.839693 -301.130557) (xy 30.758661 -301.161949) (xy 30.675079 -301.18573)
			(xy 30.589659 -301.201698) (xy 30.50313 -301.209716) (xy 30.41623 -301.209716) (xy 30.329701 -301.201698)
			(xy 30.244281 -301.18573) (xy 30.160699 -301.161949) (xy 30.079667 -301.130557) (xy 30.001878 -301.091823)
			(xy 29.927994 -301.046076) (xy 29.858647 -300.993707) (xy 29.794427 -300.935163) (xy 29.735883 -300.870943)
			(xy 29.683514 -300.801596) (xy 29.637767 -300.727712) (xy 29.599033 -300.649923) (xy 29.567641 -300.568891)
			(xy 29.54386 -300.485309) (xy 29.527892 -300.399889) (xy 29.519874 -300.31336) (xy 28.912312 -300.31336)
			(xy 28.912312 -302.85336) (xy 29.519874 -302.85336) (xy 29.519874 -302.76646) (xy 29.527892 -302.679931)
			(xy 29.54386 -302.594511) (xy 29.567641 -302.510929) (xy 29.599033 -302.429897) (xy 29.637767 -302.352108)
			(xy 29.683514 -302.278224) (xy 29.735883 -302.208877) (xy 29.794427 -302.144657) (xy 29.858647 -302.086113)
			(xy 29.927994 -302.033744) (xy 30.001878 -301.987997) (xy 30.079667 -301.949263) (xy 30.160699 -301.917871)
			(xy 30.244281 -301.89409) (xy 30.329701 -301.878122) (xy 30.41623 -301.870104) (xy 30.50313 -301.870104)
			(xy 30.589659 -301.878122) (xy 30.675079 -301.89409) (xy 30.758661 -301.917871) (xy 30.839693 -301.949263)
			(xy 30.917482 -301.987997) (xy 30.991366 -302.033744) (xy 31.060713 -302.086113) (xy 31.124933 -302.144657)
			(xy 31.183477 -302.208877) (xy 31.235846 -302.278224) (xy 31.281593 -302.352108) (xy 31.320327 -302.429897)
			(xy 31.351719 -302.510929) (xy 31.3755 -302.594511) (xy 31.391468 -302.679931) (xy 31.399486 -302.76646)
			(xy 31.399988 -302.80991) (xy 31.399486 -302.85336) (xy 34.599874 -302.85336) (xy 34.599874 -302.76646)
			(xy 34.607892 -302.679931) (xy 34.62386 -302.594511) (xy 34.647641 -302.510929) (xy 34.679033 -302.429897)
			(xy 34.717767 -302.352108) (xy 34.763514 -302.278224) (xy 34.815883 -302.208877) (xy 34.874427 -302.144657)
			(xy 34.938647 -302.086113) (xy 35.007994 -302.033744) (xy 35.081878 -301.987997) (xy 35.159667 -301.949263)
			(xy 35.240699 -301.917871) (xy 35.324281 -301.89409) (xy 35.409701 -301.878122) (xy 35.49623 -301.870104)
			(xy 35.58313 -301.870104) (xy 35.669659 -301.878122) (xy 35.755079 -301.89409) (xy 35.838661 -301.917871)
			(xy 35.919693 -301.949263) (xy 35.997482 -301.987997) (xy 36.071366 -302.033744) (xy 36.140713 -302.086113)
			(xy 36.204933 -302.144657) (xy 36.263477 -302.208877) (xy 36.315846 -302.278224) (xy 36.357258 -302.345106)
			(xy 38.511578 -302.345106) (xy 38.515465 -302.29075) (xy 38.527048 -302.237501) (xy 38.546092 -302.186443)
			(xy 38.572208 -302.138614) (xy 38.604866 -302.09499) (xy 38.6434 -302.056457) (xy 38.687026 -302.023801)
			(xy 38.734855 -301.997686) (xy 38.785915 -301.978644) (xy 38.839164 -301.967063) (xy 38.89352 -301.963178)
			(xy 38.947875 -301.967068) (xy 39.001123 -301.978655) (xy 39.052181 -301.997703) (xy 39.100007 -302.023822)
			(xy 39.122096 -302.039782) (xy 39.141108 -302.053378) (xy 39.182991 -302.07411) (xy 39.227959 -302.086836)
			(xy 39.274496 -302.091126) (xy 39.321033 -302.086836) (xy 39.366001 -302.07411) (xy 39.407884 -302.053378)
			(xy 39.426896 -302.039782) (xy 39.448994 -302.023835) (xy 39.496819 -301.997715) (xy 39.547875 -301.978668)
			(xy 39.601122 -301.96708) (xy 39.655476 -301.963189) (xy 39.70983 -301.967073) (xy 39.763079 -301.978654)
			(xy 39.814137 -301.997695) (xy 39.861965 -302.023809) (xy 39.90559 -302.056464) (xy 39.944124 -302.094996)
			(xy 39.976781 -302.138619) (xy 40.002897 -302.186446) (xy 40.021941 -302.237504) (xy 40.033524 -302.290752)
			(xy 40.037411 -302.345106) (xy 40.398271 -302.345106) (xy 40.402158 -302.290749) (xy 40.413741 -302.237498)
			(xy 40.432786 -302.186438) (xy 40.458904 -302.138608) (xy 40.491563 -302.094983) (xy 40.530098 -302.056449)
			(xy 40.573726 -302.023793) (xy 40.621557 -301.997678) (xy 40.672618 -301.978636) (xy 40.725869 -301.967055)
			(xy 40.780227 -301.963171) (xy 40.834583 -301.967062) (xy 40.887833 -301.978651) (xy 40.938891 -301.9977)
			(xy 40.986719 -302.023821) (xy 41.008808 -302.039782) (xy 41.02782 -302.053378) (xy 41.069703 -302.07411)
			(xy 41.114671 -302.086836) (xy 41.161208 -302.091126) (xy 41.207745 -302.086836) (xy 41.252713 -302.07411)
			(xy 41.294596 -302.053378) (xy 41.313608 -302.039782) (xy 41.335705 -302.023836) (xy 41.38353 -301.997718)
			(xy 41.434584 -301.978672) (xy 41.48783 -301.967086) (xy 41.542183 -301.963196) (xy 41.596535 -301.967081)
			(xy 41.649782 -301.978662) (xy 41.700838 -301.997704) (xy 41.748665 -302.023817) (xy 41.792289 -302.056472)
			(xy 41.830821 -302.095003) (xy 41.863476 -302.138625) (xy 41.889592 -302.186451) (xy 41.908634 -302.237507)
			(xy 41.920217 -302.290753) (xy 41.924104 -302.345106) (xy 42.639246 -302.345106) (xy 42.643133 -302.290743)
			(xy 42.654719 -302.237487) (xy 42.673766 -302.186422) (xy 42.699887 -302.138588) (xy 42.732551 -302.094958)
			(xy 42.771092 -302.056422) (xy 42.814725 -302.023763) (xy 42.862562 -301.997647) (xy 42.91363 -301.978606)
			(xy 42.966887 -301.967027) (xy 43.02125 -301.963146) (xy 43.075613 -301.967041) (xy 43.128867 -301.978634)
			(xy 43.17993 -301.997689) (xy 43.22776 -302.023818) (xy 43.24985 -302.039782) (xy 43.268862 -302.053378)
			(xy 43.310745 -302.07411) (xy 43.355713 -302.086836) (xy 43.40225 -302.091126) (xy 43.448787 -302.086836)
			(xy 43.493755 -302.07411) (xy 43.535638 -302.053378) (xy 43.55465 -302.039782) (xy 43.576749 -302.023831)
			(xy 43.624577 -301.997704) (xy 43.675637 -301.97865) (xy 43.728889 -301.967057) (xy 43.78325 -301.963162)
			(xy 43.837611 -301.967043) (xy 43.890866 -301.978621) (xy 43.941931 -301.997662) (xy 43.989766 -302.023777)
			(xy 44.033398 -302.056434) (xy 44.071937 -302.094969) (xy 44.104599 -302.138596) (xy 44.13072 -302.186428)
			(xy 44.149766 -302.237491) (xy 44.161351 -302.290745) (xy 44.165238 -302.345106) (xy 44.543255 -302.345106)
			(xy 44.547143 -302.290745) (xy 44.558727 -302.237491) (xy 44.577774 -302.186428) (xy 44.603894 -302.138596)
			(xy 44.636555 -302.094968) (xy 44.675094 -302.056432) (xy 44.718725 -302.023774) (xy 44.76656 -301.997659)
			(xy 44.817625 -301.978617) (xy 44.87088 -301.967037) (xy 44.925241 -301.963155) (xy 44.979602 -301.967049)
			(xy 45.032854 -301.978641) (xy 45.083915 -301.997693) (xy 45.131744 -302.023819) (xy 45.153834 -302.039782)
			(xy 45.172846 -302.053378) (xy 45.214729 -302.07411) (xy 45.259697 -302.086836) (xy 45.306234 -302.091126)
			(xy 45.352771 -302.086836) (xy 45.397739 -302.07411) (xy 45.439622 -302.053378) (xy 45.458634 -302.039782)
			(xy 45.480731 -302.023838) (xy 45.528553 -301.997724) (xy 45.579606 -301.978682) (xy 45.632848 -301.967099)
			(xy 45.687197 -301.963212) (xy 45.741546 -301.967099) (xy 45.794789 -301.978681) (xy 45.845842 -301.997722)
			(xy 45.893665 -302.023836) (xy 45.937284 -302.056489) (xy 45.975813 -302.095018) (xy 46.008466 -302.138638)
			(xy 46.034579 -302.186461) (xy 46.040976 -302.203612) (xy 95.969072 -302.203612) (xy 95.973143 -302.14799)
			(xy 95.985269 -302.093553) (xy 96.005192 -302.041462) (xy 96.032488 -301.992827) (xy 96.066574 -301.948684)
			(xy 96.106723 -301.909975) (xy 96.152081 -301.877524) (xy 96.201681 -301.852023) (xy 96.254465 -301.834016)
			(xy 96.309308 -301.823886) (xy 96.365042 -301.821849) (xy 96.420479 -301.827949) (xy 96.474436 -301.842055)
			(xy 96.525765 -301.863867) (xy 96.573371 -301.892921) (xy 96.616239 -301.928596) (xy 96.653456 -301.970133)
			(xy 96.684229 -302.016646) (xy 96.707901 -302.067143) (xy 96.723969 -302.12055) (xy 96.732089 -302.175726)
			(xy 96.732598 -302.203612) (xy 96.732089 -302.231498) (xy 96.723969 -302.286674) (xy 96.707901 -302.340081)
			(xy 96.684229 -302.390578) (xy 96.653456 -302.437091) (xy 96.616239 -302.478628) (xy 96.573371 -302.514303)
			(xy 96.525765 -302.543357) (xy 96.474436 -302.565169) (xy 96.420479 -302.579275) (xy 96.365042 -302.585375)
			(xy 96.309308 -302.583338) (xy 96.254465 -302.573208) (xy 96.201681 -302.555201) (xy 96.152081 -302.5297)
			(xy 96.106723 -302.497249) (xy 96.066574 -302.45854) (xy 96.032488 -302.414397) (xy 96.005192 -302.365762)
			(xy 95.985269 -302.313671) (xy 95.973143 -302.259234) (xy 95.969072 -302.203612) (xy 46.040976 -302.203612)
			(xy 46.05362 -302.237514) (xy 46.065202 -302.290757) (xy 46.069088 -302.345106) (xy 46.0652 -302.399455)
			(xy 46.053617 -302.452698) (xy 46.034574 -302.50375) (xy 46.00846 -302.551572) (xy 45.975805 -302.595191)
			(xy 45.937275 -302.633719) (xy 45.893655 -302.666371) (xy 45.845831 -302.692483) (xy 45.79522 -302.711358)
			(xy 66.307968 -302.711358) (xy 66.312039 -302.655736) (xy 66.324165 -302.601299) (xy 66.344088 -302.549208)
			(xy 66.371384 -302.500573) (xy 66.40547 -302.45643) (xy 66.445619 -302.417721) (xy 66.490977 -302.38527)
			(xy 66.540577 -302.359769) (xy 66.593361 -302.341762) (xy 66.648204 -302.331632) (xy 66.703938 -302.329595)
			(xy 66.759375 -302.335695) (xy 66.813332 -302.349801) (xy 66.864661 -302.371613) (xy 66.912267 -302.400667)
			(xy 66.955135 -302.436342) (xy 66.992352 -302.477879) (xy 67.023125 -302.524392) (xy 67.046797 -302.574889)
			(xy 67.062865 -302.628296) (xy 67.070985 -302.683472) (xy 67.071494 -302.711358) (xy 67.485258 -302.711358)
			(xy 67.489329 -302.655736) (xy 67.501455 -302.601299) (xy 67.521378 -302.549208) (xy 67.548674 -302.500573)
			(xy 67.58276 -302.45643) (xy 67.622909 -302.417721) (xy 67.668267 -302.38527) (xy 67.717867 -302.359769)
			(xy 67.770651 -302.341762) (xy 67.825494 -302.331632) (xy 67.881228 -302.329595) (xy 67.936665 -302.335695)
			(xy 67.990622 -302.349801) (xy 68.041951 -302.371613) (xy 68.089557 -302.400667) (xy 68.132425 -302.436342)
			(xy 68.169642 -302.477879) (xy 68.200415 -302.524392) (xy 68.224087 -302.574889) (xy 68.240155 -302.628296)
			(xy 68.248275 -302.683472) (xy 68.248784 -302.711358) (xy 68.72681 -302.711358) (xy 68.730881 -302.655736)
			(xy 68.743007 -302.601299) (xy 68.76293 -302.549208) (xy 68.790226 -302.500573) (xy 68.824312 -302.45643)
			(xy 68.864461 -302.417721) (xy 68.909819 -302.38527) (xy 68.959419 -302.359769) (xy 69.012203 -302.341762)
			(xy 69.067046 -302.331632) (xy 69.12278 -302.329595) (xy 69.178217 -302.335695) (xy 69.232174 -302.349801)
			(xy 69.283503 -302.371613) (xy 69.331109 -302.400667) (xy 69.373977 -302.436342) (xy 69.411194 -302.477879)
			(xy 69.441967 -302.524392) (xy 69.465639 -302.574889) (xy 69.481707 -302.628296) (xy 69.489827 -302.683472)
			(xy 69.490336 -302.711358) (xy 69.92696 -302.711358) (xy 69.931031 -302.655736) (xy 69.943157 -302.601299)
			(xy 69.96308 -302.549208) (xy 69.990376 -302.500573) (xy 70.024462 -302.45643) (xy 70.064611 -302.417721)
			(xy 70.109969 -302.38527) (xy 70.159569 -302.359769) (xy 70.212353 -302.341762) (xy 70.267196 -302.331632)
			(xy 70.32293 -302.329595) (xy 70.378367 -302.335695) (xy 70.432324 -302.349801) (xy 70.483653 -302.371613)
			(xy 70.531259 -302.400667) (xy 70.574127 -302.436342) (xy 70.611344 -302.477879) (xy 70.642117 -302.524392)
			(xy 70.665789 -302.574889) (xy 70.681857 -302.628296) (xy 70.689977 -302.683472) (xy 70.690486 -302.711358)
			(xy 70.689977 -302.739244) (xy 70.681857 -302.79442) (xy 70.665789 -302.847827) (xy 70.642117 -302.898324)
			(xy 70.611344 -302.944837) (xy 70.574127 -302.986374) (xy 70.531259 -303.022049) (xy 70.483653 -303.051103)
			(xy 70.432324 -303.072915) (xy 70.378367 -303.087021) (xy 70.32293 -303.093121) (xy 70.267196 -303.091084)
			(xy 70.212353 -303.080954) (xy 70.159569 -303.062947) (xy 70.109969 -303.037446) (xy 70.064611 -303.004995)
			(xy 70.024462 -302.966286) (xy 69.990376 -302.922143) (xy 69.96308 -302.873508) (xy 69.943157 -302.821417)
			(xy 69.931031 -302.76698) (xy 69.92696 -302.711358) (xy 69.490336 -302.711358) (xy 69.489827 -302.739244)
			(xy 69.481707 -302.79442) (xy 69.465639 -302.847827) (xy 69.441967 -302.898324) (xy 69.411194 -302.944837)
			(xy 69.373977 -302.986374) (xy 69.331109 -303.022049) (xy 69.283503 -303.051103) (xy 69.232174 -303.072915)
			(xy 69.178217 -303.087021) (xy 69.12278 -303.093121) (xy 69.067046 -303.091084) (xy 69.012203 -303.080954)
			(xy 68.959419 -303.062947) (xy 68.909819 -303.037446) (xy 68.864461 -303.004995) (xy 68.824312 -302.966286)
			(xy 68.790226 -302.922143) (xy 68.76293 -302.873508) (xy 68.743007 -302.821417) (xy 68.730881 -302.76698)
			(xy 68.72681 -302.711358) (xy 68.248784 -302.711358) (xy 68.248275 -302.739244) (xy 68.240155 -302.79442)
			(xy 68.224087 -302.847827) (xy 68.200415 -302.898324) (xy 68.169642 -302.944837) (xy 68.132425 -302.986374)
			(xy 68.089557 -303.022049) (xy 68.041951 -303.051103) (xy 67.990622 -303.072915) (xy 67.936665 -303.087021)
			(xy 67.881228 -303.093121) (xy 67.825494 -303.091084) (xy 67.770651 -303.080954) (xy 67.717867 -303.062947)
			(xy 67.668267 -303.037446) (xy 67.622909 -303.004995) (xy 67.58276 -302.966286) (xy 67.548674 -302.922143)
			(xy 67.521378 -302.873508) (xy 67.501455 -302.821417) (xy 67.489329 -302.76698) (xy 67.485258 -302.711358)
			(xy 67.071494 -302.711358) (xy 67.070985 -302.739244) (xy 67.062865 -302.79442) (xy 67.046797 -302.847827)
			(xy 67.023125 -302.898324) (xy 66.992352 -302.944837) (xy 66.955135 -302.986374) (xy 66.912267 -303.022049)
			(xy 66.864661 -303.051103) (xy 66.813332 -303.072915) (xy 66.759375 -303.087021) (xy 66.703938 -303.093121)
			(xy 66.648204 -303.091084) (xy 66.593361 -303.080954) (xy 66.540577 -303.062947) (xy 66.490977 -303.037446)
			(xy 66.445619 -303.004995) (xy 66.40547 -302.966286) (xy 66.371384 -302.922143) (xy 66.344088 -302.873508)
			(xy 66.324165 -302.821417) (xy 66.312039 -302.76698) (xy 66.307968 -302.711358) (xy 45.79522 -302.711358)
			(xy 45.794778 -302.711523) (xy 45.741535 -302.723103) (xy 45.687185 -302.726988) (xy 45.632836 -302.723099)
			(xy 45.579594 -302.711514) (xy 45.528542 -302.692471) (xy 45.480721 -302.666355) (xy 45.458634 -302.650398)
			(xy 45.439622 -302.636802) (xy 45.397739 -302.61607) (xy 45.352771 -302.603344) (xy 45.306234 -302.599054)
			(xy 45.259697 -302.603344) (xy 45.214729 -302.61607) (xy 45.172846 -302.636802) (xy 45.153834 -302.650398)
			(xy 45.131754 -302.666374) (xy 45.083926 -302.692502) (xy 45.032866 -302.711556) (xy 44.979614 -302.723149)
			(xy 44.925253 -302.727045) (xy 44.870892 -302.723164) (xy 44.817637 -302.711586) (xy 44.766571 -302.692546)
			(xy 44.718735 -302.666432) (xy 44.675103 -302.633776) (xy 44.636563 -302.595242) (xy 44.6039 -302.551615)
			(xy 44.577779 -302.503783) (xy 44.558731 -302.45272) (xy 44.547144 -302.399467) (xy 44.543255 -302.345106)
			(xy 44.165238 -302.345106) (xy 44.161349 -302.399467) (xy 44.149763 -302.45272) (xy 44.130715 -302.503782)
			(xy 44.104593 -302.551614) (xy 44.071929 -302.59524) (xy 44.033389 -302.633774) (xy 43.989756 -302.66643)
			(xy 43.94192 -302.692543) (xy 43.890854 -302.711582) (xy 43.837599 -302.723159) (xy 43.783238 -302.727038)
			(xy 43.728878 -302.723141) (xy 43.675626 -302.711547) (xy 43.624566 -302.692491) (xy 43.576739 -302.666362)
			(xy 43.55465 -302.650398) (xy 43.535638 -302.636802) (xy 43.493755 -302.61607) (xy 43.448787 -302.603344)
			(xy 43.40225 -302.599054) (xy 43.355713 -302.603344) (xy 43.310745 -302.61607) (xy 43.268862 -302.636802)
			(xy 43.24985 -302.650398) (xy 43.22777 -302.666376) (xy 43.17994 -302.692506) (xy 43.128879 -302.711562)
			(xy 43.075625 -302.723157) (xy 43.021262 -302.727054) (xy 42.966899 -302.723175) (xy 42.913641 -302.711597)
			(xy 42.862573 -302.692558) (xy 42.814735 -302.666443) (xy 42.771101 -302.633786) (xy 42.732559 -302.595251)
			(xy 42.699894 -302.551623) (xy 42.673771 -302.503789) (xy 42.654722 -302.452725) (xy 42.643135 -302.399469)
			(xy 42.639246 -302.345106) (xy 41.924104 -302.345106) (xy 41.920215 -302.399459) (xy 41.908631 -302.452705)
			(xy 41.889587 -302.50376) (xy 41.86347 -302.551585) (xy 41.830813 -302.595206) (xy 41.79228 -302.633736)
			(xy 41.748655 -302.666389) (xy 41.700828 -302.692501) (xy 41.649771 -302.711541) (xy 41.596523 -302.72312)
			(xy 41.542171 -302.727004) (xy 41.487818 -302.723112) (xy 41.434573 -302.711524) (xy 41.383519 -302.692477)
			(xy 41.335695 -302.666357) (xy 41.313608 -302.650398) (xy 41.294596 -302.636802) (xy 41.252713 -302.61607)
			(xy 41.207745 -302.603344) (xy 41.161208 -302.599054) (xy 41.114671 -302.603344) (xy 41.069703 -302.61607)
			(xy 41.02782 -302.636802) (xy 41.008808 -302.650398) (xy 40.986729 -302.666372) (xy 40.938902 -302.692495)
			(xy 40.887845 -302.711546) (xy 40.834595 -302.723136) (xy 40.780239 -302.727029) (xy 40.725881 -302.723147)
			(xy 40.672629 -302.711568) (xy 40.621568 -302.692527) (xy 40.573736 -302.666414) (xy 40.530107 -302.633758)
			(xy 40.491571 -302.595226) (xy 40.45891 -302.551602) (xy 40.432791 -302.503773) (xy 40.413745 -302.452713)
			(xy 40.402159 -302.399463) (xy 40.398271 -302.345106) (xy 40.037411 -302.345106) (xy 40.033522 -302.39946)
			(xy 40.021938 -302.452708) (xy 40.002892 -302.503765) (xy 39.976775 -302.551591) (xy 39.944116 -302.595213)
			(xy 39.905581 -302.633744) (xy 39.861955 -302.666398) (xy 39.814126 -302.69251) (xy 39.763067 -302.71155)
			(xy 39.709818 -302.723128) (xy 39.655464 -302.727011) (xy 39.60111 -302.723118) (xy 39.547863 -302.711529)
			(xy 39.496808 -302.69248) (xy 39.448984 -302.666358) (xy 39.426896 -302.650398) (xy 39.407884 -302.636802)
			(xy 39.366001 -302.61607) (xy 39.321033 -302.603344) (xy 39.274496 -302.599054) (xy 39.227959 -302.603344)
			(xy 39.182991 -302.61607) (xy 39.141108 -302.636802) (xy 39.122096 -302.650398) (xy 39.100017 -302.666371)
			(xy 39.052191 -302.692492) (xy 39.001135 -302.711541) (xy 38.947887 -302.72313) (xy 38.893532 -302.727022)
			(xy 38.839176 -302.723139) (xy 38.785926 -302.711559) (xy 38.734866 -302.692519) (xy 38.687036 -302.666405)
			(xy 38.643409 -302.633751) (xy 38.604874 -302.595219) (xy 38.572215 -302.551596) (xy 38.546097 -302.503768)
			(xy 38.527051 -302.45271) (xy 38.515466 -302.399461) (xy 38.511578 -302.345106) (xy 36.357258 -302.345106)
			(xy 36.361593 -302.352108) (xy 36.400327 -302.429897) (xy 36.431719 -302.510929) (xy 36.4555 -302.594511)
			(xy 36.471468 -302.679931) (xy 36.479486 -302.76646) (xy 36.479988 -302.80991) (xy 36.479486 -302.85336)
			(xy 36.471468 -302.939889) (xy 36.4555 -303.025309) (xy 36.431719 -303.108891) (xy 36.400327 -303.189923)
			(xy 36.361593 -303.267712) (xy 36.315846 -303.341596) (xy 36.263477 -303.410943) (xy 36.204933 -303.475163)
			(xy 36.145058 -303.529746) (xy 95.24187 -303.529746) (xy 95.245941 -303.474124) (xy 95.258067 -303.419687)
			(xy 95.27799 -303.367596) (xy 95.305286 -303.318961) (xy 95.339372 -303.274818) (xy 95.379521 -303.236109)
			(xy 95.424879 -303.203658) (xy 95.474479 -303.178157) (xy 95.527263 -303.16015) (xy 95.582106 -303.15002)
			(xy 95.63784 -303.147983) (xy 95.693277 -303.154083) (xy 95.747234 -303.168189) (xy 95.798563 -303.190001)
			(xy 95.846169 -303.219055) (xy 95.889037 -303.25473) (xy 95.926254 -303.296267) (xy 95.957027 -303.34278)
			(xy 95.980699 -303.393277) (xy 95.996767 -303.446684) (xy 96.004887 -303.50186) (xy 96.005396 -303.529746)
			(xy 96.004887 -303.557632) (xy 95.996767 -303.612808) (xy 95.980699 -303.666215) (xy 95.957027 -303.716712)
			(xy 95.926254 -303.763225) (xy 95.889037 -303.804762) (xy 95.846169 -303.840437) (xy 95.798563 -303.869491)
			(xy 95.747234 -303.891303) (xy 95.693277 -303.905409) (xy 95.63784 -303.911509) (xy 95.582106 -303.909472)
			(xy 95.527263 -303.899342) (xy 95.474479 -303.881335) (xy 95.424879 -303.855834) (xy 95.379521 -303.823383)
			(xy 95.339372 -303.784674) (xy 95.305286 -303.740531) (xy 95.27799 -303.691896) (xy 95.258067 -303.639805)
			(xy 95.245941 -303.585368) (xy 95.24187 -303.529746) (xy 36.145058 -303.529746) (xy 36.140713 -303.533707)
			(xy 36.071366 -303.586076) (xy 35.997482 -303.631823) (xy 35.919693 -303.670557) (xy 35.838661 -303.701949)
			(xy 35.755079 -303.72573) (xy 35.669659 -303.741698) (xy 35.58313 -303.749716) (xy 35.49623 -303.749716)
			(xy 35.409701 -303.741698) (xy 35.324281 -303.72573) (xy 35.240699 -303.701949) (xy 35.159667 -303.670557)
			(xy 35.081878 -303.631823) (xy 35.007994 -303.586076) (xy 34.938647 -303.533707) (xy 34.874427 -303.475163)
			(xy 34.815883 -303.410943) (xy 34.763514 -303.341596) (xy 34.717767 -303.267712) (xy 34.679033 -303.189923)
			(xy 34.647641 -303.108891) (xy 34.62386 -303.025309) (xy 34.607892 -302.939889) (xy 34.599874 -302.85336)
			(xy 31.399486 -302.85336) (xy 31.391468 -302.939889) (xy 31.3755 -303.025309) (xy 31.351719 -303.108891)
			(xy 31.320327 -303.189923) (xy 31.281593 -303.267712) (xy 31.235846 -303.341596) (xy 31.183477 -303.410943)
			(xy 31.124933 -303.475163) (xy 31.060713 -303.533707) (xy 30.991366 -303.586076) (xy 30.917482 -303.631823)
			(xy 30.839693 -303.670557) (xy 30.758661 -303.701949) (xy 30.675079 -303.72573) (xy 30.589659 -303.741698)
			(xy 30.50313 -303.749716) (xy 30.41623 -303.749716) (xy 30.329701 -303.741698) (xy 30.244281 -303.72573)
			(xy 30.160699 -303.701949) (xy 30.079667 -303.670557) (xy 30.001878 -303.631823) (xy 29.927994 -303.586076)
			(xy 29.858647 -303.533707) (xy 29.794427 -303.475163) (xy 29.735883 -303.410943) (xy 29.683514 -303.341596)
			(xy 29.637767 -303.267712) (xy 29.599033 -303.189923) (xy 29.567641 -303.108891) (xy 29.54386 -303.025309)
			(xy 29.527892 -302.939889) (xy 29.519874 -302.85336) (xy 28.912312 -302.85336) (xy 28.912312 -304.356323)
			(xy 38.468176 -304.356323) (xy 38.47206 -304.301969) (xy 38.48364 -304.24872) (xy 38.502681 -304.197662)
			(xy 38.528794 -304.149833) (xy 38.561448 -304.106208) (xy 38.599978 -304.067674) (xy 38.6436 -304.035015)
			(xy 38.691426 -304.008897) (xy 38.742483 -303.989851) (xy 38.79573 -303.978266) (xy 38.850084 -303.974376)
			(xy 38.904438 -303.978261) (xy 38.957686 -303.989842) (xy 39.008744 -304.008883) (xy 39.056572 -304.034997)
			(xy 39.078662 -304.050954) (xy 39.097674 -304.06455) (xy 39.139557 -304.085282) (xy 39.184525 -304.098008)
			(xy 39.231062 -304.102298) (xy 39.277599 -304.098008) (xy 39.322567 -304.085282) (xy 39.36445 -304.06455)
			(xy 39.383462 -304.050954) (xy 39.405587 -304.035042) (xy 39.453413 -304.00892) (xy 39.504469 -303.989871)
			(xy 39.557718 -303.978283) (xy 39.612073 -303.974391) (xy 39.666429 -303.978275) (xy 39.719679 -303.989856)
			(xy 39.770739 -304.008898) (xy 39.818568 -304.035013) (xy 39.862194 -304.06767) (xy 39.900728 -304.106203)
			(xy 39.933385 -304.149828) (xy 39.9595 -304.197658) (xy 39.978543 -304.248717) (xy 39.990124 -304.301967)
			(xy 39.994009 -304.356323) (xy 40.354869 -304.356323) (xy 40.358753 -304.301967) (xy 40.370334 -304.248717)
			(xy 40.389375 -304.197657) (xy 40.415489 -304.149827) (xy 40.448145 -304.106201) (xy 40.486676 -304.067666)
			(xy 40.5303 -304.035007) (xy 40.578128 -304.008888) (xy 40.629186 -303.989843) (xy 40.682435 -303.978258)
			(xy 40.73679 -303.974369) (xy 40.791146 -303.978255) (xy 40.844396 -303.989838) (xy 40.895455 -304.008881)
			(xy 40.943284 -304.034996) (xy 40.965374 -304.050954) (xy 40.984386 -304.06455) (xy 41.026269 -304.085282)
			(xy 41.071237 -304.098008) (xy 41.117774 -304.102298) (xy 41.164311 -304.098008) (xy 41.209279 -304.085282)
			(xy 41.251162 -304.06455) (xy 41.270174 -304.050954) (xy 41.292298 -304.035043) (xy 41.340123 -304.008923)
			(xy 41.391179 -303.989876) (xy 41.444426 -303.978289) (xy 41.49878 -303.974398) (xy 41.553134 -303.978283)
			(xy 41.606382 -303.989865) (xy 41.65744 -304.008907) (xy 41.705268 -304.035021) (xy 41.748892 -304.067678)
			(xy 41.787424 -304.10621) (xy 41.82008 -304.149834) (xy 41.846195 -304.197662) (xy 41.865236 -304.24872)
			(xy 41.876817 -304.301968) (xy 41.880702 -304.356323) (xy 42.595843 -304.356323) (xy 42.599728 -304.301961)
			(xy 42.611311 -304.248706) (xy 42.630355 -304.197641) (xy 42.656473 -304.149807) (xy 42.689133 -304.106176)
			(xy 42.72767 -304.067638) (xy 42.771299 -304.034977) (xy 42.819133 -304.008858) (xy 42.870198 -303.989813)
			(xy 42.923453 -303.97823) (xy 42.977814 -303.974343) (xy 43.032176 -303.978234) (xy 43.08543 -303.989821)
			(xy 43.136493 -304.00887) (xy 43.184325 -304.034993) (xy 43.206416 -304.050954) (xy 43.225428 -304.06455)
			(xy 43.267311 -304.085282) (xy 43.312279 -304.098008) (xy 43.358816 -304.102298) (xy 43.405353 -304.098008)
			(xy 43.450321 -304.085282) (xy 43.492204 -304.06455) (xy 43.511216 -304.050954) (xy 43.533339 -304.035047)
			(xy 43.581162 -304.008933) (xy 43.632213 -303.989892) (xy 43.685455 -303.97831) (xy 43.739804 -303.974423)
			(xy 43.794152 -303.978311) (xy 43.847394 -303.989894) (xy 43.898445 -304.008937) (xy 43.946267 -304.035051)
			(xy 43.989885 -304.067705) (xy 44.028412 -304.106235) (xy 44.061064 -304.149855) (xy 44.087174 -304.197679)
			(xy 44.106213 -304.248732) (xy 44.117793 -304.301974) (xy 44.121677 -304.356323) (xy 44.499853 -304.356323)
			(xy 44.503738 -304.301963) (xy 44.51532 -304.24871) (xy 44.534363 -304.197647) (xy 44.560479 -304.149815)
			(xy 44.593137 -304.106186) (xy 44.631672 -304.067649) (xy 44.6753 -304.034988) (xy 44.723131 -304.00887)
			(xy 44.774193 -303.989825) (xy 44.827446 -303.97824) (xy 44.881805 -303.974353) (xy 44.936164 -303.978242)
			(xy 44.989417 -303.989828) (xy 45.040478 -304.008874) (xy 45.088309 -304.034994) (xy 45.1104 -304.050954)
			(xy 45.129412 -304.06455) (xy 45.171295 -304.085282) (xy 45.216263 -304.098008) (xy 45.2628 -304.102298)
			(xy 45.309337 -304.098008) (xy 45.354305 -304.085282) (xy 45.396188 -304.06455) (xy 45.4152 -304.050954)
			(xy 45.437324 -304.035045) (xy 45.485147 -304.00893) (xy 45.5362 -303.989886) (xy 45.589444 -303.978302)
			(xy 45.643795 -303.974414) (xy 45.698145 -303.978301) (xy 45.75139 -303.989883) (xy 45.802443 -304.008925)
			(xy 45.850267 -304.03504) (xy 45.893888 -304.067695) (xy 45.932417 -304.106225) (xy 45.96507 -304.149847)
			(xy 45.991182 -304.197673) (xy 46.010222 -304.248727) (xy 46.021802 -304.301972) (xy 46.025686 -304.356323)
			(xy 46.021795 -304.410673) (xy 46.010209 -304.463917) (xy 45.991163 -304.514969) (xy 45.965045 -304.562791)
			(xy 45.932387 -304.606409) (xy 45.893853 -304.644935) (xy 45.850229 -304.677585) (xy 45.802402 -304.703694)
			(xy 45.751346 -304.72273) (xy 45.698624 -304.734192) (xy 57.58881 -304.734192) (xy 57.592699 -304.679842)
			(xy 57.604283 -304.626599) (xy 57.623326 -304.575546) (xy 57.649441 -304.527724) (xy 57.682096 -304.484105)
			(xy 57.720627 -304.445577) (xy 57.764249 -304.412925) (xy 57.812074 -304.386813) (xy 57.863128 -304.367774)
			(xy 57.916372 -304.356194) (xy 57.970722 -304.35231) (xy 58.025071 -304.356201) (xy 58.078314 -304.367786)
			(xy 58.129366 -304.386831) (xy 58.177187 -304.412948) (xy 58.199274 -304.428906) (xy 58.218286 -304.442502)
			(xy 58.260169 -304.463234) (xy 58.305137 -304.47596) (xy 58.351674 -304.48025) (xy 58.398211 -304.47596)
			(xy 58.443179 -304.463234) (xy 58.485062 -304.442502) (xy 58.504074 -304.428906) (xy 58.52615 -304.412925)
			(xy 58.573978 -304.386798) (xy 58.625037 -304.367745) (xy 58.678289 -304.356152) (xy 58.732649 -304.352257)
			(xy 58.787009 -304.356138) (xy 58.840264 -304.367716) (xy 58.891329 -304.386756) (xy 58.939164 -304.41287)
			(xy 58.982796 -304.445526) (xy 59.021335 -304.484059) (xy 59.053998 -304.527686) (xy 59.08012 -304.575517)
			(xy 59.099167 -304.626579) (xy 59.110754 -304.679832) (xy 59.114643 -304.734192) (xy 59.475503 -304.734192)
			(xy 59.479392 -304.67984) (xy 59.490976 -304.626596) (xy 59.51002 -304.575542) (xy 59.536136 -304.527718)
			(xy 59.568793 -304.484097) (xy 59.607325 -304.445569) (xy 59.650949 -304.412916) (xy 59.698775 -304.386805)
			(xy 59.749831 -304.367766) (xy 59.803077 -304.356186) (xy 59.857428 -304.352303) (xy 59.91178 -304.356195)
			(xy 59.965024 -304.367782) (xy 60.016077 -304.386828) (xy 60.063899 -304.412947) (xy 60.085986 -304.428906)
			(xy 60.104998 -304.442502) (xy 60.146881 -304.463234) (xy 60.191849 -304.47596) (xy 60.238386 -304.48025)
			(xy 60.284923 -304.47596) (xy 60.329891 -304.463234) (xy 60.371774 -304.442502) (xy 60.390786 -304.428906)
			(xy 60.412861 -304.412926) (xy 60.460689 -304.386801) (xy 60.511747 -304.367749) (xy 60.564998 -304.356158)
			(xy 60.619356 -304.352264) (xy 60.673714 -304.356146) (xy 60.726968 -304.367724) (xy 60.778031 -304.386764)
			(xy 60.825864 -304.412878) (xy 60.869494 -304.445534) (xy 60.908032 -304.484066) (xy 60.940693 -304.527692)
			(xy 60.966814 -304.575521) (xy 60.985861 -304.626582) (xy 60.997447 -304.679833) (xy 61.001336 -304.734192)
			(xy 61.716478 -304.734192) (xy 61.720367 -304.679835) (xy 61.731953 -304.626584) (xy 61.751 -304.575525)
			(xy 61.77712 -304.527697) (xy 61.809781 -304.484073) (xy 61.848319 -304.445541) (xy 61.891948 -304.412887)
			(xy 61.939781 -304.386775) (xy 61.990843 -304.367736) (xy 62.044095 -304.356158) (xy 62.098452 -304.352278)
			(xy 62.152809 -304.356173) (xy 62.206058 -304.367765) (xy 62.257115 -304.386818) (xy 62.30494 -304.412944)
			(xy 62.327028 -304.428906) (xy 62.34604 -304.442502) (xy 62.387923 -304.463234) (xy 62.432891 -304.47596)
			(xy 62.479428 -304.48025) (xy 62.525965 -304.47596) (xy 62.570933 -304.463234) (xy 62.612816 -304.442502)
			(xy 62.631828 -304.428906) (xy 62.653902 -304.41293) (xy 62.701727 -304.386811) (xy 62.752781 -304.367766)
			(xy 62.806027 -304.356179) (xy 62.860379 -304.352289) (xy 62.914732 -304.356174) (xy 62.967979 -304.367754)
			(xy 63.019036 -304.386794) (xy 63.066863 -304.412907) (xy 63.110487 -304.445561) (xy 63.14902 -304.484091)
			(xy 63.181677 -304.527713) (xy 63.207794 -304.575538) (xy 63.226838 -304.626593) (xy 63.238422 -304.679839)
			(xy 63.242311 -304.734192) (xy 63.620487 -304.734192) (xy 63.624376 -304.679837) (xy 63.635962 -304.626589)
			(xy 63.655008 -304.575532) (xy 63.681126 -304.527705) (xy 63.713786 -304.484082) (xy 63.752321 -304.445552)
			(xy 63.795948 -304.412898) (xy 63.843779 -304.386786) (xy 63.894838 -304.367747) (xy 63.948088 -304.356169)
			(xy 64.002443 -304.352287) (xy 64.056798 -304.356181) (xy 64.110045 -304.367772) (xy 64.1611 -304.386822)
			(xy 64.208925 -304.412945) (xy 64.231012 -304.428906) (xy 64.250024 -304.442502) (xy 64.291907 -304.463234)
			(xy 64.336875 -304.47596) (xy 64.383412 -304.48025) (xy 64.429949 -304.47596) (xy 64.474917 -304.463234)
			(xy 64.5168 -304.442502) (xy 64.535812 -304.428906) (xy 64.557887 -304.412928) (xy 64.605712 -304.386808)
			(xy 64.656768 -304.367759) (xy 64.710016 -304.356171) (xy 64.76437 -304.352279) (xy 64.818726 -304.356163)
			(xy 64.871975 -304.367743) (xy 64.923034 -304.386783) (xy 64.970863 -304.412896) (xy 65.01449 -304.445551)
			(xy 65.053024 -304.484082) (xy 65.085683 -304.527705) (xy 65.111801 -304.575532) (xy 65.130847 -304.626589)
			(xy 65.142432 -304.679837) (xy 65.146321 -304.734192) (xy 65.142434 -304.788547) (xy 65.141766 -304.791618)
			(xy 94.531178 -304.791618) (xy 94.535249 -304.735996) (xy 94.547375 -304.681559) (xy 94.567298 -304.629468)
			(xy 94.594594 -304.580833) (xy 94.62868 -304.53669) (xy 94.668829 -304.497981) (xy 94.714187 -304.46553)
			(xy 94.763787 -304.440029) (xy 94.816571 -304.422022) (xy 94.871414 -304.411892) (xy 94.927148 -304.409855)
			(xy 94.982585 -304.415955) (xy 95.036542 -304.430061) (xy 95.087871 -304.451873) (xy 95.135477 -304.480927)
			(xy 95.178345 -304.516602) (xy 95.215562 -304.558139) (xy 95.246335 -304.604652) (xy 95.270007 -304.655149)
			(xy 95.286075 -304.708556) (xy 95.294195 -304.763732) (xy 95.294704 -304.791618) (xy 95.294195 -304.819504)
			(xy 95.286075 -304.87468) (xy 95.270007 -304.928087) (xy 95.246335 -304.978584) (xy 95.215562 -305.025097)
			(xy 95.178345 -305.066634) (xy 95.135477 -305.102309) (xy 95.087871 -305.131363) (xy 95.036542 -305.153175)
			(xy 94.982585 -305.167281) (xy 94.927148 -305.173381) (xy 94.871414 -305.171344) (xy 94.816571 -305.161214)
			(xy 94.763787 -305.143207) (xy 94.714187 -305.117706) (xy 94.668829 -305.085255) (xy 94.62868 -305.046546)
			(xy 94.594594 -305.002403) (xy 94.567298 -304.953768) (xy 94.547375 -304.901677) (xy 94.535249 -304.84724)
			(xy 94.531178 -304.791618) (xy 65.141766 -304.791618) (xy 65.130851 -304.841795) (xy 65.111808 -304.892853)
			(xy 65.085692 -304.940681) (xy 65.053035 -304.984306) (xy 65.014502 -305.022838) (xy 64.970878 -305.055495)
			(xy 64.923049 -305.08161) (xy 64.871991 -305.100653) (xy 64.818742 -305.112235) (xy 64.764387 -305.116121)
			(xy 64.710032 -305.112231) (xy 64.656785 -305.100645) (xy 64.605728 -305.081599) (xy 64.557901 -305.055481)
			(xy 64.535812 -305.039522) (xy 64.5168 -305.025926) (xy 64.474917 -305.005194) (xy 64.429949 -304.992468)
			(xy 64.383412 -304.988178) (xy 64.336875 -304.992468) (xy 64.291907 -305.005194) (xy 64.250024 -305.025926)
			(xy 64.231012 -305.039522) (xy 64.20891 -305.055464) (xy 64.161085 -305.081585) (xy 64.110029 -305.100633)
			(xy 64.056781 -305.112221) (xy 64.002426 -305.116113) (xy 63.948071 -305.112229) (xy 63.894822 -305.100648)
			(xy 63.843763 -305.081607) (xy 63.795934 -305.055493) (xy 63.752309 -305.022837) (xy 63.713775 -304.984305)
			(xy 63.681117 -304.940681) (xy 63.655001 -304.892853) (xy 63.635957 -304.841795) (xy 63.624374 -304.788547)
			(xy 63.620487 -304.734192) (xy 63.242311 -304.734192) (xy 63.238425 -304.788544) (xy 63.226843 -304.841791)
			(xy 63.207801 -304.892847) (xy 63.181686 -304.940673) (xy 63.149031 -304.984296) (xy 63.1105 -305.022828)
			(xy 63.066877 -305.055484) (xy 63.019051 -305.081599) (xy 62.967995 -305.100641) (xy 62.914749 -305.112224)
			(xy 62.860396 -305.116111) (xy 62.806044 -305.112223) (xy 62.752798 -305.100639) (xy 62.701742 -305.081596)
			(xy 62.653917 -305.05548) (xy 62.631828 -305.039522) (xy 62.612816 -305.025926) (xy 62.570933 -305.005194)
			(xy 62.525965 -304.992468) (xy 62.479428 -304.988178) (xy 62.432891 -304.992468) (xy 62.387923 -305.005194)
			(xy 62.34604 -305.025926) (xy 62.327028 -305.039522) (xy 62.304926 -305.055465) (xy 62.257099 -305.081589)
			(xy 62.206042 -305.100639) (xy 62.152792 -305.112229) (xy 62.098436 -305.116122) (xy 62.044078 -305.112239)
			(xy 61.990827 -305.100659) (xy 61.939765 -305.081618) (xy 61.891934 -305.055504) (xy 61.848306 -305.022848)
			(xy 61.80977 -304.984315) (xy 61.777111 -304.940689) (xy 61.750993 -304.892859) (xy 61.731948 -304.841799)
			(xy 61.720365 -304.788549) (xy 61.716478 -304.734192) (xy 61.001336 -304.734192) (xy 60.997449 -304.78855)
			(xy 60.985866 -304.841802) (xy 60.966821 -304.892863) (xy 60.940703 -304.940694) (xy 60.908043 -304.984321)
			(xy 60.869506 -305.022855) (xy 60.825878 -305.055513) (xy 60.778046 -305.081629) (xy 60.726984 -305.100671)
			(xy 60.673731 -305.112252) (xy 60.619372 -305.116136) (xy 60.565014 -305.112244) (xy 60.511763 -305.100655)
			(xy 60.460704 -305.081606) (xy 60.412876 -305.055483) (xy 60.390786 -305.039522) (xy 60.371774 -305.025926)
			(xy 60.329891 -305.005194) (xy 60.284923 -304.992468) (xy 60.238386 -304.988178) (xy 60.191849 -304.992468)
			(xy 60.146881 -305.005194) (xy 60.104998 -305.025926) (xy 60.085986 -305.039522) (xy 60.063885 -305.055462)
			(xy 60.016061 -305.081579) (xy 59.965008 -305.100623) (xy 59.911763 -305.112208) (xy 59.857412 -305.116097)
			(xy 59.80306 -305.112211) (xy 59.749815 -305.10063) (xy 59.69876 -305.081588) (xy 59.650935 -305.055475)
			(xy 59.607313 -305.02282) (xy 59.568782 -304.98429) (xy 59.536127 -304.940668) (xy 59.510013 -304.892843)
			(xy 59.490971 -304.841788) (xy 59.479389 -304.788543) (xy 59.475503 -304.734192) (xy 59.114643 -304.734192)
			(xy 59.110756 -304.788552) (xy 59.099172 -304.841805) (xy 59.080126 -304.892868) (xy 59.054007 -304.9407)
			(xy 59.021346 -304.984328) (xy 58.982808 -305.022863) (xy 58.939178 -305.055521) (xy 58.891344 -305.081637)
			(xy 58.84028 -305.100679) (xy 58.787026 -305.11226) (xy 58.732666 -305.116143) (xy 58.678306 -305.11225)
			(xy 58.625054 -305.10066) (xy 58.573993 -305.081609) (xy 58.526164 -305.055484) (xy 58.504074 -305.039522)
			(xy 58.485062 -305.025926) (xy 58.443179 -305.005194) (xy 58.398211 -304.992468) (xy 58.351674 -304.988178)
			(xy 58.305137 -304.992468) (xy 58.260169 -305.005194) (xy 58.218286 -305.025926) (xy 58.199274 -305.039522)
			(xy 58.177173 -305.055461) (xy 58.12935 -305.081576) (xy 58.078298 -305.100618) (xy 58.025055 -305.112202)
			(xy 57.970705 -305.11609) (xy 57.916355 -305.112203) (xy 57.863112 -305.100621) (xy 57.812058 -305.08158)
			(xy 57.764235 -305.055466) (xy 57.720615 -305.022812) (xy 57.682085 -304.984283) (xy 57.649432 -304.940662)
			(xy 57.623319 -304.892838) (xy 57.604278 -304.841785) (xy 57.592696 -304.788541) (xy 57.58881 -304.734192)
			(xy 45.698624 -304.734192) (xy 45.6981 -304.734306) (xy 45.643749 -304.738186) (xy 45.589399 -304.734291)
			(xy 45.536157 -304.722701) (xy 45.485106 -304.703652) (xy 45.437285 -304.67753) (xy 45.4152 -304.66157)
			(xy 45.396188 -304.647974) (xy 45.354305 -304.627242) (xy 45.309337 -304.614516) (xy 45.2628 -304.610226)
			(xy 45.216263 -304.614516) (xy 45.171295 -304.627242) (xy 45.129412 -304.647974) (xy 45.1104 -304.66157)
			(xy 45.088347 -304.677581) (xy 45.04052 -304.703707) (xy 44.989461 -304.72276) (xy 44.93621 -304.734352)
			(xy 44.881851 -304.738247) (xy 44.827491 -304.734366) (xy 44.774237 -304.722788) (xy 44.723173 -304.703749)
			(xy 44.675338 -304.677636) (xy 44.631707 -304.644981) (xy 44.593167 -304.606449) (xy 44.560504 -304.562824)
			(xy 44.534381 -304.514994) (xy 44.515332 -304.463934) (xy 44.503744 -304.410682) (xy 44.499853 -304.356323)
			(xy 44.121677 -304.356323) (xy 44.117786 -304.410671) (xy 44.1062 -304.463912) (xy 44.087155 -304.514963)
			(xy 44.061039 -304.562783) (xy 44.028382 -304.6064) (xy 43.989851 -304.644925) (xy 43.946229 -304.677574)
			(xy 43.898404 -304.703682) (xy 43.84735 -304.722719) (xy 43.794107 -304.734295) (xy 43.739758 -304.738177)
			(xy 43.68541 -304.734283) (xy 43.63217 -304.722695) (xy 43.58112 -304.703648) (xy 43.533301 -304.677529)
			(xy 43.511216 -304.66157) (xy 43.492204 -304.647974) (xy 43.450321 -304.627242) (xy 43.405353 -304.614516)
			(xy 43.358816 -304.610226) (xy 43.312279 -304.614516) (xy 43.267311 -304.627242) (xy 43.225428 -304.647974)
			(xy 43.206416 -304.66157) (xy 43.184363 -304.677583) (xy 43.136534 -304.703711) (xy 43.085474 -304.722766)
			(xy 43.032221 -304.73436) (xy 42.97786 -304.738257) (xy 42.923498 -304.734377) (xy 42.870241 -304.7228)
			(xy 42.819175 -304.703761) (xy 42.771338 -304.677647) (xy 42.727704 -304.644992) (xy 42.689163 -304.606458)
			(xy 42.656497 -304.562832) (xy 42.630374 -304.515) (xy 42.611324 -304.463938) (xy 42.599735 -304.410684)
			(xy 42.595843 -304.356323) (xy 41.880702 -304.356323) (xy 41.876811 -304.410677) (xy 41.865223 -304.463923)
			(xy 41.846176 -304.514979) (xy 41.820055 -304.562804) (xy 41.787394 -304.606424) (xy 41.748858 -304.644952)
			(xy 41.70523 -304.677603) (xy 41.657399 -304.703712) (xy 41.606339 -304.722748) (xy 41.553089 -304.734323)
			(xy 41.498734 -304.738202) (xy 41.444381 -304.734305) (xy 41.391135 -304.722711) (xy 41.340082 -304.703658)
			(xy 41.29226 -304.677532) (xy 41.270174 -304.66157) (xy 41.251162 -304.647974) (xy 41.209279 -304.627242)
			(xy 41.164311 -304.614516) (xy 41.117774 -304.610226) (xy 41.071237 -304.614516) (xy 41.026269 -304.627242)
			(xy 40.984386 -304.647974) (xy 40.965374 -304.66157) (xy 40.943322 -304.677579) (xy 40.895496 -304.703701)
			(xy 40.844439 -304.72275) (xy 40.791191 -304.734339) (xy 40.736836 -304.738231) (xy 40.68248 -304.734349)
			(xy 40.62923 -304.72277) (xy 40.578169 -304.70373) (xy 40.530339 -304.677618) (xy 40.486711 -304.644964)
			(xy 40.448174 -304.606434) (xy 40.415514 -304.562811) (xy 40.389394 -304.514984) (xy 40.370347 -304.463927)
			(xy 40.35876 -304.410678) (xy 40.354869 -304.356323) (xy 39.994009 -304.356323) (xy 39.990118 -304.410678)
			(xy 39.97853 -304.463927) (xy 39.959481 -304.514984) (xy 39.93336 -304.56281) (xy 39.900698 -304.606431)
			(xy 39.862159 -304.64496) (xy 39.81853 -304.677612) (xy 39.770697 -304.703721) (xy 39.719635 -304.722757)
			(xy 39.666384 -304.734331) (xy 39.612028 -304.738209) (xy 39.557673 -304.734311) (xy 39.504426 -304.722716)
			(xy 39.453371 -304.703661) (xy 39.405548 -304.677533) (xy 39.383462 -304.66157) (xy 39.36445 -304.647974)
			(xy 39.322567 -304.627242) (xy 39.277599 -304.614516) (xy 39.231062 -304.610226) (xy 39.184525 -304.614516)
			(xy 39.139557 -304.627242) (xy 39.097674 -304.647974) (xy 39.078662 -304.66157) (xy 39.05661 -304.677578)
			(xy 39.008785 -304.703698) (xy 38.95773 -304.722745) (xy 38.904483 -304.734332) (xy 38.850129 -304.738224)
			(xy 38.795775 -304.734341) (xy 38.742526 -304.722761) (xy 38.691468 -304.703722) (xy 38.643639 -304.67761)
			(xy 38.600013 -304.644956) (xy 38.561478 -304.606427) (xy 38.528819 -304.562805) (xy 38.5027 -304.514979)
			(xy 38.483653 -304.463923) (xy 38.472067 -304.410677) (xy 38.468176 -304.356323) (xy 28.912312 -304.356323)
			(xy 28.912312 -305.39336) (xy 29.519874 -305.39336) (xy 29.519874 -305.30646) (xy 29.527892 -305.219931)
			(xy 29.54386 -305.134511) (xy 29.567641 -305.050929) (xy 29.599033 -304.969897) (xy 29.637767 -304.892108)
			(xy 29.683514 -304.818224) (xy 29.735883 -304.748877) (xy 29.794427 -304.684657) (xy 29.858647 -304.626113)
			(xy 29.927994 -304.573744) (xy 30.001878 -304.527997) (xy 30.079667 -304.489263) (xy 30.160699 -304.457871)
			(xy 30.244281 -304.43409) (xy 30.329701 -304.418122) (xy 30.41623 -304.410104) (xy 30.50313 -304.410104)
			(xy 30.589659 -304.418122) (xy 30.675079 -304.43409) (xy 30.758661 -304.457871) (xy 30.839693 -304.489263)
			(xy 30.917482 -304.527997) (xy 30.991366 -304.573744) (xy 31.060713 -304.626113) (xy 31.124933 -304.684657)
			(xy 31.183477 -304.748877) (xy 31.235846 -304.818224) (xy 31.281593 -304.892108) (xy 31.320327 -304.969897)
			(xy 31.351719 -305.050929) (xy 31.3755 -305.134511) (xy 31.391468 -305.219931) (xy 31.399486 -305.30646)
			(xy 31.399988 -305.34991) (xy 31.399486 -305.39336) (xy 34.599874 -305.39336) (xy 34.599874 -305.30646)
			(xy 34.607892 -305.219931) (xy 34.62386 -305.134511) (xy 34.647641 -305.050929) (xy 34.679033 -304.969897)
			(xy 34.717767 -304.892108) (xy 34.763514 -304.818224) (xy 34.815883 -304.748877) (xy 34.874427 -304.684657)
			(xy 34.938647 -304.626113) (xy 35.007994 -304.573744) (xy 35.081878 -304.527997) (xy 35.159667 -304.489263)
			(xy 35.240699 -304.457871) (xy 35.324281 -304.43409) (xy 35.409701 -304.418122) (xy 35.49623 -304.410104)
			(xy 35.58313 -304.410104) (xy 35.669659 -304.418122) (xy 35.755079 -304.43409) (xy 35.838661 -304.457871)
			(xy 35.919693 -304.489263) (xy 35.997482 -304.527997) (xy 36.071366 -304.573744) (xy 36.140713 -304.626113)
			(xy 36.204933 -304.684657) (xy 36.263477 -304.748877) (xy 36.315846 -304.818224) (xy 36.361593 -304.892108)
			(xy 36.400327 -304.969897) (xy 36.431719 -305.050929) (xy 36.4555 -305.134511) (xy 36.471468 -305.219931)
			(xy 36.479486 -305.30646) (xy 36.479988 -305.34991) (xy 36.479486 -305.39336) (xy 36.471468 -305.479889)
			(xy 36.4555 -305.565309) (xy 36.431719 -305.648891) (xy 36.400327 -305.729923) (xy 36.361593 -305.807712)
			(xy 36.315846 -305.881596) (xy 36.263477 -305.950943) (xy 36.204933 -306.015163) (xy 36.140713 -306.073707)
			(xy 36.071366 -306.126076) (xy 35.997482 -306.171823) (xy 35.919693 -306.210557) (xy 35.838661 -306.241949)
			(xy 35.755079 -306.26573) (xy 35.669659 -306.281698) (xy 35.58313 -306.289716) (xy 35.49623 -306.289716)
			(xy 35.409701 -306.281698) (xy 35.324281 -306.26573) (xy 35.240699 -306.241949) (xy 35.159667 -306.210557)
			(xy 35.081878 -306.171823) (xy 35.007994 -306.126076) (xy 34.938647 -306.073707) (xy 34.874427 -306.015163)
			(xy 34.815883 -305.950943) (xy 34.763514 -305.881596) (xy 34.717767 -305.807712) (xy 34.679033 -305.729923)
			(xy 34.647641 -305.648891) (xy 34.62386 -305.565309) (xy 34.607892 -305.479889) (xy 34.599874 -305.39336)
			(xy 31.399486 -305.39336) (xy 31.391468 -305.479889) (xy 31.3755 -305.565309) (xy 31.351719 -305.648891)
			(xy 31.320327 -305.729923) (xy 31.281593 -305.807712) (xy 31.235846 -305.881596) (xy 31.183477 -305.950943)
			(xy 31.124933 -306.015163) (xy 31.060713 -306.073707) (xy 30.991366 -306.126076) (xy 30.917482 -306.171823)
			(xy 30.839693 -306.210557) (xy 30.758661 -306.241949) (xy 30.675079 -306.26573) (xy 30.589659 -306.281698)
			(xy 30.50313 -306.289716) (xy 30.41623 -306.289716) (xy 30.329701 -306.281698) (xy 30.244281 -306.26573)
			(xy 30.160699 -306.241949) (xy 30.079667 -306.210557) (xy 30.001878 -306.171823) (xy 29.927994 -306.126076)
			(xy 29.858647 -306.073707) (xy 29.794427 -306.015163) (xy 29.735883 -305.950943) (xy 29.683514 -305.881596)
			(xy 29.637767 -305.807712) (xy 29.599033 -305.729923) (xy 29.567641 -305.648891) (xy 29.54386 -305.565309)
			(xy 29.527892 -305.479889) (xy 29.519874 -305.39336) (xy 28.912312 -305.39336) (xy 28.912312 -306.423737)
			(xy 47.775358 -306.423737) (xy 47.775358 -306.342627) (xy 47.783308 -306.261908) (xy 47.799131 -306.182357)
			(xy 47.822676 -306.104741) (xy 47.853715 -306.029805) (xy 47.89195 -305.958273) (xy 47.937012 -305.890833)
			(xy 47.988467 -305.828134) (xy 48.04582 -305.770781) (xy 48.108519 -305.719326) (xy 48.175959 -305.674264)
			(xy 48.247491 -305.636029) (xy 48.322427 -305.60499) (xy 48.400043 -305.581445) (xy 48.479594 -305.565622)
			(xy 48.560313 -305.557672) (xy 48.641423 -305.557672) (xy 48.722142 -305.565622) (xy 48.801693 -305.581445)
			(xy 48.879309 -305.60499) (xy 48.954245 -305.636029) (xy 49.025777 -305.674264) (xy 49.093217 -305.719326)
			(xy 49.155916 -305.770781) (xy 49.213269 -305.828134) (xy 49.264724 -305.890833) (xy 49.309786 -305.958273)
			(xy 49.348021 -306.029805) (xy 49.37906 -306.104741) (xy 49.402605 -306.182357) (xy 49.418428 -306.261908)
			(xy 49.426378 -306.342627) (xy 49.426876 -306.383182) (xy 49.426378 -306.423737) (xy 51.275478 -306.423737)
			(xy 51.275478 -306.342627) (xy 51.283428 -306.261908) (xy 51.299251 -306.182357) (xy 51.322796 -306.104741)
			(xy 51.353835 -306.029805) (xy 51.39207 -305.958273) (xy 51.437132 -305.890833) (xy 51.488587 -305.828134)
			(xy 51.54594 -305.770781) (xy 51.608639 -305.719326) (xy 51.676079 -305.674264) (xy 51.747611 -305.636029)
			(xy 51.822547 -305.60499) (xy 51.900163 -305.581445) (xy 51.979714 -305.565622) (xy 52.060433 -305.557672)
			(xy 52.141543 -305.557672) (xy 52.222262 -305.565622) (xy 52.301813 -305.581445) (xy 52.379429 -305.60499)
			(xy 52.454365 -305.636029) (xy 52.525897 -305.674264) (xy 52.593337 -305.719326) (xy 52.656036 -305.770781)
			(xy 52.713389 -305.828134) (xy 52.764844 -305.890833) (xy 52.809906 -305.958273) (xy 52.83229 -306.00015)
			(xy 93.984824 -306.00015) (xy 93.988895 -305.944528) (xy 94.001021 -305.890091) (xy 94.020944 -305.838)
			(xy 94.04824 -305.789365) (xy 94.082326 -305.745222) (xy 94.122475 -305.706513) (xy 94.167833 -305.674062)
			(xy 94.217433 -305.648561) (xy 94.270217 -305.630554) (xy 94.32506 -305.620424) (xy 94.380794 -305.618387)
			(xy 94.436231 -305.624487) (xy 94.490188 -305.638593) (xy 94.541517 -305.660405) (xy 94.589123 -305.689459)
			(xy 94.631991 -305.725134) (xy 94.669208 -305.766671) (xy 94.699981 -305.813184) (xy 94.723653 -305.863681)
			(xy 94.739721 -305.917088) (xy 94.747841 -305.972264) (xy 94.74835 -306.00015) (xy 94.747841 -306.028036)
			(xy 94.739721 -306.083212) (xy 94.723653 -306.136619) (xy 94.699981 -306.187116) (xy 94.669208 -306.233629)
			(xy 94.631991 -306.275166) (xy 94.589123 -306.310841) (xy 94.541517 -306.339895) (xy 94.490188 -306.361707)
			(xy 94.436231 -306.375813) (xy 94.380794 -306.381913) (xy 94.32506 -306.379876) (xy 94.270217 -306.369746)
			(xy 94.217433 -306.351739) (xy 94.167833 -306.326238) (xy 94.122475 -306.293787) (xy 94.082326 -306.255078)
			(xy 94.04824 -306.210935) (xy 94.020944 -306.1623) (xy 94.001021 -306.110209) (xy 93.988895 -306.055772)
			(xy 93.984824 -306.00015) (xy 52.83229 -306.00015) (xy 52.848141 -306.029805) (xy 52.87918 -306.104741)
			(xy 52.902725 -306.182357) (xy 52.918548 -306.261908) (xy 52.926498 -306.342627) (xy 52.926996 -306.383182)
			(xy 52.926498 -306.423737) (xy 52.918548 -306.504456) (xy 52.902725 -306.584007) (xy 52.87918 -306.661623)
			(xy 52.848141 -306.736559) (xy 52.827367 -306.775425) (xy 57.588765 -306.775425) (xy 57.59265 -306.721069)
			(xy 57.60423 -306.667818) (xy 57.623271 -306.616758) (xy 57.649385 -306.568928) (xy 57.682041 -306.525301)
			(xy 57.720572 -306.486765) (xy 57.764196 -306.454105) (xy 57.812024 -306.427987) (xy 57.863083 -306.408941)
			(xy 57.916332 -306.397355) (xy 57.970688 -306.393465) (xy 58.025044 -306.397351) (xy 58.078294 -306.408934)
			(xy 58.129354 -306.427977) (xy 58.177183 -306.454092) (xy 58.199274 -306.47005) (xy 58.218286 -306.483646)
			(xy 58.260169 -306.504378) (xy 58.305137 -306.517104) (xy 58.351674 -306.521394) (xy 58.398211 -306.517104)
			(xy 58.443179 -306.504378) (xy 58.485062 -306.483646) (xy 58.504074 -306.47005) (xy 58.526202 -306.454144)
			(xy 58.574027 -306.428025) (xy 58.625082 -306.408978) (xy 58.678329 -306.397392) (xy 58.732682 -306.393502)
			(xy 58.787036 -306.397387) (xy 58.840284 -306.408968) (xy 58.891341 -306.42801) (xy 58.939168 -306.454125)
			(xy 58.982792 -306.486782) (xy 59.021323 -306.525314) (xy 59.053979 -306.568938) (xy 59.080093 -306.616766)
			(xy 59.099134 -306.667823) (xy 59.110714 -306.721071) (xy 59.114598 -306.775425) (xy 59.475458 -306.775425)
			(xy 59.479343 -306.721067) (xy 59.490923 -306.667815) (xy 59.509965 -306.616754) (xy 59.53608 -306.568922)
			(xy 59.568737 -306.525293) (xy 59.607271 -306.486757) (xy 59.650896 -306.454097) (xy 59.698726 -306.427978)
			(xy 59.749786 -306.408932) (xy 59.803037 -306.397347) (xy 59.857395 -306.393458) (xy 59.911753 -306.397345)
			(xy 59.965004 -306.408929) (xy 60.016065 -306.427974) (xy 60.063895 -306.454091) (xy 60.085986 -306.47005)
			(xy 60.104998 -306.483646) (xy 60.146881 -306.504378) (xy 60.191849 -306.517104) (xy 60.238386 -306.521394)
			(xy 60.284923 -306.517104) (xy 60.329891 -306.504378) (xy 60.371774 -306.483646) (xy 60.390786 -306.47005)
			(xy 60.412914 -306.454146) (xy 60.460738 -306.428028) (xy 60.511792 -306.408983) (xy 60.565037 -306.397398)
			(xy 60.619389 -306.393509) (xy 60.673741 -306.397395) (xy 60.726987 -306.408977) (xy 60.778042 -306.428019)
			(xy 60.825868 -306.454134) (xy 60.86949 -306.486789) (xy 60.90802 -306.525321) (xy 60.940674 -306.568944)
			(xy 60.966787 -306.616771) (xy 60.985827 -306.667827) (xy 60.997407 -306.721073) (xy 61.001291 -306.775425)
			(xy 61.716433 -306.775425) (xy 61.720318 -306.721061) (xy 61.731901 -306.667804) (xy 61.750945 -306.616737)
			(xy 61.777064 -306.568901) (xy 61.809725 -306.525269) (xy 61.848264 -306.486729) (xy 61.891895 -306.454067)
			(xy 61.939731 -306.427948) (xy 61.990798 -306.408902) (xy 62.044055 -306.397319) (xy 62.098419 -306.393433)
			(xy 62.152782 -306.397324) (xy 62.206038 -306.408913) (xy 62.257103 -306.427963) (xy 62.304936 -306.454088)
			(xy 62.327028 -306.47005) (xy 62.34604 -306.483646) (xy 62.387923 -306.504378) (xy 62.432891 -306.517104)
			(xy 62.479428 -306.521394) (xy 62.525965 -306.517104) (xy 62.570933 -306.504378) (xy 62.612816 -306.483646)
			(xy 62.631828 -306.47005) (xy 62.653955 -306.454149) (xy 62.701776 -306.428038) (xy 62.752826 -306.408999)
			(xy 62.806067 -306.397419) (xy 62.860413 -306.393534) (xy 62.914759 -306.397423) (xy 62.967999 -306.409006)
			(xy 63.019048 -306.428049) (xy 63.066867 -306.454163) (xy 63.110483 -306.486817) (xy 63.149008 -306.525346)
			(xy 63.181657 -306.568965) (xy 63.207767 -306.616787) (xy 63.226804 -306.667838) (xy 63.238383 -306.721079)
			(xy 63.242266 -306.775425) (xy 63.620443 -306.775425) (xy 63.624327 -306.721064) (xy 63.635909 -306.667808)
			(xy 63.654953 -306.616743) (xy 63.68107 -306.568909) (xy 63.71373 -306.525278) (xy 63.752266 -306.48674)
			(xy 63.795896 -306.454079) (xy 63.843729 -306.427959) (xy 63.894793 -306.408914) (xy 63.948048 -306.39733)
			(xy 64.00241 -306.393443) (xy 64.056771 -306.397332) (xy 64.110025 -306.408919) (xy 64.161088 -306.427967)
			(xy 64.208921 -306.454089) (xy 64.231012 -306.47005) (xy 64.250024 -306.483646) (xy 64.291907 -306.504378)
			(xy 64.336875 -306.517104) (xy 64.383412 -306.521394) (xy 64.429949 -306.517104) (xy 64.474917 -306.504378)
			(xy 64.5168 -306.483646) (xy 64.535812 -306.47005) (xy 64.557939 -306.454148) (xy 64.605761 -306.428034)
			(xy 64.656813 -306.408993) (xy 64.710055 -306.397411) (xy 64.764404 -306.393524) (xy 64.818752 -306.397412)
			(xy 64.871994 -306.408995) (xy 64.923046 -306.428038) (xy 64.970867 -306.454152) (xy 65.014486 -306.486807)
			(xy 65.053013 -306.525336) (xy 65.085664 -306.568957) (xy 65.111774 -306.616781) (xy 65.130813 -306.667834)
			(xy 65.142392 -306.721076) (xy 65.146276 -306.775425) (xy 65.142385 -306.829773) (xy 65.130799 -306.883015)
			(xy 65.111753 -306.934065) (xy 65.085636 -306.981885) (xy 65.05298 -307.025502) (xy 65.014448 -307.064026)
			(xy 64.970825 -307.096675) (xy 64.923 -307.122783) (xy 64.871946 -307.141819) (xy 64.818703 -307.153395)
			(xy 64.764354 -307.157276) (xy 64.710006 -307.153382) (xy 64.656765 -307.141793) (xy 64.605716 -307.122745)
			(xy 64.557897 -307.096625) (xy 64.535812 -307.080666) (xy 64.5168 -307.06707) (xy 64.474917 -307.046338)
			(xy 64.429949 -307.033612) (xy 64.383412 -307.029322) (xy 64.336875 -307.033612) (xy 64.291907 -307.046338)
			(xy 64.250024 -307.06707) (xy 64.231012 -307.080666) (xy 64.208963 -307.096684) (xy 64.161134 -307.122812)
			(xy 64.110074 -307.141867) (xy 64.056821 -307.153461) (xy 64.00246 -307.157357) (xy 63.948098 -307.153478)
			(xy 63.894842 -307.141901) (xy 63.843775 -307.122862) (xy 63.795938 -307.096749) (xy 63.752305 -307.064093)
			(xy 63.713763 -307.02556) (xy 63.681098 -306.981934) (xy 63.654974 -306.934102) (xy 63.635924 -306.88304)
			(xy 63.624334 -306.829786) (xy 63.620443 -306.775425) (xy 63.242266 -306.775425) (xy 63.238376 -306.829771)
			(xy 63.22679 -306.88301) (xy 63.207746 -306.934059) (xy 63.18163 -306.981877) (xy 63.148975 -307.025492)
			(xy 63.110445 -307.064016) (xy 63.066825 -307.096664) (xy 63.019002 -307.122772) (xy 62.96795 -307.141808)
			(xy 62.914709 -307.153384) (xy 62.860363 -307.157266) (xy 62.806017 -307.153374) (xy 62.752778 -307.141787)
			(xy 62.70173 -307.122741) (xy 62.653912 -307.096624) (xy 62.631828 -307.080666) (xy 62.612816 -307.06707)
			(xy 62.570933 -307.046338) (xy 62.525965 -307.033612) (xy 62.479428 -307.029322) (xy 62.432891 -307.033612)
			(xy 62.387923 -307.046338) (xy 62.34604 -307.06707) (xy 62.327028 -307.080666) (xy 62.304979 -307.096685)
			(xy 62.257149 -307.122816) (xy 62.206087 -307.141873) (xy 62.152832 -307.153469) (xy 62.098469 -307.157367)
			(xy 62.044105 -307.153488) (xy 61.990846 -307.141912) (xy 61.939777 -307.122873) (xy 61.891938 -307.09676)
			(xy 61.848302 -307.064104) (xy 61.809758 -307.025569) (xy 61.777091 -306.981942) (xy 61.750966 -306.934109)
			(xy 61.731915 -306.883044) (xy 61.720325 -306.829788) (xy 61.716433 -306.775425) (xy 61.001291 -306.775425)
			(xy 60.9974 -306.829777) (xy 60.985813 -306.883022) (xy 60.966766 -306.934075) (xy 60.940647 -306.981898)
			(xy 60.907987 -307.025517) (xy 60.869452 -307.064044) (xy 60.825826 -307.096693) (xy 60.777997 -307.122802)
			(xy 60.726939 -307.141837) (xy 60.673691 -307.153412) (xy 60.619339 -307.157291) (xy 60.564987 -307.153395)
			(xy 60.511744 -307.141803) (xy 60.460692 -307.122751) (xy 60.412871 -307.096627) (xy 60.390786 -307.080666)
			(xy 60.371774 -307.06707) (xy 60.329891 -307.046338) (xy 60.284923 -307.033612) (xy 60.238386 -307.029322)
			(xy 60.191849 -307.033612) (xy 60.146881 -307.046338) (xy 60.104998 -307.06707) (xy 60.085986 -307.080666)
			(xy 60.063938 -307.096681) (xy 60.016111 -307.122805) (xy 59.965052 -307.141857) (xy 59.911803 -307.153447)
			(xy 59.857445 -307.157342) (xy 59.803087 -307.15346) (xy 59.749835 -307.141882) (xy 59.698772 -307.122843)
			(xy 59.650939 -307.09673) (xy 59.607309 -307.064076) (xy 59.56877 -307.025545) (xy 59.536108 -306.981921)
			(xy 59.509986 -306.934092) (xy 59.490938 -306.883033) (xy 59.47935 -306.829783) (xy 59.475458 -306.775425)
			(xy 59.114598 -306.775425) (xy 59.110707 -306.829779) (xy 59.09912 -306.883025) (xy 59.080072 -306.93408)
			(xy 59.053951 -306.981904) (xy 59.02129 -307.025524) (xy 58.982754 -307.064051) (xy 58.939126 -307.096702)
			(xy 58.891295 -307.12281) (xy 58.840235 -307.141846) (xy 58.786986 -307.15342) (xy 58.732632 -307.157298)
			(xy 58.678279 -307.153401) (xy 58.625034 -307.141808) (xy 58.573981 -307.122754) (xy 58.52616 -307.096628)
			(xy 58.504074 -307.080666) (xy 58.485062 -307.06707) (xy 58.443179 -307.046338) (xy 58.398211 -307.033612)
			(xy 58.351674 -307.029322) (xy 58.305137 -307.033612) (xy 58.260169 -307.046338) (xy 58.218286 -307.06707)
			(xy 58.199274 -307.080666) (xy 58.177226 -307.09668) (xy 58.1294 -307.122802) (xy 58.078343 -307.141852)
			(xy 58.025094 -307.153441) (xy 57.970738 -307.157335) (xy 57.916382 -307.153452) (xy 57.863131 -307.141874)
			(xy 57.81207 -307.122834) (xy 57.764239 -307.096722) (xy 57.720611 -307.064068) (xy 57.682074 -307.025538)
			(xy 57.649412 -306.981915) (xy 57.623292 -306.934088) (xy 57.604244 -306.88303) (xy 57.592657 -306.829781)
			(xy 57.588765 -306.775425) (xy 52.827367 -306.775425) (xy 52.809906 -306.808091) (xy 52.764844 -306.875531)
			(xy 52.713389 -306.93823) (xy 52.656036 -306.995583) (xy 52.593337 -307.047038) (xy 52.525897 -307.0921)
			(xy 52.454365 -307.130335) (xy 52.379429 -307.161374) (xy 52.301813 -307.184919) (xy 52.222262 -307.200742)
			(xy 52.141543 -307.208692) (xy 52.060433 -307.208692) (xy 51.979714 -307.200742) (xy 51.900163 -307.184919)
			(xy 51.822547 -307.161374) (xy 51.747611 -307.130335) (xy 51.676079 -307.0921) (xy 51.608639 -307.047038)
			(xy 51.54594 -306.995583) (xy 51.488587 -306.93823) (xy 51.437132 -306.875531) (xy 51.39207 -306.808091)
			(xy 51.353835 -306.736559) (xy 51.322796 -306.661623) (xy 51.299251 -306.584007) (xy 51.283428 -306.504456)
			(xy 51.275478 -306.423737) (xy 49.426378 -306.423737) (xy 49.418428 -306.504456) (xy 49.402605 -306.584007)
			(xy 49.37906 -306.661623) (xy 49.348021 -306.736559) (xy 49.309786 -306.808091) (xy 49.264724 -306.875531)
			(xy 49.213269 -306.93823) (xy 49.155916 -306.995583) (xy 49.093217 -307.047038) (xy 49.025777 -307.0921)
			(xy 48.954245 -307.130335) (xy 48.879309 -307.161374) (xy 48.801693 -307.184919) (xy 48.722142 -307.200742)
			(xy 48.641423 -307.208692) (xy 48.560313 -307.208692) (xy 48.479594 -307.200742) (xy 48.400043 -307.184919)
			(xy 48.322427 -307.161374) (xy 48.247491 -307.130335) (xy 48.175959 -307.0921) (xy 48.108519 -307.047038)
			(xy 48.04582 -306.995583) (xy 47.988467 -306.93823) (xy 47.937012 -306.875531) (xy 47.89195 -306.808091)
			(xy 47.853715 -306.736559) (xy 47.822676 -306.661623) (xy 47.799131 -306.584007) (xy 47.783308 -306.504456)
			(xy 47.775358 -306.423737) (xy 28.912312 -306.423737) (xy 28.912312 -307.93336) (xy 29.519874 -307.93336)
			(xy 29.519874 -307.84646) (xy 29.527892 -307.759931) (xy 29.54386 -307.674511) (xy 29.567641 -307.590929)
			(xy 29.599033 -307.509897) (xy 29.637767 -307.432108) (xy 29.683514 -307.358224) (xy 29.735883 -307.288877)
			(xy 29.794427 -307.224657) (xy 29.858647 -307.166113) (xy 29.927994 -307.113744) (xy 30.001878 -307.067997)
			(xy 30.079667 -307.029263) (xy 30.160699 -306.997871) (xy 30.244281 -306.97409) (xy 30.329701 -306.958122)
			(xy 30.41623 -306.950104) (xy 30.50313 -306.950104) (xy 30.589659 -306.958122) (xy 30.675079 -306.97409)
			(xy 30.758661 -306.997871) (xy 30.839693 -307.029263) (xy 30.917482 -307.067997) (xy 30.991366 -307.113744)
			(xy 31.060713 -307.166113) (xy 31.124933 -307.224657) (xy 31.183477 -307.288877) (xy 31.235846 -307.358224)
			(xy 31.281593 -307.432108) (xy 31.320327 -307.509897) (xy 31.351719 -307.590929) (xy 31.3755 -307.674511)
			(xy 31.391468 -307.759931) (xy 31.399486 -307.84646) (xy 31.399988 -307.88991) (xy 31.399486 -307.93336)
			(xy 34.599874 -307.93336) (xy 34.599874 -307.84646) (xy 34.607892 -307.759931) (xy 34.62386 -307.674511)
			(xy 34.647641 -307.590929) (xy 34.679033 -307.509897) (xy 34.717767 -307.432108) (xy 34.763514 -307.358224)
			(xy 34.815883 -307.288877) (xy 34.874427 -307.224657) (xy 34.938647 -307.166113) (xy 35.007994 -307.113744)
			(xy 35.081878 -307.067997) (xy 35.159667 -307.029263) (xy 35.240699 -306.997871) (xy 35.324281 -306.97409)
			(xy 35.409701 -306.958122) (xy 35.49623 -306.950104) (xy 35.58313 -306.950104) (xy 35.669659 -306.958122)
			(xy 35.755079 -306.97409) (xy 35.838661 -306.997871) (xy 35.919693 -307.029263) (xy 35.997482 -307.067997)
			(xy 36.071366 -307.113744) (xy 36.140713 -307.166113) (xy 36.204933 -307.224657) (xy 36.263477 -307.288877)
			(xy 36.315846 -307.358224) (xy 36.361593 -307.432108) (xy 36.400327 -307.509897) (xy 36.431719 -307.590929)
			(xy 36.4555 -307.674511) (xy 36.471468 -307.759931) (xy 36.479486 -307.84646) (xy 36.479988 -307.88991)
			(xy 36.479486 -307.93336) (xy 36.471468 -308.019889) (xy 36.4555 -308.105309) (xy 36.431719 -308.188891)
			(xy 36.400327 -308.269923) (xy 36.361593 -308.347712) (xy 36.315846 -308.421596) (xy 36.263477 -308.490943)
			(xy 36.204933 -308.555163) (xy 36.140713 -308.613707) (xy 36.071366 -308.666076) (xy 36.040464 -308.68521)
			(xy 57.588786 -308.68521) (xy 57.592672 -308.630856) (xy 57.604254 -308.577609) (xy 57.623297 -308.526553)
			(xy 57.649411 -308.478726) (xy 57.682067 -308.435102) (xy 57.720598 -308.39657) (xy 57.764221 -308.363914)
			(xy 57.812047 -308.337799) (xy 57.863104 -308.318756) (xy 57.91635 -308.307173) (xy 57.970704 -308.303286)
			(xy 58.025057 -308.307174) (xy 58.078303 -308.318758) (xy 58.129359 -308.337802) (xy 58.177185 -308.363918)
			(xy 58.199274 -308.379876) (xy 58.218286 -308.393472) (xy 58.260169 -308.414204) (xy 58.305137 -308.42693)
			(xy 58.351674 -308.43122) (xy 58.398211 -308.42693) (xy 58.443179 -308.414204) (xy 58.485062 -308.393472)
			(xy 58.504074 -308.379876) (xy 58.526178 -308.363935) (xy 58.574004 -308.337813) (xy 58.625062 -308.318763)
			(xy 58.67831 -308.307173) (xy 58.732667 -308.303281) (xy 58.787024 -308.307164) (xy 58.840275 -308.318744)
			(xy 58.891335 -308.337785) (xy 58.939166 -308.363899) (xy 58.982794 -308.396556) (xy 59.021329 -308.435089)
			(xy 59.053988 -308.478714) (xy 59.080105 -308.526543) (xy 59.099149 -308.577603) (xy 59.110733 -308.630853)
			(xy 59.114619 -308.68521) (xy 59.475479 -308.68521) (xy 59.479365 -308.630855) (xy 59.490948 -308.577606)
			(xy 59.509991 -308.526548) (xy 59.536106 -308.47872) (xy 59.568763 -308.435095) (xy 59.607296 -308.396563)
			(xy 59.650921 -308.363906) (xy 59.698749 -308.33779) (xy 59.749807 -308.318748) (xy 59.803056 -308.307165)
			(xy 59.85741 -308.303279) (xy 59.911765 -308.307168) (xy 59.965013 -308.318754) (xy 60.01607 -308.337799)
			(xy 60.063897 -308.363917) (xy 60.085986 -308.379876) (xy 60.104998 -308.393472) (xy 60.146881 -308.414204)
			(xy 60.191849 -308.42693) (xy 60.238386 -308.43122) (xy 60.284923 -308.42693) (xy 60.329891 -308.414204)
			(xy 60.371774 -308.393472) (xy 60.390786 -308.379876) (xy 60.41289 -308.363936) (xy 60.460715 -308.337816)
			(xy 60.511771 -308.318767) (xy 60.565019 -308.307179) (xy 60.619374 -308.303288) (xy 60.673729 -308.307172)
			(xy 60.726978 -308.318752) (xy 60.778037 -308.337794) (xy 60.825866 -308.363908) (xy 60.869492 -308.396564)
			(xy 60.908025 -308.435096) (xy 60.940683 -308.47872) (xy 60.966799 -308.526548) (xy 60.985843 -308.577606)
			(xy 60.997426 -308.630855) (xy 61.001312 -308.68521) (xy 61.716454 -308.68521) (xy 61.720341 -308.630849)
			(xy 61.731925 -308.577595) (xy 61.750971 -308.526532) (xy 61.77709 -308.478699) (xy 61.809751 -308.435071)
			(xy 61.848289 -308.396535) (xy 61.89192 -308.363877) (xy 61.939754 -308.33776) (xy 61.990819 -308.318718)
			(xy 62.044073 -308.307137) (xy 62.098434 -308.303254) (xy 62.152795 -308.307147) (xy 62.206047 -308.318737)
			(xy 62.257108 -308.337789) (xy 62.304938 -308.363914) (xy 62.327028 -308.379876) (xy 62.34604 -308.393472)
			(xy 62.387923 -308.414204) (xy 62.432891 -308.42693) (xy 62.479428 -308.43122) (xy 62.525965 -308.42693)
			(xy 62.570933 -308.414204) (xy 62.612816 -308.393472) (xy 62.631828 -308.379876) (xy 62.653931 -308.36394)
			(xy 62.701753 -308.337826) (xy 62.752805 -308.318784) (xy 62.806048 -308.307201) (xy 62.860397 -308.303313)
			(xy 62.914747 -308.3072) (xy 62.96799 -308.318782) (xy 63.019042 -308.337824) (xy 63.066865 -308.363937)
			(xy 63.110485 -308.396591) (xy 63.149014 -308.43512) (xy 63.181667 -308.478741) (xy 63.207779 -308.526564)
			(xy 63.22682 -308.577617) (xy 63.238401 -308.63086) (xy 63.242287 -308.68521) (xy 63.620463 -308.68521)
			(xy 63.62435 -308.630851) (xy 63.635934 -308.577599) (xy 63.654978 -308.526538) (xy 63.681096 -308.478707)
			(xy 63.713756 -308.43508) (xy 63.752292 -308.396545) (xy 63.79592 -308.363888) (xy 63.843752 -308.337772)
			(xy 63.894814 -308.318729) (xy 63.948067 -308.307148) (xy 64.002425 -308.303263) (xy 64.056783 -308.307155)
			(xy 64.110034 -308.318743) (xy 64.161094 -308.337793) (xy 64.208922 -308.363915) (xy 64.231012 -308.379876)
			(xy 64.250024 -308.393472) (xy 64.291907 -308.414204) (xy 64.336875 -308.42693) (xy 64.383412 -308.43122)
			(xy 64.429949 -308.42693) (xy 64.474917 -308.414204) (xy 64.5168 -308.393472) (xy 64.535812 -308.379876)
			(xy 64.557915 -308.363939) (xy 64.605739 -308.337822) (xy 64.656792 -308.318777) (xy 64.710037 -308.307193)
			(xy 64.764388 -308.303303) (xy 64.81874 -308.307189) (xy 64.871985 -308.318771) (xy 64.92304 -308.337812)
			(xy 64.970866 -308.363926) (xy 65.014488 -308.396581) (xy 65.053018 -308.435111) (xy 65.085673 -308.478733)
			(xy 65.111787 -308.526558) (xy 65.130829 -308.577613) (xy 65.14241 -308.630858) (xy 65.146297 -308.68521)
			(xy 65.142408 -308.739561) (xy 65.130823 -308.792806) (xy 65.111779 -308.84386) (xy 65.085662 -308.891683)
			(xy 65.053006 -308.935304) (xy 65.014473 -308.973832) (xy 64.970849 -309.006484) (xy 64.923023 -309.032596)
			(xy 64.871967 -309.051635) (xy 64.818721 -309.063213) (xy 64.764369 -309.067097) (xy 64.710018 -309.063205)
			(xy 64.656774 -309.051617) (xy 64.605721 -309.03257) (xy 64.557899 -309.006451) (xy 64.535812 -308.990492)
			(xy 64.5168 -308.976896) (xy 64.474917 -308.956164) (xy 64.429949 -308.943438) (xy 64.383412 -308.939148)
			(xy 64.336875 -308.943438) (xy 64.291907 -308.956164) (xy 64.250024 -308.976896) (xy 64.231012 -308.990492)
			(xy 64.208939 -309.006475) (xy 64.161111 -309.032599) (xy 64.110053 -309.051651) (xy 64.056802 -309.063242)
			(xy 64.002444 -309.067137) (xy 63.948086 -309.063255) (xy 63.894833 -309.051676) (xy 63.84377 -309.032636)
			(xy 63.795936 -309.006523) (xy 63.752306 -308.973867) (xy 63.713768 -308.935334) (xy 63.681107 -308.891709)
			(xy 63.654986 -308.84388) (xy 63.635939 -308.792819) (xy 63.624353 -308.739568) (xy 63.620463 -308.68521)
			(xy 63.242287 -308.68521) (xy 63.238398 -308.739559) (xy 63.226815 -308.792801) (xy 63.207771 -308.843853)
			(xy 63.181656 -308.891675) (xy 63.149001 -308.935294) (xy 63.110471 -308.973822) (xy 63.066849 -309.006473)
			(xy 63.019025 -309.032584) (xy 62.967971 -309.051623) (xy 62.914728 -309.063203) (xy 62.860378 -309.067087)
			(xy 62.806029 -309.063197) (xy 62.752787 -309.051611) (xy 62.701736 -309.032566) (xy 62.653914 -309.00645)
			(xy 62.631828 -308.990492) (xy 62.612816 -308.976896) (xy 62.570933 -308.956164) (xy 62.525965 -308.943438)
			(xy 62.479428 -308.939148) (xy 62.432891 -308.943438) (xy 62.387923 -308.956164) (xy 62.34604 -308.976896)
			(xy 62.327028 -308.990492) (xy 62.304954 -309.006476) (xy 62.257126 -309.032603) (xy 62.206066 -309.051657)
			(xy 62.152814 -309.06325) (xy 62.098454 -309.067146) (xy 62.044092 -309.063266) (xy 61.990837 -309.051687)
			(xy 61.939772 -309.032648) (xy 61.891936 -309.006534) (xy 61.848304 -308.973878) (xy 61.809764 -308.935344)
			(xy 61.7771 -308.891717) (xy 61.750979 -308.843886) (xy 61.73193 -308.792824) (xy 61.720343 -308.73957)
			(xy 61.716454 -308.68521) (xy 61.001312 -308.68521) (xy 60.997423 -308.739565) (xy 60.985837 -308.792813)
			(xy 60.966791 -308.84387) (xy 60.940673 -308.891696) (xy 60.908013 -308.935319) (xy 60.869477 -308.973849)
			(xy 60.82585 -309.006502) (xy 60.778019 -309.032614) (xy 60.72696 -309.051653) (xy 60.67371 -309.063231)
			(xy 60.619354 -309.067112) (xy 60.565 -309.063218) (xy 60.511753 -309.051627) (xy 60.460698 -309.032576)
			(xy 60.412873 -309.006453) (xy 60.390786 -308.990492) (xy 60.371774 -308.976896) (xy 60.329891 -308.956164)
			(xy 60.284923 -308.943438) (xy 60.238386 -308.939148) (xy 60.191849 -308.943438) (xy 60.146881 -308.956164)
			(xy 60.104998 -308.976896) (xy 60.085986 -308.990492) (xy 60.063913 -309.006472) (xy 60.016088 -309.032593)
			(xy 59.965032 -309.051641) (xy 59.911784 -309.063229) (xy 59.85743 -309.067121) (xy 59.803075 -309.063237)
			(xy 59.749825 -309.051658) (xy 59.698766 -309.032618) (xy 59.650937 -309.006504) (xy 59.607311 -308.97385)
			(xy 59.568776 -308.935319) (xy 59.536117 -308.891696) (xy 59.509999 -308.843869) (xy 59.490953 -308.792812)
			(xy 59.479368 -308.739564) (xy 59.475479 -308.68521) (xy 59.114619 -308.68521) (xy 59.11073 -308.739566)
			(xy 59.099144 -308.792816) (xy 59.080097 -308.843874) (xy 59.053977 -308.891702) (xy 59.021316 -308.935326)
			(xy 58.982779 -308.973857) (xy 58.93915 -309.006511) (xy 58.891318 -309.032623) (xy 58.840256 -309.051661)
			(xy 58.787005 -309.063239) (xy 58.732648 -309.067119) (xy 58.678291 -309.063224) (xy 58.625043 -309.051632)
			(xy 58.573987 -309.032579) (xy 58.526162 -309.006454) (xy 58.504074 -308.990492) (xy 58.485062 -308.976896)
			(xy 58.443179 -308.956164) (xy 58.398211 -308.943438) (xy 58.351674 -308.939148) (xy 58.305137 -308.943438)
			(xy 58.260169 -308.956164) (xy 58.218286 -308.976896) (xy 58.199274 -308.990492) (xy 58.177201 -309.006471)
			(xy 58.129377 -309.03259) (xy 58.078322 -309.051636) (xy 58.025076 -309.063223) (xy 57.970723 -309.067114)
			(xy 57.916369 -309.063229) (xy 57.863122 -309.051649) (xy 57.812065 -309.032609) (xy 57.764237 -309.006496)
			(xy 57.720612 -308.973842) (xy 57.682079 -308.935312) (xy 57.649422 -308.89169) (xy 57.623305 -308.843865)
			(xy 57.60426 -308.792809) (xy 57.592675 -308.739563) (xy 57.588786 -308.68521) (xy 36.040464 -308.68521)
			(xy 35.997482 -308.711823) (xy 35.919693 -308.750557) (xy 35.838661 -308.781949) (xy 35.755079 -308.80573)
			(xy 35.669659 -308.821698) (xy 35.58313 -308.829716) (xy 35.49623 -308.829716) (xy 35.409701 -308.821698)
			(xy 35.324281 -308.80573) (xy 35.240699 -308.781949) (xy 35.159667 -308.750557) (xy 35.081878 -308.711823)
			(xy 35.007994 -308.666076) (xy 34.938647 -308.613707) (xy 34.874427 -308.555163) (xy 34.815883 -308.490943)
			(xy 34.763514 -308.421596) (xy 34.717767 -308.347712) (xy 34.679033 -308.269923) (xy 34.647641 -308.188891)
			(xy 34.62386 -308.105309) (xy 34.607892 -308.019889) (xy 34.599874 -307.93336) (xy 31.399486 -307.93336)
			(xy 31.391468 -308.019889) (xy 31.3755 -308.105309) (xy 31.351719 -308.188891) (xy 31.320327 -308.269923)
			(xy 31.281593 -308.347712) (xy 31.235846 -308.421596) (xy 31.183477 -308.490943) (xy 31.124933 -308.555163)
			(xy 31.060713 -308.613707) (xy 30.991366 -308.666076) (xy 30.917482 -308.711823) (xy 30.839693 -308.750557)
			(xy 30.758661 -308.781949) (xy 30.675079 -308.80573) (xy 30.589659 -308.821698) (xy 30.50313 -308.829716)
			(xy 30.41623 -308.829716) (xy 30.329701 -308.821698) (xy 30.244281 -308.80573) (xy 30.160699 -308.781949)
			(xy 30.079667 -308.750557) (xy 30.001878 -308.711823) (xy 29.927994 -308.666076) (xy 29.858647 -308.613707)
			(xy 29.794427 -308.555163) (xy 29.735883 -308.490943) (xy 29.683514 -308.421596) (xy 29.637767 -308.347712)
			(xy 29.599033 -308.269923) (xy 29.567641 -308.188891) (xy 29.54386 -308.105309) (xy 29.527892 -308.019889)
			(xy 29.519874 -307.93336) (xy 28.912312 -307.93336) (xy 28.912312 -310.47336) (xy 29.519874 -310.47336)
			(xy 29.519874 -310.38646) (xy 29.527892 -310.299931) (xy 29.54386 -310.214511) (xy 29.567641 -310.130929)
			(xy 29.599033 -310.049897) (xy 29.637767 -309.972108) (xy 29.683514 -309.898224) (xy 29.735883 -309.828877)
			(xy 29.794427 -309.764657) (xy 29.858647 -309.706113) (xy 29.927994 -309.653744) (xy 30.001878 -309.607997)
			(xy 30.079667 -309.569263) (xy 30.160699 -309.537871) (xy 30.244281 -309.51409) (xy 30.329701 -309.498122)
			(xy 30.41623 -309.490104) (xy 30.50313 -309.490104) (xy 30.589659 -309.498122) (xy 30.675079 -309.51409)
			(xy 30.758661 -309.537871) (xy 30.839693 -309.569263) (xy 30.917482 -309.607997) (xy 30.991366 -309.653744)
			(xy 31.060713 -309.706113) (xy 31.124933 -309.764657) (xy 31.183477 -309.828877) (xy 31.235846 -309.898224)
			(xy 31.281593 -309.972108) (xy 31.320327 -310.049897) (xy 31.351719 -310.130929) (xy 31.3755 -310.214511)
			(xy 31.391468 -310.299931) (xy 31.399486 -310.38646) (xy 31.399988 -310.42991) (xy 31.399486 -310.47336)
			(xy 34.599874 -310.47336) (xy 34.599874 -310.38646) (xy 34.607892 -310.299931) (xy 34.62386 -310.214511)
			(xy 34.647641 -310.130929) (xy 34.679033 -310.049897) (xy 34.717767 -309.972108) (xy 34.763514 -309.898224)
			(xy 34.815883 -309.828877) (xy 34.874427 -309.764657) (xy 34.938647 -309.706113) (xy 35.007994 -309.653744)
			(xy 35.081878 -309.607997) (xy 35.159667 -309.569263) (xy 35.240699 -309.537871) (xy 35.324281 -309.51409)
			(xy 35.409701 -309.498122) (xy 35.49623 -309.490104) (xy 35.58313 -309.490104) (xy 35.669659 -309.498122)
			(xy 35.755079 -309.51409) (xy 35.838661 -309.537871) (xy 35.919693 -309.569263) (xy 35.997482 -309.607997)
			(xy 36.071366 -309.653744) (xy 36.140713 -309.706113) (xy 36.204933 -309.764657) (xy 36.263477 -309.828877)
			(xy 36.315846 -309.898224) (xy 36.361593 -309.972108) (xy 36.400327 -310.049897) (xy 36.431719 -310.130929)
			(xy 36.4555 -310.214511) (xy 36.471468 -310.299931) (xy 36.479486 -310.38646) (xy 36.479988 -310.42991)
			(xy 36.479486 -310.47336) (xy 36.471468 -310.559889) (xy 36.4555 -310.645309) (xy 36.431719 -310.728891)
			(xy 36.400327 -310.809923) (xy 36.361593 -310.887712) (xy 36.315846 -310.961596) (xy 36.263477 -311.030943)
			(xy 36.204933 -311.095163) (xy 36.140713 -311.153707) (xy 36.071366 -311.206076) (xy 35.997482 -311.251823)
			(xy 35.919693 -311.290557) (xy 35.838661 -311.321949) (xy 35.755079 -311.34573) (xy 35.669659 -311.361698)
			(xy 35.58313 -311.369716) (xy 35.49623 -311.369716) (xy 35.409701 -311.361698) (xy 35.324281 -311.34573)
			(xy 35.240699 -311.321949) (xy 35.159667 -311.290557) (xy 35.081878 -311.251823) (xy 35.007994 -311.206076)
			(xy 34.938647 -311.153707) (xy 34.874427 -311.095163) (xy 34.815883 -311.030943) (xy 34.763514 -310.961596)
			(xy 34.717767 -310.887712) (xy 34.679033 -310.809923) (xy 34.647641 -310.728891) (xy 34.62386 -310.645309)
			(xy 34.607892 -310.559889) (xy 34.599874 -310.47336) (xy 31.399486 -310.47336) (xy 31.391468 -310.559889)
			(xy 31.3755 -310.645309) (xy 31.351719 -310.728891) (xy 31.320327 -310.809923) (xy 31.281593 -310.887712)
			(xy 31.235846 -310.961596) (xy 31.183477 -311.030943) (xy 31.124933 -311.095163) (xy 31.060713 -311.153707)
			(xy 30.991366 -311.206076) (xy 30.917482 -311.251823) (xy 30.839693 -311.290557) (xy 30.758661 -311.321949)
			(xy 30.675079 -311.34573) (xy 30.589659 -311.361698) (xy 30.50313 -311.369716) (xy 30.41623 -311.369716)
			(xy 30.329701 -311.361698) (xy 30.244281 -311.34573) (xy 30.160699 -311.321949) (xy 30.079667 -311.290557)
			(xy 30.001878 -311.251823) (xy 29.927994 -311.206076) (xy 29.858647 -311.153707) (xy 29.794427 -311.095163)
			(xy 29.735883 -311.030943) (xy 29.683514 -310.961596) (xy 29.637767 -310.887712) (xy 29.599033 -310.809923)
			(xy 29.567641 -310.728891) (xy 29.54386 -310.645309) (xy 29.527892 -310.559889) (xy 29.519874 -310.47336)
			(xy 28.912312 -310.47336) (xy 28.912312 -313.01336) (xy 29.519874 -313.01336) (xy 29.519874 -312.92646)
			(xy 29.527892 -312.839931) (xy 29.54386 -312.754511) (xy 29.567641 -312.670929) (xy 29.599033 -312.589897)
			(xy 29.637767 -312.512108) (xy 29.683514 -312.438224) (xy 29.735883 -312.368877) (xy 29.794427 -312.304657)
			(xy 29.858647 -312.246113) (xy 29.927994 -312.193744) (xy 30.001878 -312.147997) (xy 30.079667 -312.109263)
			(xy 30.160699 -312.077871) (xy 30.244281 -312.05409) (xy 30.329701 -312.038122) (xy 30.41623 -312.030104)
			(xy 30.50313 -312.030104) (xy 30.589659 -312.038122) (xy 30.675079 -312.05409) (xy 30.758661 -312.077871)
			(xy 30.839693 -312.109263) (xy 30.917482 -312.147997) (xy 30.991366 -312.193744) (xy 31.060713 -312.246113)
			(xy 31.124933 -312.304657) (xy 31.183477 -312.368877) (xy 31.235846 -312.438224) (xy 31.281593 -312.512108)
			(xy 31.320327 -312.589897) (xy 31.351719 -312.670929) (xy 31.3755 -312.754511) (xy 31.391468 -312.839931)
			(xy 31.399486 -312.92646) (xy 31.399988 -312.96991) (xy 31.399486 -313.01336) (xy 34.599874 -313.01336)
			(xy 34.599874 -312.92646) (xy 34.607892 -312.839931) (xy 34.62386 -312.754511) (xy 34.647641 -312.670929)
			(xy 34.679033 -312.589897) (xy 34.717767 -312.512108) (xy 34.763514 -312.438224) (xy 34.815883 -312.368877)
			(xy 34.874427 -312.304657) (xy 34.938647 -312.246113) (xy 35.007994 -312.193744) (xy 35.081878 -312.147997)
			(xy 35.159667 -312.109263) (xy 35.240699 -312.077871) (xy 35.324281 -312.05409) (xy 35.409701 -312.038122)
			(xy 35.49623 -312.030104) (xy 35.58313 -312.030104) (xy 35.669659 -312.038122) (xy 35.755079 -312.05409)
			(xy 35.838661 -312.077871) (xy 35.919693 -312.109263) (xy 35.997482 -312.147997) (xy 36.071366 -312.193744)
			(xy 36.140713 -312.246113) (xy 36.204933 -312.304657) (xy 36.263477 -312.368877) (xy 36.315846 -312.438224)
			(xy 36.361593 -312.512108) (xy 36.400327 -312.589897) (xy 36.431719 -312.670929) (xy 36.4555 -312.754511)
			(xy 36.471468 -312.839931) (xy 36.479486 -312.92646) (xy 36.479988 -312.96991) (xy 36.479486 -313.01336)
			(xy 36.471468 -313.099889) (xy 36.4555 -313.185309) (xy 36.431719 -313.268891) (xy 36.400327 -313.349923)
			(xy 36.361593 -313.427712) (xy 36.315846 -313.501596) (xy 36.263477 -313.570943) (xy 36.204933 -313.635163)
			(xy 36.140713 -313.693707) (xy 36.071366 -313.746076) (xy 35.997482 -313.791823) (xy 35.919693 -313.830557)
			(xy 35.838661 -313.861949) (xy 35.755079 -313.88573) (xy 35.669659 -313.901698) (xy 35.58313 -313.909716)
			(xy 35.49623 -313.909716) (xy 35.409701 -313.901698) (xy 35.324281 -313.88573) (xy 35.240699 -313.861949)
			(xy 35.159667 -313.830557) (xy 35.081878 -313.791823) (xy 35.007994 -313.746076) (xy 34.938647 -313.693707)
			(xy 34.874427 -313.635163) (xy 34.815883 -313.570943) (xy 34.763514 -313.501596) (xy 34.717767 -313.427712)
			(xy 34.679033 -313.349923) (xy 34.647641 -313.268891) (xy 34.62386 -313.185309) (xy 34.607892 -313.099889)
			(xy 34.599874 -313.01336) (xy 31.399486 -313.01336) (xy 31.391468 -313.099889) (xy 31.3755 -313.185309)
			(xy 31.351719 -313.268891) (xy 31.320327 -313.349923) (xy 31.281593 -313.427712) (xy 31.235846 -313.501596)
			(xy 31.183477 -313.570943) (xy 31.124933 -313.635163) (xy 31.060713 -313.693707) (xy 30.991366 -313.746076)
			(xy 30.917482 -313.791823) (xy 30.839693 -313.830557) (xy 30.758661 -313.861949) (xy 30.675079 -313.88573)
			(xy 30.589659 -313.901698) (xy 30.50313 -313.909716) (xy 30.41623 -313.909716) (xy 30.329701 -313.901698)
			(xy 30.244281 -313.88573) (xy 30.160699 -313.861949) (xy 30.079667 -313.830557) (xy 30.001878 -313.791823)
			(xy 29.927994 -313.746076) (xy 29.858647 -313.693707) (xy 29.794427 -313.635163) (xy 29.735883 -313.570943)
			(xy 29.683514 -313.501596) (xy 29.637767 -313.427712) (xy 29.599033 -313.349923) (xy 29.567641 -313.268891)
			(xy 29.54386 -313.185309) (xy 29.527892 -313.099889) (xy 29.519874 -313.01336) (xy 28.912312 -313.01336)
			(xy 28.912312 -315.55336) (xy 29.519874 -315.55336) (xy 29.519874 -315.46646) (xy 29.527892 -315.379931)
			(xy 29.54386 -315.294511) (xy 29.567641 -315.210929) (xy 29.599033 -315.129897) (xy 29.637767 -315.052108)
			(xy 29.683514 -314.978224) (xy 29.735883 -314.908877) (xy 29.794427 -314.844657) (xy 29.858647 -314.786113)
			(xy 29.927994 -314.733744) (xy 30.001878 -314.687997) (xy 30.079667 -314.649263) (xy 30.160699 -314.617871)
			(xy 30.244281 -314.59409) (xy 30.329701 -314.578122) (xy 30.41623 -314.570104) (xy 30.50313 -314.570104)
			(xy 30.589659 -314.578122) (xy 30.675079 -314.59409) (xy 30.758661 -314.617871) (xy 30.839693 -314.649263)
			(xy 30.917482 -314.687997) (xy 30.991366 -314.733744) (xy 31.060713 -314.786113) (xy 31.124933 -314.844657)
			(xy 31.183477 -314.908877) (xy 31.235846 -314.978224) (xy 31.281593 -315.052108) (xy 31.320327 -315.129897)
			(xy 31.351719 -315.210929) (xy 31.3755 -315.294511) (xy 31.391468 -315.379931) (xy 31.399486 -315.46646)
			(xy 31.399988 -315.50991) (xy 31.399486 -315.55336) (xy 34.599874 -315.55336) (xy 34.599874 -315.46646)
			(xy 34.607892 -315.379931) (xy 34.62386 -315.294511) (xy 34.647641 -315.210929) (xy 34.679033 -315.129897)
			(xy 34.717767 -315.052108) (xy 34.763514 -314.978224) (xy 34.815883 -314.908877) (xy 34.874427 -314.844657)
			(xy 34.938647 -314.786113) (xy 35.007994 -314.733744) (xy 35.081878 -314.687997) (xy 35.159667 -314.649263)
			(xy 35.240699 -314.617871) (xy 35.324281 -314.59409) (xy 35.409701 -314.578122) (xy 35.49623 -314.570104)
			(xy 35.58313 -314.570104) (xy 35.669659 -314.578122) (xy 35.755079 -314.59409) (xy 35.838661 -314.617871)
			(xy 35.919693 -314.649263) (xy 35.997482 -314.687997) (xy 36.071366 -314.733744) (xy 36.140713 -314.786113)
			(xy 36.204933 -314.844657) (xy 36.263477 -314.908877) (xy 36.315846 -314.978224) (xy 36.361593 -315.052108)
			(xy 36.400327 -315.129897) (xy 36.431719 -315.210929) (xy 36.4555 -315.294511) (xy 36.471468 -315.379931)
			(xy 36.479486 -315.46646) (xy 36.479988 -315.50991) (xy 36.479486 -315.55336) (xy 36.471468 -315.639889)
			(xy 36.4555 -315.725309) (xy 36.431719 -315.808891) (xy 36.400327 -315.889923) (xy 36.361593 -315.967712)
			(xy 36.315846 -316.041596) (xy 36.263477 -316.110943) (xy 36.204933 -316.175163) (xy 36.140713 -316.233707)
			(xy 36.071366 -316.286076) (xy 35.997482 -316.331823) (xy 35.919693 -316.370557) (xy 35.838661 -316.401949)
			(xy 35.755079 -316.42573) (xy 35.669659 -316.441698) (xy 35.58313 -316.449716) (xy 35.49623 -316.449716)
			(xy 35.409701 -316.441698) (xy 35.324281 -316.42573) (xy 35.240699 -316.401949) (xy 35.159667 -316.370557)
			(xy 35.081878 -316.331823) (xy 35.007994 -316.286076) (xy 34.938647 -316.233707) (xy 34.874427 -316.175163)
			(xy 34.815883 -316.110943) (xy 34.763514 -316.041596) (xy 34.717767 -315.967712) (xy 34.679033 -315.889923)
			(xy 34.647641 -315.808891) (xy 34.62386 -315.725309) (xy 34.607892 -315.639889) (xy 34.599874 -315.55336)
			(xy 31.399486 -315.55336) (xy 31.391468 -315.639889) (xy 31.3755 -315.725309) (xy 31.351719 -315.808891)
			(xy 31.320327 -315.889923) (xy 31.281593 -315.967712) (xy 31.235846 -316.041596) (xy 31.183477 -316.110943)
			(xy 31.124933 -316.175163) (xy 31.060713 -316.233707) (xy 30.991366 -316.286076) (xy 30.917482 -316.331823)
			(xy 30.839693 -316.370557) (xy 30.758661 -316.401949) (xy 30.675079 -316.42573) (xy 30.589659 -316.441698)
			(xy 30.50313 -316.449716) (xy 30.41623 -316.449716) (xy 30.329701 -316.441698) (xy 30.244281 -316.42573)
			(xy 30.160699 -316.401949) (xy 30.079667 -316.370557) (xy 30.001878 -316.331823) (xy 29.927994 -316.286076)
			(xy 29.858647 -316.233707) (xy 29.794427 -316.175163) (xy 29.735883 -316.110943) (xy 29.683514 -316.041596)
			(xy 29.637767 -315.967712) (xy 29.599033 -315.889923) (xy 29.567641 -315.808891) (xy 29.54386 -315.725309)
			(xy 29.527892 -315.639889) (xy 29.519874 -315.55336) (xy 28.912312 -315.55336) (xy 28.912312 -318.09336)
			(xy 29.519874 -318.09336) (xy 29.519874 -318.00646) (xy 29.527892 -317.919931) (xy 29.54386 -317.834511)
			(xy 29.567641 -317.750929) (xy 29.599033 -317.669897) (xy 29.637767 -317.592108) (xy 29.683514 -317.518224)
			(xy 29.735883 -317.448877) (xy 29.794427 -317.384657) (xy 29.858647 -317.326113) (xy 29.927994 -317.273744)
			(xy 30.001878 -317.227997) (xy 30.079667 -317.189263) (xy 30.160699 -317.157871) (xy 30.244281 -317.13409)
			(xy 30.329701 -317.118122) (xy 30.41623 -317.110104) (xy 30.50313 -317.110104) (xy 30.589659 -317.118122)
			(xy 30.675079 -317.13409) (xy 30.758661 -317.157871) (xy 30.839693 -317.189263) (xy 30.917482 -317.227997)
			(xy 30.991366 -317.273744) (xy 31.060713 -317.326113) (xy 31.124933 -317.384657) (xy 31.183477 -317.448877)
			(xy 31.235846 -317.518224) (xy 31.281593 -317.592108) (xy 31.320327 -317.669897) (xy 31.351719 -317.750929)
			(xy 31.3755 -317.834511) (xy 31.391468 -317.919931) (xy 31.399486 -318.00646) (xy 31.399988 -318.04991)
			(xy 31.399486 -318.09336) (xy 34.599874 -318.09336) (xy 34.599874 -318.00646) (xy 34.607892 -317.919931)
			(xy 34.62386 -317.834511) (xy 34.647641 -317.750929) (xy 34.679033 -317.669897) (xy 34.717767 -317.592108)
			(xy 34.763514 -317.518224) (xy 34.815883 -317.448877) (xy 34.874427 -317.384657) (xy 34.938647 -317.326113)
			(xy 35.007994 -317.273744) (xy 35.081878 -317.227997) (xy 35.159667 -317.189263) (xy 35.240699 -317.157871)
			(xy 35.324281 -317.13409) (xy 35.409701 -317.118122) (xy 35.49623 -317.110104) (xy 35.58313 -317.110104)
			(xy 35.669659 -317.118122) (xy 35.755079 -317.13409) (xy 35.838661 -317.157871) (xy 35.919693 -317.189263)
			(xy 35.997482 -317.227997) (xy 36.071366 -317.273744) (xy 36.140713 -317.326113) (xy 36.204933 -317.384657)
			(xy 36.263477 -317.448877) (xy 36.315846 -317.518224) (xy 36.361593 -317.592108) (xy 36.400327 -317.669897)
			(xy 36.431719 -317.750929) (xy 36.4555 -317.834511) (xy 36.471468 -317.919931) (xy 36.479486 -318.00646)
			(xy 36.479988 -318.04991) (xy 36.479871 -318.06007) (xy 39.818564 -318.06007) (xy 39.819058 -318.002661)
			(xy 39.826902 -317.888113) (xy 39.842544 -317.774366) (xy 39.865911 -317.661952) (xy 39.896896 -317.551394)
			(xy 39.935352 -317.443209) (xy 39.981101 -317.3379) (xy 40.03393 -317.235958) (xy 40.093592 -317.137859)
			(xy 40.159809 -317.04406) (xy 40.232272 -316.954998) (xy 40.310645 -316.871089) (xy 40.39456 -316.792723)
			(xy 40.483627 -316.720266) (xy 40.577431 -316.654056) (xy 40.675535 -316.594402) (xy 40.777481 -316.541581)
			(xy 40.882793 -316.495839) (xy 40.990981 -316.457391) (xy 41.101541 -316.426415) (xy 41.213957 -316.403056)
			(xy 41.327705 -316.387423) (xy 41.442254 -316.379588) (xy 41.557072 -316.379588) (xy 41.671621 -316.387423)
			(xy 41.785369 -316.403056) (xy 41.897785 -316.426415) (xy 42.008345 -316.457391) (xy 42.116533 -316.495839)
			(xy 42.221845 -316.541581) (xy 42.323791 -316.594402) (xy 42.421895 -316.654056) (xy 42.501239 -316.71006)
			(xy 43.327577 -316.71006) (xy 43.331612 -316.634356) (xy 43.343671 -316.559511) (xy 43.363617 -316.48637)
			(xy 43.391224 -316.415765) (xy 43.42618 -316.348494) (xy 43.468088 -316.285319) (xy 43.516474 -316.226957)
			(xy 43.57079 -316.174069) (xy 43.630419 -316.127254) (xy 43.694687 -316.087042) (xy 43.762864 -316.05389)
			(xy 43.83418 -316.028172) (xy 43.907825 -316.01018) (xy 43.982965 -316.000118) (xy 44.058749 -315.998099)
			(xy 44.134319 -316.004148) (xy 44.208817 -316.018195) (xy 44.2814 -316.040081) (xy 44.351246 -316.069558)
			(xy 44.417563 -316.106293) (xy 44.479599 -316.149868) (xy 44.536652 -316.19979) (xy 44.588076 -316.255494)
			(xy 44.633287 -316.316349) (xy 44.671774 -316.381664) (xy 44.7031 -316.4507) (xy 44.72691 -316.522675)
			(xy 44.742935 -316.596773) (xy 44.750994 -316.672154) (xy 44.751498 -316.71006) (xy 45.867577 -316.71006)
			(xy 45.871612 -316.634356) (xy 45.883671 -316.559511) (xy 45.903617 -316.48637) (xy 45.931224 -316.415765)
			(xy 45.96618 -316.348494) (xy 46.008088 -316.285319) (xy 46.056474 -316.226957) (xy 46.11079 -316.174069)
			(xy 46.170419 -316.127254) (xy 46.234687 -316.087042) (xy 46.302864 -316.05389) (xy 46.37418 -316.028172)
			(xy 46.447825 -316.01018) (xy 46.522965 -316.000118) (xy 46.598749 -315.998099) (xy 46.674319 -316.004148)
			(xy 46.748817 -316.018195) (xy 46.8214 -316.040081) (xy 46.891246 -316.069558) (xy 46.957563 -316.106293)
			(xy 47.019599 -316.149868) (xy 47.076652 -316.19979) (xy 47.128076 -316.255494) (xy 47.173287 -316.316349)
			(xy 47.211774 -316.381664) (xy 47.2431 -316.4507) (xy 47.26691 -316.522675) (xy 47.282935 -316.596773)
			(xy 47.290994 -316.672154) (xy 47.291498 -316.71006) (xy 48.407577 -316.71006) (xy 48.411612 -316.634356)
			(xy 48.423671 -316.559511) (xy 48.443617 -316.48637) (xy 48.471224 -316.415765) (xy 48.50618 -316.348494)
			(xy 48.548088 -316.285319) (xy 48.596474 -316.226957) (xy 48.65079 -316.174069) (xy 48.710419 -316.127254)
			(xy 48.774687 -316.087042) (xy 48.842864 -316.05389) (xy 48.91418 -316.028172) (xy 48.987825 -316.01018)
			(xy 49.062965 -316.000118) (xy 49.138749 -315.998099) (xy 49.214319 -316.004148) (xy 49.288817 -316.018195)
			(xy 49.3614 -316.040081) (xy 49.431246 -316.069558) (xy 49.497563 -316.106293) (xy 49.559599 -316.149868)
			(xy 49.616652 -316.19979) (xy 49.668076 -316.255494) (xy 49.713287 -316.316349) (xy 49.751774 -316.381664)
			(xy 49.7831 -316.4507) (xy 49.80691 -316.522675) (xy 49.822935 -316.596773) (xy 49.830994 -316.672154)
			(xy 49.831498 -316.71006) (xy 50.947577 -316.71006) (xy 50.951612 -316.634356) (xy 50.963671 -316.559511)
			(xy 50.983617 -316.48637) (xy 51.011224 -316.415765) (xy 51.04618 -316.348494) (xy 51.088088 -316.285319)
			(xy 51.136474 -316.226957) (xy 51.19079 -316.174069) (xy 51.250419 -316.127254) (xy 51.314687 -316.087042)
			(xy 51.382864 -316.05389) (xy 51.45418 -316.028172) (xy 51.527825 -316.01018) (xy 51.602965 -316.000118)
			(xy 51.678749 -315.998099) (xy 51.754319 -316.004148) (xy 51.828817 -316.018195) (xy 51.9014 -316.040081)
			(xy 51.971246 -316.069558) (xy 52.037563 -316.106293) (xy 52.099599 -316.149868) (xy 52.156652 -316.19979)
			(xy 52.208076 -316.255494) (xy 52.253287 -316.316349) (xy 52.291774 -316.381664) (xy 52.3231 -316.4507)
			(xy 52.34691 -316.522675) (xy 52.362935 -316.596773) (xy 52.370994 -316.672154) (xy 52.371498 -316.71006)
			(xy 53.487577 -316.71006) (xy 53.491612 -316.634356) (xy 53.503671 -316.559511) (xy 53.523617 -316.48637)
			(xy 53.551224 -316.415765) (xy 53.58618 -316.348494) (xy 53.628088 -316.285319) (xy 53.676474 -316.226957)
			(xy 53.73079 -316.174069) (xy 53.790419 -316.127254) (xy 53.854687 -316.087042) (xy 53.922864 -316.05389)
			(xy 53.99418 -316.028172) (xy 54.067825 -316.01018) (xy 54.142965 -316.000118) (xy 54.218749 -315.998099)
			(xy 54.294319 -316.004148) (xy 54.368817 -316.018195) (xy 54.4414 -316.040081) (xy 54.511246 -316.069558)
			(xy 54.577563 -316.106293) (xy 54.639599 -316.149868) (xy 54.696652 -316.19979) (xy 54.748076 -316.255494)
			(xy 54.793287 -316.316349) (xy 54.831774 -316.381664) (xy 54.8631 -316.4507) (xy 54.88691 -316.522675)
			(xy 54.902935 -316.596773) (xy 54.910994 -316.672154) (xy 54.911498 -316.71006) (xy 56.027577 -316.71006)
			(xy 56.031612 -316.634356) (xy 56.043671 -316.559511) (xy 56.063617 -316.48637) (xy 56.091224 -316.415765)
			(xy 56.12618 -316.348494) (xy 56.168088 -316.285319) (xy 56.216474 -316.226957) (xy 56.27079 -316.174069)
			(xy 56.330419 -316.127254) (xy 56.394687 -316.087042) (xy 56.462864 -316.05389) (xy 56.53418 -316.028172)
			(xy 56.607825 -316.01018) (xy 56.682965 -316.000118) (xy 56.758749 -315.998099) (xy 56.834319 -316.004148)
			(xy 56.908817 -316.018195) (xy 56.9814 -316.040081) (xy 57.051246 -316.069558) (xy 57.117563 -316.106293)
			(xy 57.179599 -316.149868) (xy 57.236652 -316.19979) (xy 57.288076 -316.255494) (xy 57.333287 -316.316349)
			(xy 57.371774 -316.381664) (xy 57.4031 -316.4507) (xy 57.42691 -316.522675) (xy 57.442935 -316.596773)
			(xy 57.450994 -316.672154) (xy 57.451498 -316.71006) (xy 58.567577 -316.71006) (xy 58.571612 -316.634356)
			(xy 58.583671 -316.559511) (xy 58.603617 -316.48637) (xy 58.631224 -316.415765) (xy 58.66618 -316.348494)
			(xy 58.708088 -316.285319) (xy 58.756474 -316.226957) (xy 58.81079 -316.174069) (xy 58.870419 -316.127254)
			(xy 58.934687 -316.087042) (xy 59.002864 -316.05389) (xy 59.07418 -316.028172) (xy 59.147825 -316.01018)
			(xy 59.222965 -316.000118) (xy 59.298749 -315.998099) (xy 59.374319 -316.004148) (xy 59.448817 -316.018195)
			(xy 59.5214 -316.040081) (xy 59.591246 -316.069558) (xy 59.657563 -316.106293) (xy 59.719599 -316.149868)
			(xy 59.776652 -316.19979) (xy 59.828076 -316.255494) (xy 59.873287 -316.316349) (xy 59.911774 -316.381664)
			(xy 59.9431 -316.4507) (xy 59.96691 -316.522675) (xy 59.982935 -316.596773) (xy 59.990994 -316.672154)
			(xy 59.991498 -316.71006) (xy 61.107577 -316.71006) (xy 61.111612 -316.634356) (xy 61.123671 -316.559511)
			(xy 61.143617 -316.48637) (xy 61.171224 -316.415765) (xy 61.20618 -316.348494) (xy 61.248088 -316.285319)
			(xy 61.296474 -316.226957) (xy 61.35079 -316.174069) (xy 61.410419 -316.127254) (xy 61.474687 -316.087042)
			(xy 61.542864 -316.05389) (xy 61.61418 -316.028172) (xy 61.687825 -316.01018) (xy 61.762965 -316.000118)
			(xy 61.838749 -315.998099) (xy 61.914319 -316.004148) (xy 61.988817 -316.018195) (xy 62.0614 -316.040081)
			(xy 62.131246 -316.069558) (xy 62.197563 -316.106293) (xy 62.259599 -316.149868) (xy 62.316652 -316.19979)
			(xy 62.368076 -316.255494) (xy 62.413287 -316.316349) (xy 62.451774 -316.381664) (xy 62.4831 -316.4507)
			(xy 62.50691 -316.522675) (xy 62.522935 -316.596773) (xy 62.530994 -316.672154) (xy 62.531498 -316.71006)
			(xy 62.530994 -316.747966) (xy 62.522935 -316.823347) (xy 62.50691 -316.897445) (xy 62.4831 -316.96942)
			(xy 62.451774 -317.038456) (xy 62.413287 -317.103771) (xy 62.368076 -317.164626) (xy 62.316652 -317.22033)
			(xy 62.259599 -317.270252) (xy 62.197563 -317.313827) (xy 62.131246 -317.350562) (xy 62.0614 -317.380039)
			(xy 61.988817 -317.401925) (xy 61.914319 -317.415972) (xy 61.838749 -317.422021) (xy 61.762965 -317.420002)
			(xy 61.687825 -317.40994) (xy 61.61418 -317.391948) (xy 61.542864 -317.36623) (xy 61.474687 -317.333078)
			(xy 61.410419 -317.292866) (xy 61.35079 -317.246051) (xy 61.296474 -317.193163) (xy 61.248088 -317.134801)
			(xy 61.20618 -317.071626) (xy 61.171224 -317.004355) (xy 61.143617 -316.93375) (xy 61.123671 -316.860609)
			(xy 61.111612 -316.785764) (xy 61.107577 -316.71006) (xy 59.991498 -316.71006) (xy 59.990994 -316.747966)
			(xy 59.982935 -316.823347) (xy 59.96691 -316.897445) (xy 59.9431 -316.96942) (xy 59.911774 -317.038456)
			(xy 59.873287 -317.103771) (xy 59.828076 -317.164626) (xy 59.776652 -317.22033) (xy 59.719599 -317.270252)
			(xy 59.657563 -317.313827) (xy 59.591246 -317.350562) (xy 59.5214 -317.380039) (xy 59.448817 -317.401925)
			(xy 59.374319 -317.415972) (xy 59.298749 -317.422021) (xy 59.222965 -317.420002) (xy 59.147825 -317.40994)
			(xy 59.07418 -317.391948) (xy 59.002864 -317.36623) (xy 58.934687 -317.333078) (xy 58.870419 -317.292866)
			(xy 58.81079 -317.246051) (xy 58.756474 -317.193163) (xy 58.708088 -317.134801) (xy 58.66618 -317.071626)
			(xy 58.631224 -317.004355) (xy 58.603617 -316.93375) (xy 58.583671 -316.860609) (xy 58.571612 -316.785764)
			(xy 58.567577 -316.71006) (xy 57.451498 -316.71006) (xy 57.450994 -316.747966) (xy 57.442935 -316.823347)
			(xy 57.42691 -316.897445) (xy 57.4031 -316.96942) (xy 57.371774 -317.038456) (xy 57.333287 -317.103771)
			(xy 57.288076 -317.164626) (xy 57.236652 -317.22033) (xy 57.179599 -317.270252) (xy 57.117563 -317.313827)
			(xy 57.051246 -317.350562) (xy 56.9814 -317.380039) (xy 56.908817 -317.401925) (xy 56.834319 -317.415972)
			(xy 56.758749 -317.422021) (xy 56.682965 -317.420002) (xy 56.607825 -317.40994) (xy 56.53418 -317.391948)
			(xy 56.462864 -317.36623) (xy 56.394687 -317.333078) (xy 56.330419 -317.292866) (xy 56.27079 -317.246051)
			(xy 56.216474 -317.193163) (xy 56.168088 -317.134801) (xy 56.12618 -317.071626) (xy 56.091224 -317.004355)
			(xy 56.063617 -316.93375) (xy 56.043671 -316.860609) (xy 56.031612 -316.785764) (xy 56.027577 -316.71006)
			(xy 54.911498 -316.71006) (xy 54.910994 -316.747966) (xy 54.902935 -316.823347) (xy 54.88691 -316.897445)
			(xy 54.8631 -316.96942) (xy 54.831774 -317.038456) (xy 54.793287 -317.103771) (xy 54.748076 -317.164626)
			(xy 54.696652 -317.22033) (xy 54.639599 -317.270252) (xy 54.577563 -317.313827) (xy 54.511246 -317.350562)
			(xy 54.4414 -317.380039) (xy 54.368817 -317.401925) (xy 54.294319 -317.415972) (xy 54.218749 -317.422021)
			(xy 54.142965 -317.420002) (xy 54.067825 -317.40994) (xy 53.99418 -317.391948) (xy 53.922864 -317.36623)
			(xy 53.854687 -317.333078) (xy 53.790419 -317.292866) (xy 53.73079 -317.246051) (xy 53.676474 -317.193163)
			(xy 53.628088 -317.134801) (xy 53.58618 -317.071626) (xy 53.551224 -317.004355) (xy 53.523617 -316.93375)
			(xy 53.503671 -316.860609) (xy 53.491612 -316.785764) (xy 53.487577 -316.71006) (xy 52.371498 -316.71006)
			(xy 52.370994 -316.747966) (xy 52.362935 -316.823347) (xy 52.34691 -316.897445) (xy 52.3231 -316.96942)
			(xy 52.291774 -317.038456) (xy 52.253287 -317.103771) (xy 52.208076 -317.164626) (xy 52.156652 -317.22033)
			(xy 52.099599 -317.270252) (xy 52.037563 -317.313827) (xy 51.971246 -317.350562) (xy 51.9014 -317.380039)
			(xy 51.828817 -317.401925) (xy 51.754319 -317.415972) (xy 51.678749 -317.422021) (xy 51.602965 -317.420002)
			(xy 51.527825 -317.40994) (xy 51.45418 -317.391948) (xy 51.382864 -317.36623) (xy 51.314687 -317.333078)
			(xy 51.250419 -317.292866) (xy 51.19079 -317.246051) (xy 51.136474 -317.193163) (xy 51.088088 -317.134801)
			(xy 51.04618 -317.071626) (xy 51.011224 -317.004355) (xy 50.983617 -316.93375) (xy 50.963671 -316.860609)
			(xy 50.951612 -316.785764) (xy 50.947577 -316.71006) (xy 49.831498 -316.71006) (xy 49.830994 -316.747966)
			(xy 49.822935 -316.823347) (xy 49.80691 -316.897445) (xy 49.7831 -316.96942) (xy 49.751774 -317.038456)
			(xy 49.713287 -317.103771) (xy 49.668076 -317.164626) (xy 49.616652 -317.22033) (xy 49.559599 -317.270252)
			(xy 49.497563 -317.313827) (xy 49.431246 -317.350562) (xy 49.3614 -317.380039) (xy 49.288817 -317.401925)
			(xy 49.214319 -317.415972) (xy 49.138749 -317.422021) (xy 49.062965 -317.420002) (xy 48.987825 -317.40994)
			(xy 48.91418 -317.391948) (xy 48.842864 -317.36623) (xy 48.774687 -317.333078) (xy 48.710419 -317.292866)
			(xy 48.65079 -317.246051) (xy 48.596474 -317.193163) (xy 48.548088 -317.134801) (xy 48.50618 -317.071626)
			(xy 48.471224 -317.004355) (xy 48.443617 -316.93375) (xy 48.423671 -316.860609) (xy 48.411612 -316.785764)
			(xy 48.407577 -316.71006) (xy 47.291498 -316.71006) (xy 47.290994 -316.747966) (xy 47.282935 -316.823347)
			(xy 47.26691 -316.897445) (xy 47.2431 -316.96942) (xy 47.211774 -317.038456) (xy 47.173287 -317.103771)
			(xy 47.128076 -317.164626) (xy 47.076652 -317.22033) (xy 47.019599 -317.270252) (xy 46.957563 -317.313827)
			(xy 46.891246 -317.350562) (xy 46.8214 -317.380039) (xy 46.748817 -317.401925) (xy 46.674319 -317.415972)
			(xy 46.598749 -317.422021) (xy 46.522965 -317.420002) (xy 46.447825 -317.40994) (xy 46.37418 -317.391948)
			(xy 46.302864 -317.36623) (xy 46.234687 -317.333078) (xy 46.170419 -317.292866) (xy 46.11079 -317.246051)
			(xy 46.056474 -317.193163) (xy 46.008088 -317.134801) (xy 45.96618 -317.071626) (xy 45.931224 -317.004355)
			(xy 45.903617 -316.93375) (xy 45.883671 -316.860609) (xy 45.871612 -316.785764) (xy 45.867577 -316.71006)
			(xy 44.751498 -316.71006) (xy 44.750994 -316.747966) (xy 44.742935 -316.823347) (xy 44.72691 -316.897445)
			(xy 44.7031 -316.96942) (xy 44.671774 -317.038456) (xy 44.633287 -317.103771) (xy 44.588076 -317.164626)
			(xy 44.536652 -317.22033) (xy 44.479599 -317.270252) (xy 44.417563 -317.313827) (xy 44.351246 -317.350562)
			(xy 44.2814 -317.380039) (xy 44.208817 -317.401925) (xy 44.134319 -317.415972) (xy 44.058749 -317.422021)
			(xy 43.982965 -317.420002) (xy 43.907825 -317.40994) (xy 43.83418 -317.391948) (xy 43.762864 -317.36623)
			(xy 43.694687 -317.333078) (xy 43.630419 -317.292866) (xy 43.57079 -317.246051) (xy 43.516474 -317.193163)
			(xy 43.468088 -317.134801) (xy 43.42618 -317.071626) (xy 43.391224 -317.004355) (xy 43.363617 -316.93375)
			(xy 43.343671 -316.860609) (xy 43.331612 -316.785764) (xy 43.327577 -316.71006) (xy 42.501239 -316.71006)
			(xy 42.515699 -316.720266) (xy 42.604766 -316.792723) (xy 42.688681 -316.871089) (xy 42.767054 -316.954998)
			(xy 42.839517 -317.04406) (xy 42.905734 -317.137859) (xy 42.965396 -317.235958) (xy 43.018225 -317.3379)
			(xy 43.056094 -317.42507) (xy 84.927697 -317.42507) (xy 84.931732 -317.349366) (xy 84.943791 -317.274521)
			(xy 84.963737 -317.20138) (xy 84.991344 -317.130775) (xy 85.0263 -317.063504) (xy 85.068208 -317.000329)
			(xy 85.116594 -316.941967) (xy 85.17091 -316.889079) (xy 85.230539 -316.842264) (xy 85.294807 -316.802052)
			(xy 85.362984 -316.7689) (xy 85.4343 -316.743182) (xy 85.507945 -316.72519) (xy 85.583085 -316.715128)
			(xy 85.658869 -316.713109) (xy 85.734439 -316.719158) (xy 85.808937 -316.733205) (xy 85.88152 -316.755091)
			(xy 85.951366 -316.784568) (xy 86.017683 -316.821303) (xy 86.079719 -316.864878) (xy 86.136772 -316.9148)
			(xy 86.188196 -316.970504) (xy 86.233407 -317.031359) (xy 86.271894 -317.096674) (xy 86.30322 -317.16571)
			(xy 86.32703 -317.237685) (xy 86.343055 -317.311783) (xy 86.351114 -317.387164) (xy 86.351618 -317.42507)
			(xy 86.351114 -317.462976) (xy 86.343055 -317.538357) (xy 86.32703 -317.612455) (xy 86.30322 -317.68443)
			(xy 86.271894 -317.753466) (xy 86.233407 -317.818781) (xy 86.188196 -317.879636) (xy 86.136772 -317.93534)
			(xy 86.079719 -317.985262) (xy 86.017683 -318.028837) (xy 85.951366 -318.065572) (xy 85.88152 -318.095049)
			(xy 85.808937 -318.116935) (xy 85.734439 -318.130982) (xy 85.658869 -318.137031) (xy 85.583085 -318.135012)
			(xy 85.507945 -318.12495) (xy 85.4343 -318.106958) (xy 85.362984 -318.08124) (xy 85.294807 -318.048088)
			(xy 85.230539 -318.007876) (xy 85.17091 -317.961061) (xy 85.116594 -317.908173) (xy 85.068208 -317.849811)
			(xy 85.0263 -317.786636) (xy 84.991344 -317.719365) (xy 84.963737 -317.64876) (xy 84.943791 -317.575619)
			(xy 84.931732 -317.500774) (xy 84.927697 -317.42507) (xy 43.056094 -317.42507) (xy 43.063974 -317.443209)
			(xy 43.10243 -317.551394) (xy 43.133415 -317.661952) (xy 43.156782 -317.774366) (xy 43.172424 -317.888113)
			(xy 43.180268 -318.002661) (xy 43.180762 -318.06007) (xy 43.180576 -318.093253) (xy 43.177909 -318.159567)
			(xy 43.175428 -318.192658) (xy 43.170272 -318.250942) (xy 43.152948 -318.366671) (xy 43.127616 -318.480914)
			(xy 43.094401 -318.593119) (xy 43.053462 -318.702742) (xy 43.004999 -318.809253) (xy 42.949245 -318.912135)
			(xy 42.886471 -319.010891) (xy 42.816981 -319.105042) (xy 42.741111 -319.194132) (xy 42.659229 -319.277729)
			(xy 42.571732 -319.35543) (xy 42.500813 -319.41008) (xy 43.327577 -319.41008) (xy 43.331612 -319.334376)
			(xy 43.343671 -319.259531) (xy 43.363617 -319.18639) (xy 43.391224 -319.115785) (xy 43.42618 -319.048514)
			(xy 43.468088 -318.985339) (xy 43.516474 -318.926977) (xy 43.57079 -318.874089) (xy 43.630419 -318.827274)
			(xy 43.694687 -318.787062) (xy 43.762864 -318.75391) (xy 43.83418 -318.728192) (xy 43.907825 -318.7102)
			(xy 43.982965 -318.700138) (xy 44.058749 -318.698119) (xy 44.134319 -318.704168) (xy 44.208817 -318.718215)
			(xy 44.2814 -318.740101) (xy 44.351246 -318.769578) (xy 44.417563 -318.806313) (xy 44.479599 -318.849888)
			(xy 44.536652 -318.89981) (xy 44.588076 -318.955514) (xy 44.633287 -319.016369) (xy 44.671774 -319.081684)
			(xy 44.7031 -319.15072) (xy 44.72691 -319.222695) (xy 44.742935 -319.296793) (xy 44.750994 -319.372174)
			(xy 44.751498 -319.41008) (xy 45.867577 -319.41008) (xy 45.871612 -319.334376) (xy 45.883671 -319.259531)
			(xy 45.903617 -319.18639) (xy 45.931224 -319.115785) (xy 45.96618 -319.048514) (xy 46.008088 -318.985339)
			(xy 46.056474 -318.926977) (xy 46.11079 -318.874089) (xy 46.170419 -318.827274) (xy 46.234687 -318.787062)
			(xy 46.302864 -318.75391) (xy 46.37418 -318.728192) (xy 46.447825 -318.7102) (xy 46.522965 -318.700138)
			(xy 46.598749 -318.698119) (xy 46.674319 -318.704168) (xy 46.748817 -318.718215) (xy 46.8214 -318.740101)
			(xy 46.891246 -318.769578) (xy 46.957563 -318.806313) (xy 47.019599 -318.849888) (xy 47.076652 -318.89981)
			(xy 47.128076 -318.955514) (xy 47.173287 -319.016369) (xy 47.211774 -319.081684) (xy 47.2431 -319.15072)
			(xy 47.26691 -319.222695) (xy 47.282935 -319.296793) (xy 47.290994 -319.372174) (xy 47.291498 -319.41008)
			(xy 48.407577 -319.41008) (xy 48.411612 -319.334376) (xy 48.423671 -319.259531) (xy 48.443617 -319.18639)
			(xy 48.471224 -319.115785) (xy 48.50618 -319.048514) (xy 48.548088 -318.985339) (xy 48.596474 -318.926977)
			(xy 48.65079 -318.874089) (xy 48.710419 -318.827274) (xy 48.774687 -318.787062) (xy 48.842864 -318.75391)
			(xy 48.91418 -318.728192) (xy 48.987825 -318.7102) (xy 49.062965 -318.700138) (xy 49.138749 -318.698119)
			(xy 49.214319 -318.704168) (xy 49.288817 -318.718215) (xy 49.3614 -318.740101) (xy 49.431246 -318.769578)
			(xy 49.497563 -318.806313) (xy 49.559599 -318.849888) (xy 49.616652 -318.89981) (xy 49.668076 -318.955514)
			(xy 49.713287 -319.016369) (xy 49.751774 -319.081684) (xy 49.7831 -319.15072) (xy 49.80691 -319.222695)
			(xy 49.822935 -319.296793) (xy 49.830994 -319.372174) (xy 49.831498 -319.41008) (xy 50.947577 -319.41008)
			(xy 50.951612 -319.334376) (xy 50.963671 -319.259531) (xy 50.983617 -319.18639) (xy 51.011224 -319.115785)
			(xy 51.04618 -319.048514) (xy 51.088088 -318.985339) (xy 51.136474 -318.926977) (xy 51.19079 -318.874089)
			(xy 51.250419 -318.827274) (xy 51.314687 -318.787062) (xy 51.382864 -318.75391) (xy 51.45418 -318.728192)
			(xy 51.527825 -318.7102) (xy 51.602965 -318.700138) (xy 51.678749 -318.698119) (xy 51.754319 -318.704168)
			(xy 51.828817 -318.718215) (xy 51.9014 -318.740101) (xy 51.971246 -318.769578) (xy 52.037563 -318.806313)
			(xy 52.099599 -318.849888) (xy 52.156652 -318.89981) (xy 52.208076 -318.955514) (xy 52.253287 -319.016369)
			(xy 52.291774 -319.081684) (xy 52.3231 -319.15072) (xy 52.34691 -319.222695) (xy 52.362935 -319.296793)
			(xy 52.370994 -319.372174) (xy 52.371498 -319.41008) (xy 53.487577 -319.41008) (xy 53.491612 -319.334376)
			(xy 53.503671 -319.259531) (xy 53.523617 -319.18639) (xy 53.551224 -319.115785) (xy 53.58618 -319.048514)
			(xy 53.628088 -318.985339) (xy 53.676474 -318.926977) (xy 53.73079 -318.874089) (xy 53.790419 -318.827274)
			(xy 53.854687 -318.787062) (xy 53.922864 -318.75391) (xy 53.99418 -318.728192) (xy 54.067825 -318.7102)
			(xy 54.142965 -318.700138) (xy 54.218749 -318.698119) (xy 54.294319 -318.704168) (xy 54.368817 -318.718215)
			(xy 54.4414 -318.740101) (xy 54.511246 -318.769578) (xy 54.577563 -318.806313) (xy 54.639599 -318.849888)
			(xy 54.696652 -318.89981) (xy 54.748076 -318.955514) (xy 54.793287 -319.016369) (xy 54.831774 -319.081684)
			(xy 54.8631 -319.15072) (xy 54.88691 -319.222695) (xy 54.902935 -319.296793) (xy 54.910994 -319.372174)
			(xy 54.911498 -319.41008) (xy 56.027577 -319.41008) (xy 56.031612 -319.334376) (xy 56.043671 -319.259531)
			(xy 56.063617 -319.18639) (xy 56.091224 -319.115785) (xy 56.12618 -319.048514) (xy 56.168088 -318.985339)
			(xy 56.216474 -318.926977) (xy 56.27079 -318.874089) (xy 56.330419 -318.827274) (xy 56.394687 -318.787062)
			(xy 56.462864 -318.75391) (xy 56.53418 -318.728192) (xy 56.607825 -318.7102) (xy 56.682965 -318.700138)
			(xy 56.758749 -318.698119) (xy 56.834319 -318.704168) (xy 56.908817 -318.718215) (xy 56.9814 -318.740101)
			(xy 57.051246 -318.769578) (xy 57.117563 -318.806313) (xy 57.179599 -318.849888) (xy 57.236652 -318.89981)
			(xy 57.288076 -318.955514) (xy 57.333287 -319.016369) (xy 57.371774 -319.081684) (xy 57.4031 -319.15072)
			(xy 57.42691 -319.222695) (xy 57.442935 -319.296793) (xy 57.450994 -319.372174) (xy 57.451498 -319.41008)
			(xy 58.567577 -319.41008) (xy 58.571612 -319.334376) (xy 58.583671 -319.259531) (xy 58.603617 -319.18639)
			(xy 58.631224 -319.115785) (xy 58.66618 -319.048514) (xy 58.708088 -318.985339) (xy 58.756474 -318.926977)
			(xy 58.81079 -318.874089) (xy 58.870419 -318.827274) (xy 58.934687 -318.787062) (xy 59.002864 -318.75391)
			(xy 59.07418 -318.728192) (xy 59.147825 -318.7102) (xy 59.222965 -318.700138) (xy 59.298749 -318.698119)
			(xy 59.374319 -318.704168) (xy 59.448817 -318.718215) (xy 59.5214 -318.740101) (xy 59.591246 -318.769578)
			(xy 59.657563 -318.806313) (xy 59.719599 -318.849888) (xy 59.776652 -318.89981) (xy 59.828076 -318.955514)
			(xy 59.873287 -319.016369) (xy 59.911774 -319.081684) (xy 59.9431 -319.15072) (xy 59.96691 -319.222695)
			(xy 59.982935 -319.296793) (xy 59.990994 -319.372174) (xy 59.991498 -319.41008) (xy 61.107577 -319.41008)
			(xy 61.111612 -319.334376) (xy 61.123671 -319.259531) (xy 61.143617 -319.18639) (xy 61.171224 -319.115785)
			(xy 61.20618 -319.048514) (xy 61.248088 -318.985339) (xy 61.296474 -318.926977) (xy 61.35079 -318.874089)
			(xy 61.410419 -318.827274) (xy 61.474687 -318.787062) (xy 61.542864 -318.75391) (xy 61.61418 -318.728192)
			(xy 61.687825 -318.7102) (xy 61.762965 -318.700138) (xy 61.838749 -318.698119) (xy 61.914319 -318.704168)
			(xy 61.988817 -318.718215) (xy 62.0614 -318.740101) (xy 62.131246 -318.769578) (xy 62.197563 -318.806313)
			(xy 62.259599 -318.849888) (xy 62.316652 -318.89981) (xy 62.368076 -318.955514) (xy 62.413287 -319.016369)
			(xy 62.451774 -319.081684) (xy 62.4831 -319.15072) (xy 62.50691 -319.222695) (xy 62.522935 -319.296793)
			(xy 62.530994 -319.372174) (xy 62.531498 -319.41008) (xy 62.530994 -319.447986) (xy 62.522935 -319.523367)
			(xy 62.50691 -319.597465) (xy 62.4831 -319.66944) (xy 62.451774 -319.738476) (xy 62.413287 -319.803791)
			(xy 62.368076 -319.864646) (xy 62.316652 -319.92035) (xy 62.259599 -319.970272) (xy 62.197563 -320.013847)
			(xy 62.131246 -320.050582) (xy 62.0614 -320.080059) (xy 61.988817 -320.101945) (xy 61.914319 -320.115992)
			(xy 61.838749 -320.122041) (xy 61.762965 -320.120022) (xy 61.687825 -320.10996) (xy 61.61418 -320.091968)
			(xy 61.542864 -320.06625) (xy 61.474687 -320.033098) (xy 61.410419 -319.992886) (xy 61.35079 -319.946071)
			(xy 61.296474 -319.893183) (xy 61.248088 -319.834821) (xy 61.20618 -319.771646) (xy 61.171224 -319.704375)
			(xy 61.143617 -319.63377) (xy 61.123671 -319.560629) (xy 61.111612 -319.485784) (xy 61.107577 -319.41008)
			(xy 59.991498 -319.41008) (xy 59.990994 -319.447986) (xy 59.982935 -319.523367) (xy 59.96691 -319.597465)
			(xy 59.9431 -319.66944) (xy 59.911774 -319.738476) (xy 59.873287 -319.803791) (xy 59.828076 -319.864646)
			(xy 59.776652 -319.92035) (xy 59.719599 -319.970272) (xy 59.657563 -320.013847) (xy 59.591246 -320.050582)
			(xy 59.5214 -320.080059) (xy 59.448817 -320.101945) (xy 59.374319 -320.115992) (xy 59.298749 -320.122041)
			(xy 59.222965 -320.120022) (xy 59.147825 -320.10996) (xy 59.07418 -320.091968) (xy 59.002864 -320.06625)
			(xy 58.934687 -320.033098) (xy 58.870419 -319.992886) (xy 58.81079 -319.946071) (xy 58.756474 -319.893183)
			(xy 58.708088 -319.834821) (xy 58.66618 -319.771646) (xy 58.631224 -319.704375) (xy 58.603617 -319.63377)
			(xy 58.583671 -319.560629) (xy 58.571612 -319.485784) (xy 58.567577 -319.41008) (xy 57.451498 -319.41008)
			(xy 57.450994 -319.447986) (xy 57.442935 -319.523367) (xy 57.42691 -319.597465) (xy 57.4031 -319.66944)
			(xy 57.371774 -319.738476) (xy 57.333287 -319.803791) (xy 57.288076 -319.864646) (xy 57.236652 -319.92035)
			(xy 57.179599 -319.970272) (xy 57.117563 -320.013847) (xy 57.051246 -320.050582) (xy 56.9814 -320.080059)
			(xy 56.908817 -320.101945) (xy 56.834319 -320.115992) (xy 56.758749 -320.122041) (xy 56.682965 -320.120022)
			(xy 56.607825 -320.10996) (xy 56.53418 -320.091968) (xy 56.462864 -320.06625) (xy 56.394687 -320.033098)
			(xy 56.330419 -319.992886) (xy 56.27079 -319.946071) (xy 56.216474 -319.893183) (xy 56.168088 -319.834821)
			(xy 56.12618 -319.771646) (xy 56.091224 -319.704375) (xy 56.063617 -319.63377) (xy 56.043671 -319.560629)
			(xy 56.031612 -319.485784) (xy 56.027577 -319.41008) (xy 54.911498 -319.41008) (xy 54.910994 -319.447986)
			(xy 54.902935 -319.523367) (xy 54.88691 -319.597465) (xy 54.8631 -319.66944) (xy 54.831774 -319.738476)
			(xy 54.793287 -319.803791) (xy 54.748076 -319.864646) (xy 54.696652 -319.92035) (xy 54.639599 -319.970272)
			(xy 54.577563 -320.013847) (xy 54.511246 -320.050582) (xy 54.4414 -320.080059) (xy 54.368817 -320.101945)
			(xy 54.294319 -320.115992) (xy 54.218749 -320.122041) (xy 54.142965 -320.120022) (xy 54.067825 -320.10996)
			(xy 53.99418 -320.091968) (xy 53.922864 -320.06625) (xy 53.854687 -320.033098) (xy 53.790419 -319.992886)
			(xy 53.73079 -319.946071) (xy 53.676474 -319.893183) (xy 53.628088 -319.834821) (xy 53.58618 -319.771646)
			(xy 53.551224 -319.704375) (xy 53.523617 -319.63377) (xy 53.503671 -319.560629) (xy 53.491612 -319.485784)
			(xy 53.487577 -319.41008) (xy 52.371498 -319.41008) (xy 52.370994 -319.447986) (xy 52.362935 -319.523367)
			(xy 52.34691 -319.597465) (xy 52.3231 -319.66944) (xy 52.291774 -319.738476) (xy 52.253287 -319.803791)
			(xy 52.208076 -319.864646) (xy 52.156652 -319.92035) (xy 52.099599 -319.970272) (xy 52.037563 -320.013847)
			(xy 51.971246 -320.050582) (xy 51.9014 -320.080059) (xy 51.828817 -320.101945) (xy 51.754319 -320.115992)
			(xy 51.678749 -320.122041) (xy 51.602965 -320.120022) (xy 51.527825 -320.10996) (xy 51.45418 -320.091968)
			(xy 51.382864 -320.06625) (xy 51.314687 -320.033098) (xy 51.250419 -319.992886) (xy 51.19079 -319.946071)
			(xy 51.136474 -319.893183) (xy 51.088088 -319.834821) (xy 51.04618 -319.771646) (xy 51.011224 -319.704375)
			(xy 50.983617 -319.63377) (xy 50.963671 -319.560629) (xy 50.951612 -319.485784) (xy 50.947577 -319.41008)
			(xy 49.831498 -319.41008) (xy 49.830994 -319.447986) (xy 49.822935 -319.523367) (xy 49.80691 -319.597465)
			(xy 49.7831 -319.66944) (xy 49.751774 -319.738476) (xy 49.713287 -319.803791) (xy 49.668076 -319.864646)
			(xy 49.616652 -319.92035) (xy 49.559599 -319.970272) (xy 49.497563 -320.013847) (xy 49.431246 -320.050582)
			(xy 49.3614 -320.080059) (xy 49.288817 -320.101945) (xy 49.214319 -320.115992) (xy 49.138749 -320.122041)
			(xy 49.062965 -320.120022) (xy 48.987825 -320.10996) (xy 48.91418 -320.091968) (xy 48.842864 -320.06625)
			(xy 48.774687 -320.033098) (xy 48.710419 -319.992886) (xy 48.65079 -319.946071) (xy 48.596474 -319.893183)
			(xy 48.548088 -319.834821) (xy 48.50618 -319.771646) (xy 48.471224 -319.704375) (xy 48.443617 -319.63377)
			(xy 48.423671 -319.560629) (xy 48.411612 -319.485784) (xy 48.407577 -319.41008) (xy 47.291498 -319.41008)
			(xy 47.290994 -319.447986) (xy 47.282935 -319.523367) (xy 47.26691 -319.597465) (xy 47.2431 -319.66944)
			(xy 47.211774 -319.738476) (xy 47.173287 -319.803791) (xy 47.128076 -319.864646) (xy 47.076652 -319.92035)
			(xy 47.019599 -319.970272) (xy 46.957563 -320.013847) (xy 46.891246 -320.050582) (xy 46.8214 -320.080059)
			(xy 46.748817 -320.101945) (xy 46.674319 -320.115992) (xy 46.598749 -320.122041) (xy 46.522965 -320.120022)
			(xy 46.447825 -320.10996) (xy 46.37418 -320.091968) (xy 46.302864 -320.06625) (xy 46.234687 -320.033098)
			(xy 46.170419 -319.992886) (xy 46.11079 -319.946071) (xy 46.056474 -319.893183) (xy 46.008088 -319.834821)
			(xy 45.96618 -319.771646) (xy 45.931224 -319.704375) (xy 45.903617 -319.63377) (xy 45.883671 -319.560629)
			(xy 45.871612 -319.485784) (xy 45.867577 -319.41008) (xy 44.751498 -319.41008) (xy 44.750994 -319.447986)
			(xy 44.742935 -319.523367) (xy 44.72691 -319.597465) (xy 44.7031 -319.66944) (xy 44.671774 -319.738476)
			(xy 44.633287 -319.803791) (xy 44.588076 -319.864646) (xy 44.536652 -319.92035) (xy 44.479599 -319.970272)
			(xy 44.417563 -320.013847) (xy 44.351246 -320.050582) (xy 44.2814 -320.080059) (xy 44.208817 -320.101945)
			(xy 44.134319 -320.115992) (xy 44.058749 -320.122041) (xy 43.982965 -320.120022) (xy 43.907825 -320.10996)
			(xy 43.83418 -320.091968) (xy 43.762864 -320.06625) (xy 43.694687 -320.033098) (xy 43.630419 -319.992886)
			(xy 43.57079 -319.946071) (xy 43.516474 -319.893183) (xy 43.468088 -319.834821) (xy 43.42618 -319.771646)
			(xy 43.391224 -319.704375) (xy 43.363617 -319.63377) (xy 43.343671 -319.560629) (xy 43.331612 -319.485784)
			(xy 43.327577 -319.41008) (xy 42.500813 -319.41008) (xy 42.479042 -319.426857) (xy 42.381609 -319.491665)
			(xy 42.279905 -319.54954) (xy 42.174422 -319.600202) (xy 42.065671 -319.643404) (xy 41.954179 -319.678939)
			(xy 41.840485 -319.706634) (xy 41.725141 -319.726354) (xy 41.608704 -319.738005) (xy 41.491739 -319.74153)
			(xy 41.374812 -319.736912) (xy 41.258489 -319.724173) (xy 41.143334 -319.703375) (xy 41.029905 -319.674618)
			(xy 40.91875 -319.638042) (xy 40.810407 -319.593825) (xy 40.705403 -319.542179) (xy 40.604244 -319.483356)
			(xy 40.507421 -319.41764) (xy 40.415403 -319.345349) (xy 40.328636 -319.266834) (xy 40.247539 -319.182474)
			(xy 40.172506 -319.092679) (xy 40.103899 -318.997883) (xy 40.042051 -318.898544) (xy 39.987262 -318.795145)
			(xy 39.939796 -318.688186) (xy 39.899884 -318.578185) (xy 39.86772 -318.465674) (xy 39.843457 -318.351199)
			(xy 39.827215 -318.235313) (xy 39.819072 -318.118579) (xy 39.818564 -318.06007) (xy 36.479871 -318.06007)
			(xy 36.479486 -318.09336) (xy 36.471468 -318.179889) (xy 36.4555 -318.265309) (xy 36.431719 -318.348891)
			(xy 36.400327 -318.429923) (xy 36.361593 -318.507712) (xy 36.315846 -318.581596) (xy 36.263477 -318.650943)
			(xy 36.204933 -318.715163) (xy 36.140713 -318.773707) (xy 36.071366 -318.826076) (xy 35.997482 -318.871823)
			(xy 35.919693 -318.910557) (xy 35.838661 -318.941949) (xy 35.755079 -318.96573) (xy 35.669659 -318.981698)
			(xy 35.58313 -318.989716) (xy 35.49623 -318.989716) (xy 35.409701 -318.981698) (xy 35.324281 -318.96573)
			(xy 35.240699 -318.941949) (xy 35.159667 -318.910557) (xy 35.081878 -318.871823) (xy 35.007994 -318.826076)
			(xy 34.938647 -318.773707) (xy 34.874427 -318.715163) (xy 34.815883 -318.650943) (xy 34.763514 -318.581596)
			(xy 34.717767 -318.507712) (xy 34.679033 -318.429923) (xy 34.647641 -318.348891) (xy 34.62386 -318.265309)
			(xy 34.607892 -318.179889) (xy 34.599874 -318.09336) (xy 31.399486 -318.09336) (xy 31.391468 -318.179889)
			(xy 31.3755 -318.265309) (xy 31.351719 -318.348891) (xy 31.320327 -318.429923) (xy 31.281593 -318.507712)
			(xy 31.235846 -318.581596) (xy 31.183477 -318.650943) (xy 31.124933 -318.715163) (xy 31.060713 -318.773707)
			(xy 30.991366 -318.826076) (xy 30.917482 -318.871823) (xy 30.839693 -318.910557) (xy 30.758661 -318.941949)
			(xy 30.675079 -318.96573) (xy 30.589659 -318.981698) (xy 30.50313 -318.989716) (xy 30.41623 -318.989716)
			(xy 30.329701 -318.981698) (xy 30.244281 -318.96573) (xy 30.160699 -318.941949) (xy 30.079667 -318.910557)
			(xy 30.001878 -318.871823) (xy 29.927994 -318.826076) (xy 29.858647 -318.773707) (xy 29.794427 -318.715163)
			(xy 29.735883 -318.650943) (xy 29.683514 -318.581596) (xy 29.637767 -318.507712) (xy 29.599033 -318.429923)
			(xy 29.567641 -318.348891) (xy 29.54386 -318.265309) (xy 29.527892 -318.179889) (xy 29.519874 -318.09336)
			(xy 28.912312 -318.09336) (xy 28.912312 -330.012971) (xy 47.903374 -330.012971) (xy 47.903374 -329.931861)
			(xy 47.911324 -329.851142) (xy 47.927147 -329.771591) (xy 47.950692 -329.693975) (xy 47.981731 -329.619039)
			(xy 48.019966 -329.547507) (xy 48.065028 -329.480067) (xy 48.116483 -329.417368) (xy 48.173836 -329.360015)
			(xy 48.236535 -329.30856) (xy 48.303975 -329.263498) (xy 48.375507 -329.225263) (xy 48.450443 -329.194224)
			(xy 48.528059 -329.170679) (xy 48.60761 -329.154856) (xy 48.688329 -329.146906) (xy 48.769439 -329.146906)
			(xy 48.850158 -329.154856) (xy 48.929709 -329.170679) (xy 49.007325 -329.194224) (xy 49.082261 -329.225263)
			(xy 49.153793 -329.263498) (xy 49.221233 -329.30856) (xy 49.283932 -329.360015) (xy 49.341285 -329.417368)
			(xy 49.39274 -329.480067) (xy 49.437802 -329.547507) (xy 49.476037 -329.619039) (xy 49.507076 -329.693975)
			(xy 49.530621 -329.771591) (xy 49.546444 -329.851142) (xy 49.554394 -329.931861) (xy 49.554892 -329.972416)
			(xy 49.554394 -330.012971) (xy 51.403494 -330.012971) (xy 51.403494 -329.931861) (xy 51.411444 -329.851142)
			(xy 51.427267 -329.771591) (xy 51.450812 -329.693975) (xy 51.481851 -329.619039) (xy 51.520086 -329.547507)
			(xy 51.565148 -329.480067) (xy 51.616603 -329.417368) (xy 51.673956 -329.360015) (xy 51.736655 -329.30856)
			(xy 51.804095 -329.263498) (xy 51.875627 -329.225263) (xy 51.950563 -329.194224) (xy 52.028179 -329.170679)
			(xy 52.10773 -329.154856) (xy 52.188449 -329.146906) (xy 52.269559 -329.146906) (xy 52.350278 -329.154856)
			(xy 52.429829 -329.170679) (xy 52.507445 -329.194224) (xy 52.582381 -329.225263) (xy 52.653913 -329.263498)
			(xy 52.721353 -329.30856) (xy 52.784052 -329.360015) (xy 52.841405 -329.417368) (xy 52.89286 -329.480067)
			(xy 52.937922 -329.547507) (xy 52.976157 -329.619039) (xy 53.007196 -329.693975) (xy 53.030741 -329.771591)
			(xy 53.046564 -329.851142) (xy 53.054514 -329.931861) (xy 53.055012 -329.972416) (xy 53.054514 -330.012971)
			(xy 53.046564 -330.09369) (xy 53.030741 -330.173241) (xy 53.007196 -330.250857) (xy 52.976157 -330.325793)
			(xy 52.937922 -330.397325) (xy 52.89286 -330.464765) (xy 52.841405 -330.527464) (xy 52.784052 -330.584817)
			(xy 52.721353 -330.636272) (xy 52.653913 -330.681334) (xy 52.582381 -330.719569) (xy 52.507445 -330.750608)
			(xy 52.429829 -330.774153) (xy 52.350278 -330.789976) (xy 52.269559 -330.797926) (xy 52.188449 -330.797926)
			(xy 52.10773 -330.789976) (xy 52.028179 -330.774153) (xy 51.950563 -330.750608) (xy 51.875627 -330.719569)
			(xy 51.804095 -330.681334) (xy 51.736655 -330.636272) (xy 51.673956 -330.584817) (xy 51.616603 -330.527464)
			(xy 51.565148 -330.464765) (xy 51.520086 -330.397325) (xy 51.481851 -330.325793) (xy 51.450812 -330.250857)
			(xy 51.427267 -330.173241) (xy 51.411444 -330.09369) (xy 51.403494 -330.012971) (xy 49.554394 -330.012971)
			(xy 49.546444 -330.09369) (xy 49.530621 -330.173241) (xy 49.507076 -330.250857) (xy 49.476037 -330.325793)
			(xy 49.437802 -330.397325) (xy 49.39274 -330.464765) (xy 49.341285 -330.527464) (xy 49.283932 -330.584817)
			(xy 49.221233 -330.636272) (xy 49.153793 -330.681334) (xy 49.082261 -330.719569) (xy 49.007325 -330.750608)
			(xy 48.929709 -330.774153) (xy 48.850158 -330.789976) (xy 48.769439 -330.797926) (xy 48.688329 -330.797926)
			(xy 48.60761 -330.789976) (xy 48.528059 -330.774153) (xy 48.450443 -330.750608) (xy 48.375507 -330.719569)
			(xy 48.303975 -330.681334) (xy 48.236535 -330.636272) (xy 48.173836 -330.584817) (xy 48.116483 -330.527464)
			(xy 48.065028 -330.464765) (xy 48.019966 -330.397325) (xy 47.981731 -330.325793) (xy 47.950692 -330.250857)
			(xy 47.927147 -330.173241) (xy 47.911324 -330.09369) (xy 47.903374 -330.012971) (xy 28.912312 -330.012971)
			(xy 28.912312 -331.631036) (xy 73.077322 -331.631036) (xy 73.081393 -331.575414) (xy 73.093519 -331.520977)
			(xy 73.113442 -331.468886) (xy 73.140738 -331.420251) (xy 73.174824 -331.376108) (xy 73.214973 -331.337399)
			(xy 73.260331 -331.304948) (xy 73.309931 -331.279447) (xy 73.362715 -331.26144) (xy 73.417558 -331.25131)
			(xy 73.473292 -331.249273) (xy 73.528729 -331.255373) (xy 73.582686 -331.269479) (xy 73.634015 -331.291291)
			(xy 73.681621 -331.320345) (xy 73.724489 -331.35602) (xy 73.761706 -331.397557) (xy 73.792479 -331.44407)
			(xy 73.816151 -331.494567) (xy 73.832219 -331.547974) (xy 73.840339 -331.60315) (xy 73.840848 -331.631036)
			(xy 73.840339 -331.658922) (xy 73.832219 -331.714098) (xy 73.816151 -331.767505) (xy 73.792479 -331.818002)
			(xy 73.761706 -331.864515) (xy 73.724489 -331.906052) (xy 73.681621 -331.941727) (xy 73.634015 -331.970781)
			(xy 73.582686 -331.992593) (xy 73.528729 -332.006699) (xy 73.473292 -332.012799) (xy 73.417558 -332.010762)
			(xy 73.362715 -332.000632) (xy 73.309931 -331.982625) (xy 73.260331 -331.957124) (xy 73.214973 -331.924673)
			(xy 73.174824 -331.885964) (xy 73.140738 -331.841821) (xy 73.113442 -331.793186) (xy 73.093519 -331.741095)
			(xy 73.081393 -331.686658) (xy 73.077322 -331.631036) (xy 28.912312 -331.631036) (xy 28.912312 -332.475586)
			(xy 71.705214 -332.475586) (xy 71.709285 -332.419964) (xy 71.721411 -332.365527) (xy 71.741334 -332.313436)
			(xy 71.76863 -332.264801) (xy 71.802716 -332.220658) (xy 71.842865 -332.181949) (xy 71.888223 -332.149498)
			(xy 71.937823 -332.123997) (xy 71.990607 -332.10599) (xy 72.04545 -332.09586) (xy 72.101184 -332.093823)
			(xy 72.156621 -332.099923) (xy 72.210578 -332.114029) (xy 72.261907 -332.135841) (xy 72.309513 -332.164895)
			(xy 72.352381 -332.20057) (xy 72.389598 -332.242107) (xy 72.420371 -332.28862) (xy 72.444043 -332.339117)
			(xy 72.460111 -332.392524) (xy 72.468231 -332.4477) (xy 72.46874 -332.475586) (xy 72.468231 -332.503472)
			(xy 72.460111 -332.558648) (xy 72.444043 -332.612055) (xy 72.420371 -332.662552) (xy 72.389598 -332.709065)
			(xy 72.352381 -332.750602) (xy 72.309513 -332.786277) (xy 72.261907 -332.815331) (xy 72.210578 -332.837143)
			(xy 72.156621 -332.851249) (xy 72.101184 -332.857349) (xy 72.04545 -332.855312) (xy 71.990607 -332.845182)
			(xy 71.937823 -332.827175) (xy 71.888223 -332.801674) (xy 71.842865 -332.769223) (xy 71.802716 -332.730514)
			(xy 71.76863 -332.686371) (xy 71.741334 -332.637736) (xy 71.721411 -332.585645) (xy 71.709285 -332.531208)
			(xy 71.705214 -332.475586) (xy 28.912312 -332.475586) (xy 28.912312 -348.234) (xy 30.343348 -349.665036)
			(xy 43.049444 -349.665036) (xy 43.055032 -349.659448) (xy 44.422568 -349.659448) (xy 45.199046 -348.88297)
			(xy 45.342302 -348.739968) (xy 46.480222 -347.602048) (xy 59.343036 -347.602048) (xy 59.362546 -347.598827)
			(xy 59.398372 -347.582142) (xy 59.413394 -347.569282) (xy 74.604118 -332.378558) (xy 74.619115 -332.362938)
			(xy 74.644095 -332.327572) (xy 74.662722 -332.288485) (xy 74.674455 -332.246806) (xy 74.678957 -332.203742)
			(xy 74.676096 -332.160538) (xy 74.665956 -332.118443) (xy 74.64883 -332.078675) (xy 74.625212 -332.042385)
			(xy 74.595787 -332.010621) (xy 74.561405 -331.984302) (xy 74.542396 -331.973936) (xy 74.517508 -331.961245)
			(xy 74.471415 -331.929681) (xy 74.430416 -331.891735) (xy 74.395388 -331.848216) (xy 74.367079 -331.800056)
			(xy 74.346093 -331.748283) (xy 74.33288 -331.694003) (xy 74.327722 -331.638377) (xy 74.330729 -331.582594)
			(xy 74.341837 -331.527845) (xy 74.360808 -331.4753) (xy 74.387237 -331.426083) (xy 74.42056 -331.381244)
			(xy 74.460063 -331.341743) (xy 74.504904 -331.308424) (xy 74.554123 -331.281998) (xy 74.606669 -331.26303)
			(xy 74.661418 -331.251926) (xy 74.717202 -331.248923) (xy 74.772828 -331.254084) (xy 74.827106 -331.267301)
			(xy 74.878878 -331.28829) (xy 74.927037 -331.316602) (xy 74.970553 -331.351633) (xy 75.008497 -331.392635)
			(xy 75.040058 -331.43873) (xy 75.052682 -331.46365) (xy 75.06311 -331.482632) (xy 75.089405 -331.517043)
			(xy 75.121155 -331.546495) (xy 75.15744 -331.570137) (xy 75.197208 -331.587283) (xy 75.239308 -331.597437)
			(xy 75.28252 -331.600304) (xy 75.325592 -331.595802) (xy 75.367277 -331.584061) (xy 75.406368 -331.565421)
			(xy 75.441731 -331.540422) (xy 75.457304 -331.525372) (xy 81.406746 -325.57593) (xy 81.415636 -325.544434)
			(xy 81.423655 -325.518235) (xy 81.446163 -325.468282) (xy 81.47559 -325.422066) (xy 81.511328 -325.380537)
			(xy 81.552643 -325.344552) (xy 81.575402 -325.329296) (xy 81.586832 -325.32193) (xy 85.269832 -321.63893)
			(xy 85.269832 -320.640456) (xy 85.269454 -320.625572) (xy 85.262594 -320.596607) (xy 85.249191 -320.570029)
			(xy 85.229978 -320.547294) (xy 85.21827 -320.538094) (xy 85.202979 -320.526728) (xy 85.173498 -320.502586)
			(xy 85.159342 -320.489834) (xy 85.148968 -320.480345) (xy 85.128895 -320.460655) (xy 85.11921 -320.450464)
			(xy 85.101938 -320.43116) (xy 85.07563 -320.399926) (xy 85.029562 -320.332493) (xy 84.9915 -320.260238)
			(xy 84.976208 -320.222372) (xy 84.962938 -320.186793) (xy 84.943181 -320.113467) (xy 84.931347 -320.038454)
			(xy 84.927573 -319.962607) (xy 84.9319 -319.886789) (xy 84.9376 -319.849246) (xy 84.944134 -319.812614)
			(xy 84.96384 -319.740855) (xy 84.990925 -319.671545) (xy 85.025094 -319.605438) (xy 85.065973 -319.543258)
			(xy 85.113117 -319.485681) (xy 85.16601 -319.433338) (xy 85.224076 -319.386798) (xy 85.28668 -319.34657)
			(xy 85.35314 -319.313094) (xy 85.422729 -319.286734) (xy 85.49469 -319.267779) (xy 85.568235 -319.256434)
			(xy 85.642562 -319.252825) (xy 85.71686 -319.25699) (xy 85.790318 -319.268883) (xy 85.862134 -319.288376)
			(xy 85.931525 -319.315256) (xy 85.997733 -319.349228) (xy 86.060035 -319.389922) (xy 86.117751 -319.436894)
			(xy 86.144354 -319.462912) (xy 86.160753 -319.478679) (xy 86.198064 -319.504696) (xy 86.239413 -319.523652)
			(xy 86.283478 -319.534938) (xy 86.328848 -319.538195) (xy 86.374072 -319.533318) (xy 86.417705 -319.520463)
			(xy 86.45835 -319.500041) (xy 86.47684 -319.486788) (xy 86.591648 -319.37198) (xy 86.591648 -319.369948)
			(xy 86.496144 -319.274444) (xy 86.48827 -319.268602) (xy 86.45813 -319.245826) (xy 86.402343 -319.194882)
			(xy 86.352266 -319.138315) (xy 86.308461 -319.076763) (xy 86.271422 -319.010918) (xy 86.241564 -318.94152)
			(xy 86.219225 -318.86935) (xy 86.204654 -318.79522) (xy 86.198017 -318.719964) (xy 86.199388 -318.644429)
			(xy 86.20875 -318.569463) (xy 86.226 -318.49591) (xy 86.250943 -318.424598) (xy 86.283298 -318.356329)
			(xy 86.322702 -318.291871) (xy 86.368711 -318.231948) (xy 86.420807 -318.177235) (xy 86.478405 -318.128348)
			(xy 86.540857 -318.085836) (xy 86.60746 -318.050177) (xy 86.677465 -318.021773) (xy 86.750085 -318.000942)
			(xy 86.824503 -317.98792) (xy 86.862158 -317.984886) (xy 86.90991 -317.981584) (xy 87.034624 -317.856362)
			(xy 87.034624 -316.993778) (xy 86.908132 -316.866778) (xy 86.869945 -316.866176) (xy 86.794029 -316.857799)
			(xy 86.719446 -316.841342) (xy 86.647054 -316.816993) (xy 86.577686 -316.785034) (xy 86.512138 -316.745831)
			(xy 86.451164 -316.699835) (xy 86.395466 -316.647575) (xy 86.345683 -316.589652) (xy 86.302389 -316.526731)
			(xy 86.26608 -316.459536) (xy 86.237175 -316.388841) (xy 86.216005 -316.315456) (xy 86.202814 -316.240227)
			(xy 86.197754 -316.164018) (xy 86.200883 -316.087705) (xy 86.212165 -316.012166) (xy 86.23147 -315.93827)
			(xy 86.258576 -315.866865) (xy 86.293172 -315.798772) (xy 86.313518 -315.76645) (xy 86.334857 -315.734626)
			(xy 86.383342 -315.67529) (xy 86.437924 -315.62151) (xy 86.49797 -315.573908) (xy 86.562786 -315.533037)
			(xy 86.596982 -315.515752) (xy 86.632145 -315.499122) (xy 86.705326 -315.472748) (xy 86.780946 -315.45451)
			(xy 86.858104 -315.444627) (xy 86.93588 -315.443215) (xy 87.013345 -315.450292) (xy 87.089578 -315.465774)
			(xy 87.163667 -315.489475) (xy 87.234731 -315.521113) (xy 87.301921 -315.560311) (xy 87.364437 -315.606601)
			(xy 87.421533 -315.659432) (xy 87.472528 -315.718173) (xy 87.516814 -315.782125) (xy 87.553863 -315.850523)
			(xy 87.56904 -315.886338) (xy 87.578086 -315.907224) (xy 87.602473 -315.945648) (xy 87.633314 -315.979115)
			(xy 87.669622 -316.006554) (xy 87.710237 -316.027087) (xy 87.753859 -316.040059) (xy 87.799095 -316.045054)
			(xy 87.844496 -316.041913) (xy 87.888613 -316.030736) (xy 87.930033 -316.011881) (xy 87.967433 -315.98595)
			(xy 87.983822 -315.970158) (xy 87.998808 -315.955426) (xy 88.116918 -315.837316) (xy 88.738964 -315.837316)
			(xy 88.755062 -315.836849) (xy 88.786233 -315.828797) (xy 88.814396 -315.813198) (xy 88.837757 -315.791044)
			(xy 88.84666 -315.777626) (xy 88.866969 -315.746082) (xy 88.913239 -315.68702) (xy 88.965465 -315.633154)
			(xy 89.02307 -315.585083) (xy 89.085412 -315.543338) (xy 89.1518 -315.508385) (xy 89.221497 -315.48061)
			(xy 89.29373 -315.460323) (xy 89.367696 -315.447748) (xy 89.442575 -315.443025) (xy 89.517535 -315.446207)
			(xy 89.591744 -315.457257) (xy 89.664379 -315.476054) (xy 89.734633 -315.502389) (xy 89.801726 -315.535969)
			(xy 89.864914 -315.576422) (xy 89.923495 -315.623299) (xy 89.976818 -315.676079) (xy 90.024293 -315.734176)
			(xy 90.065391 -315.796946) (xy 90.099658 -315.863691) (xy 90.126711 -315.933672) (xy 90.146252 -316.00611)
			(xy 90.158063 -316.080202) (xy 90.162009 -316.15507) (xy 91.277697 -316.15507) (xy 91.281732 -316.079366)
			(xy 91.293791 -316.004521) (xy 91.313737 -315.93138) (xy 91.341344 -315.860775) (xy 91.3763 -315.793504)
			(xy 91.418208 -315.730329) (xy 91.466594 -315.671967) (xy 91.52091 -315.619079) (xy 91.580539 -315.572264)
			(xy 91.644807 -315.532052) (xy 91.712984 -315.4989) (xy 91.7843 -315.473182) (xy 91.857945 -315.45519)
			(xy 91.933085 -315.445128) (xy 92.008869 -315.443109) (xy 92.084439 -315.449158) (xy 92.158937 -315.463205)
			(xy 92.23152 -315.485091) (xy 92.301366 -315.514568) (xy 92.367683 -315.551303) (xy 92.429719 -315.594878)
			(xy 92.486772 -315.6448) (xy 92.538196 -315.700504) (xy 92.583407 -315.761359) (xy 92.621894 -315.826674)
			(xy 92.65322 -315.89571) (xy 92.67703 -315.967685) (xy 92.693055 -316.041783) (xy 92.701114 -316.117164)
			(xy 92.701618 -316.15507) (xy 92.701114 -316.192976) (xy 92.693055 -316.268357) (xy 92.67703 -316.342455)
			(xy 92.65322 -316.41443) (xy 92.621894 -316.483466) (xy 92.583407 -316.548781) (xy 92.538196 -316.609636)
			(xy 92.486772 -316.66534) (xy 92.429719 -316.715262) (xy 92.367683 -316.758837) (xy 92.301366 -316.795572)
			(xy 92.23152 -316.825049) (xy 92.158937 -316.846935) (xy 92.084439 -316.860982) (xy 92.008869 -316.867031)
			(xy 91.933085 -316.865012) (xy 91.857945 -316.85495) (xy 91.7843 -316.836958) (xy 91.712984 -316.81124)
			(xy 91.644807 -316.778088) (xy 91.580539 -316.737876) (xy 91.52091 -316.691061) (xy 91.466594 -316.638173)
			(xy 91.418208 -316.579811) (xy 91.3763 -316.516636) (xy 91.341344 -316.449365) (xy 91.313737 -316.37876)
			(xy 91.293791 -316.305619) (xy 91.281732 -316.230774) (xy 91.277697 -316.15507) (xy 90.162009 -316.15507)
			(xy 90.162012 -316.155125) (xy 90.158057 -316.230049) (xy 90.146241 -316.30414) (xy 90.126695 -316.376577)
			(xy 90.099637 -316.446555) (xy 90.065366 -316.513298) (xy 90.024263 -316.576065) (xy 89.976784 -316.634159)
			(xy 89.923457 -316.686935) (xy 89.864872 -316.733807) (xy 89.801682 -316.774256) (xy 89.734586 -316.807831)
			(xy 89.66433 -316.834161) (xy 89.591694 -316.852953) (xy 89.517484 -316.863998) (xy 89.442524 -316.867174)
			(xy 89.367646 -316.862446) (xy 89.29368 -316.849866) (xy 89.221449 -316.829573) (xy 89.151754 -316.801794)
			(xy 89.085368 -316.766836) (xy 89.023029 -316.725087) (xy 88.965428 -316.677011) (xy 88.913205 -316.623142)
			(xy 88.86694 -316.564077) (xy 88.84666 -316.532514) (xy 88.83773 -316.519116) (xy 88.814379 -316.496962)
			(xy 88.786223 -316.481362) (xy 88.755058 -316.47331) (xy 88.738964 -316.472824) (xy 88.380316 -316.472824)
			(xy 88.32342 -316.52972) (xy 88.31198 -316.541837) (xy 88.295303 -316.570675) (xy 88.28667 -316.60285)
			(xy 88.286671 -316.636163) (xy 88.295308 -316.668337) (xy 88.311988 -316.697173) (xy 88.32342 -316.709298)
			(xy 88.346534 -316.732412) (xy 88.37803 -316.741556) (xy 88.413635 -316.752382) (xy 88.482561 -316.780451)
			(xy 88.548181 -316.815561) (xy 88.609778 -316.857328) (xy 88.666679 -316.905295) (xy 88.718263 -316.95894)
			(xy 88.763966 -317.017676) (xy 88.80329 -317.080861) (xy 88.835804 -317.147805) (xy 88.861153 -317.217777)
			(xy 88.87906 -317.290012) (xy 88.889331 -317.363722) (xy 88.89141 -317.42507) (xy 90.007697 -317.42507)
			(xy 90.011732 -317.349366) (xy 90.023791 -317.274521) (xy 90.043737 -317.20138) (xy 90.071344 -317.130775)
			(xy 90.1063 -317.063504) (xy 90.148208 -317.000329) (xy 90.196594 -316.941967) (xy 90.25091 -316.889079)
			(xy 90.310539 -316.842264) (xy 90.374807 -316.802052) (xy 90.442984 -316.7689) (xy 90.5143 -316.743182)
			(xy 90.587945 -316.72519) (xy 90.663085 -316.715128) (xy 90.738869 -316.713109) (xy 90.814439 -316.719158)
			(xy 90.888937 -316.733205) (xy 90.96152 -316.755091) (xy 91.031366 -316.784568) (xy 91.097683 -316.821303)
			(xy 91.159719 -316.864878) (xy 91.216772 -316.9148) (xy 91.268196 -316.970504) (xy 91.313407 -317.031359)
			(xy 91.351894 -317.096674) (xy 91.38322 -317.16571) (xy 91.40703 -317.237685) (xy 91.423055 -317.311783)
			(xy 91.431114 -317.387164) (xy 91.431618 -317.42507) (xy 91.431114 -317.462976) (xy 91.423055 -317.538357)
			(xy 91.40703 -317.612455) (xy 91.38322 -317.68443) (xy 91.351894 -317.753466) (xy 91.313407 -317.818781)
			(xy 91.268196 -317.879636) (xy 91.216772 -317.93534) (xy 91.159719 -317.985262) (xy 91.097683 -318.028837)
			(xy 91.031366 -318.065572) (xy 90.96152 -318.095049) (xy 90.888937 -318.116935) (xy 90.814439 -318.130982)
			(xy 90.738869 -318.137031) (xy 90.663085 -318.135012) (xy 90.587945 -318.12495) (xy 90.5143 -318.106958)
			(xy 90.442984 -318.08124) (xy 90.374807 -318.048088) (xy 90.310539 -318.007876) (xy 90.25091 -317.961061)
			(xy 90.196594 -317.908173) (xy 90.148208 -317.849811) (xy 90.1063 -317.786636) (xy 90.071344 -317.719365)
			(xy 90.043737 -317.64876) (xy 90.023791 -317.575619) (xy 90.011732 -317.500774) (xy 90.007697 -317.42507)
			(xy 88.89141 -317.42507) (xy 88.891852 -317.438102) (xy 88.886596 -317.512338) (xy 88.87362 -317.585621)
			(xy 88.853067 -317.657148) (xy 88.825161 -317.72614) (xy 88.790206 -317.791843) (xy 88.748584 -317.853538)
			(xy 88.700751 -317.910552) (xy 88.647228 -317.962263) (xy 88.5886 -318.008105) (xy 88.557354 -318.02832)
			(xy 88.54396 -318.037253) (xy 88.521812 -318.060607) (xy 88.506216 -318.088761) (xy 88.498163 -318.119923)
			(xy 88.497664 -318.136016) (xy 88.497664 -318.541908) (xy 88.498208 -318.558557) (xy 88.506827 -318.590721)
			(xy 88.523474 -318.61956) (xy 88.547018 -318.643108) (xy 88.575853 -318.659763) (xy 88.608015 -318.668388)
			(xy 88.624664 -318.668908) (xy 88.639372 -318.668483) (xy 88.668005 -318.661734) (xy 88.694332 -318.64861)
			(xy 88.716955 -318.629807) (xy 88.734673 -318.606324) (xy 88.746544 -318.579408) (xy 88.749632 -318.565022)
			(xy 88.757115 -318.52741) (xy 88.779103 -318.453938) (xy 88.808864 -318.383256) (xy 88.846051 -318.316184)
			(xy 88.890233 -318.253498) (xy 88.9409 -318.195926) (xy 88.997462 -318.144135) (xy 89.059265 -318.098726)
			(xy 89.125591 -318.060224) (xy 89.195673 -318.029077) (xy 89.268697 -318.005644) (xy 89.343817 -317.990199)
			(xy 89.420162 -317.98292) (xy 89.496848 -317.983891) (xy 89.572984 -317.993101) (xy 89.647689 -318.010443)
			(xy 89.720097 -318.035717) (xy 89.789367 -318.068629) (xy 89.854698 -318.108797) (xy 89.885266 -318.131952)
			(xy 89.91301 -318.153952) (xy 89.964454 -318.202609) (xy 90.010811 -318.256136) (xy 90.051621 -318.314003)
			(xy 90.086482 -318.375637) (xy 90.115048 -318.440429) (xy 90.137036 -318.507739) (xy 90.15223 -318.576899)
			(xy 90.156792 -318.612012) (xy 90.160381 -318.646042) (xy 90.161399 -318.69507) (xy 91.277697 -318.69507)
			(xy 91.281732 -318.619366) (xy 91.293791 -318.544521) (xy 91.313737 -318.47138) (xy 91.341344 -318.400775)
			(xy 91.3763 -318.333504) (xy 91.418208 -318.270329) (xy 91.466594 -318.211967) (xy 91.52091 -318.159079)
			(xy 91.580539 -318.112264) (xy 91.644807 -318.072052) (xy 91.712984 -318.0389) (xy 91.7843 -318.013182)
			(xy 91.857945 -317.99519) (xy 91.933085 -317.985128) (xy 92.008869 -317.983109) (xy 92.084439 -317.989158)
			(xy 92.158937 -318.003205) (xy 92.23152 -318.025091) (xy 92.301366 -318.054568) (xy 92.367683 -318.091303)
			(xy 92.429719 -318.134878) (xy 92.486772 -318.1848) (xy 92.538196 -318.240504) (xy 92.583407 -318.301359)
			(xy 92.621894 -318.366674) (xy 92.65322 -318.43571) (xy 92.67703 -318.507685) (xy 92.693055 -318.581783)
			(xy 92.701114 -318.657164) (xy 92.701618 -318.69507) (xy 92.701114 -318.732976) (xy 92.693055 -318.808357)
			(xy 92.67703 -318.882455) (xy 92.65322 -318.95443) (xy 92.621894 -319.023466) (xy 92.583407 -319.088781)
			(xy 92.538196 -319.149636) (xy 92.486772 -319.20534) (xy 92.429719 -319.255262) (xy 92.367683 -319.298837)
			(xy 92.301366 -319.335572) (xy 92.23152 -319.365049) (xy 92.158937 -319.386935) (xy 92.084439 -319.400982)
			(xy 92.008869 -319.407031) (xy 91.933085 -319.405012) (xy 91.857945 -319.39495) (xy 91.7843 -319.376958)
			(xy 91.712984 -319.35124) (xy 91.644807 -319.318088) (xy 91.580539 -319.277876) (xy 91.52091 -319.231061)
			(xy 91.466594 -319.178173) (xy 91.418208 -319.119811) (xy 91.3763 -319.056636) (xy 91.341344 -318.989365)
			(xy 91.313737 -318.91876) (xy 91.293791 -318.845619) (xy 91.281732 -318.770774) (xy 91.277697 -318.69507)
			(xy 90.161399 -318.69507) (xy 90.161802 -318.71446) (xy 90.156641 -318.782698) (xy 90.151204 -318.816482)
			(xy 90.147902 -318.83477) (xy 90.139673 -318.873221) (xy 90.115837 -318.948157) (xy 90.083882 -319.020007)
			(xy 90.044199 -319.087896) (xy 90.021156 -319.119758) (xy 90.001046 -319.146169) (xy 89.956652 -319.195527)
			(xy 89.93251 -319.21831) (xy 89.907892 -319.240421) (xy 89.855229 -319.28049) (xy 89.827354 -319.29832)
			(xy 89.813935 -319.307273) (xy 89.791756 -319.330684) (xy 89.776157 -319.358909) (xy 89.768136 -319.390145)
			(xy 89.767664 -319.40627) (xy 89.767664 -319.813686) (xy 89.768205 -319.830337) (xy 89.77682 -319.862506)
			(xy 89.793467 -319.89135) (xy 89.81701 -319.914903) (xy 89.845847 -319.931561) (xy 89.878013 -319.940188)
			(xy 89.894664 -319.940686) (xy 89.940638 -319.940686) (xy 90.010996 -319.882266) (xy 90.019378 -319.8368)
			(xy 90.023522 -319.815577) (xy 90.034071 -319.773638) (xy 90.04046 -319.75298) (xy 90.053158 -319.714202)
			(xy 90.086219 -319.639599) (xy 90.127595 -319.569266) (xy 90.17674 -319.504126) (xy 90.233012 -319.445032)
			(xy 90.26398 -319.418462) (xy 90.29573 -319.39357) (xy 90.326321 -319.371487) (xy 90.391328 -319.333187)
			(xy 90.460021 -319.301978) (xy 90.531631 -319.27821) (xy 90.605352 -319.26215) (xy 90.680359 -319.253978)
			(xy 90.75581 -319.253785) (xy 90.830857 -319.261575) (xy 90.90466 -319.277258) (xy 90.97639 -319.30066)
			(xy 91.045242 -319.331518) (xy 91.110444 -319.369486) (xy 91.165738 -319.41008) (xy 93.154506 -319.41008)
			(xy 93.158522 -319.29381) (xy 93.170549 -319.178095) (xy 93.190531 -319.063485) (xy 93.218373 -318.950526)
			(xy 93.253942 -318.839758) (xy 93.297068 -318.731707) (xy 93.347545 -318.626889) (xy 93.405134 -318.525804)
			(xy 93.46956 -318.428932) (xy 93.540515 -318.336736) (xy 93.617662 -318.249655) (xy 93.700633 -318.168104)
			(xy 93.789033 -318.092472) (xy 93.88244 -318.023118) (xy 93.980409 -317.960375) (xy 94.082473 -317.904539)
			(xy 94.188147 -317.855878) (xy 94.296926 -317.814624) (xy 94.408291 -317.780973) (xy 94.521714 -317.755085)
			(xy 94.636651 -317.737084) (xy 94.752557 -317.727055) (xy 94.868879 -317.725047) (xy 94.985062 -317.731069)
			(xy 95.100553 -317.745092) (xy 95.214801 -317.76705) (xy 95.327262 -317.796837) (xy 95.4374 -317.834312)
			(xy 95.54469 -317.879297) (xy 95.648621 -317.931576) (xy 95.748697 -317.990901) (xy 95.844443 -318.056989)
			(xy 95.9354 -318.129525) (xy 96.021136 -318.208164) (xy 96.101243 -318.29253) (xy 96.175339 -318.382222)
			(xy 96.243069 -318.476812) (xy 96.304113 -318.57585) (xy 96.358178 -318.678863) (xy 96.405008 -318.78536)
			(xy 96.444379 -318.894835) (xy 96.476103 -319.006765) (xy 96.500029 -319.120617) (xy 96.516043 -319.235849)
			(xy 96.52407 -319.351911) (xy 96.524572 -319.41008) (xy 96.52407 -319.468249) (xy 96.516043 -319.584311)
			(xy 96.500029 -319.699543) (xy 96.476103 -319.813395) (xy 96.444379 -319.925325) (xy 96.405008 -320.0348)
			(xy 96.358178 -320.141297) (xy 96.304113 -320.24431) (xy 96.243069 -320.343348) (xy 96.175339 -320.437938)
			(xy 96.101243 -320.52763) (xy 96.021136 -320.611996) (xy 95.9354 -320.690635) (xy 95.844443 -320.763171)
			(xy 95.748697 -320.829259) (xy 95.648621 -320.888584) (xy 95.54469 -320.940863) (xy 95.4374 -320.985848)
			(xy 95.327262 -321.023323) (xy 95.214801 -321.05311) (xy 95.100553 -321.075068) (xy 94.985062 -321.089091)
			(xy 94.868879 -321.095113) (xy 94.752557 -321.093105) (xy 94.636651 -321.083076) (xy 94.521714 -321.065075)
			(xy 94.408291 -321.039187) (xy 94.296926 -321.005536) (xy 94.188147 -320.964282) (xy 94.082473 -320.915621)
			(xy 93.980409 -320.859785) (xy 93.88244 -320.797042) (xy 93.789033 -320.727688) (xy 93.700633 -320.652056)
			(xy 93.617662 -320.570505) (xy 93.540515 -320.483424) (xy 93.46956 -320.391228) (xy 93.405134 -320.294356)
			(xy 93.347545 -320.193271) (xy 93.297068 -320.088453) (xy 93.253942 -319.980402) (xy 93.218373 -319.869634)
			(xy 93.190531 -319.756675) (xy 93.170549 -319.642065) (xy 93.158522 -319.52635) (xy 93.154506 -319.41008)
			(xy 91.165738 -319.41008) (xy 91.171264 -319.414137) (xy 91.22702 -319.464971) (xy 91.277086 -319.521417)
			(xy 91.320901 -319.582842) (xy 91.357973 -319.648557) (xy 91.387886 -319.717825) (xy 91.410305 -319.789868)
			(xy 91.424977 -319.863878) (xy 91.431739 -319.939026) (xy 91.431618 -319.976754) (xy 91.430602 -320.003678)
			(xy 91.430348 -320.006472) (xy 91.427694 -320.043734) (xy 91.415548 -320.117447) (xy 91.395751 -320.189484)
			(xy 91.368521 -320.259052) (xy 91.334157 -320.325386) (xy 91.293037 -320.387758) (xy 91.245612 -320.445482)
			(xy 91.192405 -320.497924) (xy 91.133999 -320.544507) (xy 91.071037 -320.584718) (xy 91.004212 -320.618117)
			(xy 90.934256 -320.644336) (xy 90.898218 -320.654172) (xy 90.891868 -320.655696) (xy 90.856661 -320.664)
			(xy 90.785054 -320.674269) (xy 90.712775 -320.677227) (xy 90.640568 -320.672845) (xy 90.569176 -320.661167)
			(xy 90.499336 -320.642314) (xy 90.465402 -320.629788) (xy 90.451432 -320.6242) (xy 90.416894 -320.609607)
			(xy 90.350807 -320.574181) (xy 90.288802 -320.532017) (xy 90.231562 -320.48358) (xy 90.205306 -320.456814)
			(xy 90.189091 -320.440561) (xy 90.151931 -320.41361) (xy 90.110536 -320.393767) (xy 90.066251 -320.381678)
			(xy 90.020515 -320.377735) (xy 89.974815 -320.382067) (xy 89.930635 -320.394533) (xy 89.88941 -320.414728)
			(xy 89.852481 -320.441995) (xy 89.821046 -320.475449) (xy 89.796128 -320.514003) (xy 89.778536 -320.556403)
			(xy 89.768842 -320.601273) (xy 89.767664 -320.6242) (xy 89.767664 -322.325746) (xy 86.239604 -325.85406)
			(xy 86.230714 -325.885556) (xy 86.222629 -325.911922) (xy 86.199923 -325.962177) (xy 86.17022 -326.008641)
			(xy 86.13414 -326.050347) (xy 86.092433 -326.086426) (xy 86.045968 -326.116128) (xy 85.995713 -326.138832)
			(xy 85.969348 -326.146922) (xy 85.937852 -326.155812) (xy 83.757516 -328.336148) (xy 81.46034 -328.336148)
			(xy 81.443721 -328.336684) (xy 81.411613 -328.345271) (xy 81.382818 -328.361871) (xy 81.370678 -328.373232)
			(xy 78.583824 -331.16012) (xy 86.877404 -331.16012) (xy 86.881424 -330.969469) (xy 86.893478 -330.779156)
			(xy 86.913544 -330.589521) (xy 86.941587 -330.4009) (xy 86.977556 -330.21363) (xy 87.021388 -330.028042)
			(xy 87.073005 -329.844467) (xy 87.132315 -329.663231) (xy 87.199213 -329.484656) (xy 87.273579 -329.309061)
			(xy 87.355281 -329.136756) (xy 87.444175 -328.968049) (xy 87.540101 -328.803239) (xy 87.64289 -328.64262)
			(xy 87.752359 -328.486477) (xy 87.868313 -328.335088) (xy 87.990547 -328.188721) (xy 88.118841 -328.047637)
			(xy 88.252969 -327.912088) (xy 88.392693 -327.782313) (xy 88.537763 -327.658543) (xy 88.687921 -327.541)
			(xy 88.842902 -327.429891) (xy 89.002429 -327.325414) (xy 89.166218 -327.227755) (xy 89.333978 -327.137088)
			(xy 89.505412 -327.053574) (xy 89.680214 -326.977361) (xy 89.858073 -326.908585) (xy 90.038674 -326.847367)
			(xy 90.221694 -326.793818) (xy 90.40681 -326.748032) (xy 90.593691 -326.71009) (xy 90.782006 -326.680061)
			(xy 90.971419 -326.657996) (xy 91.161593 -326.643937) (xy 91.352192 -326.637907) (xy 91.542875 -326.639917)
			(xy 91.733304 -326.649964) (xy 91.92314 -326.66803) (xy 92.112046 -326.694083) (xy 92.299685 -326.728076)
			(xy 92.485725 -326.769949) (xy 92.669834 -326.819628) (xy 92.851685 -326.877024) (xy 93.030955 -326.942035)
			(xy 93.207325 -327.014546) (xy 93.380481 -327.094427) (xy 93.550116 -327.181537) (xy 93.715928 -327.275721)
			(xy 93.877622 -327.376812) (xy 94.03491 -327.484628) (xy 94.187513 -327.59898) (xy 94.335161 -327.719663)
			(xy 94.477589 -327.846464) (xy 94.614545 -327.979155) (xy 94.745786 -328.117503) (xy 94.871078 -328.26126)
			(xy 94.990198 -328.410171) (xy 95.102934 -328.563972) (xy 95.209087 -328.722388) (xy 95.308467 -328.885139)
			(xy 95.400897 -329.051934) (xy 95.486214 -329.222478) (xy 95.564266 -329.396466) (xy 95.634913 -329.573591)
			(xy 95.698031 -329.753536) (xy 95.753507 -329.935982) (xy 95.801242 -330.120605) (xy 95.841152 -330.307075)
			(xy 95.873165 -330.495063) (xy 95.897225 -330.684233) (xy 95.913288 -330.874249) (xy 95.921327 -331.064773)
			(xy 95.92183 -331.16012) (xy 95.921327 -331.255467) (xy 95.913288 -331.445991) (xy 95.897225 -331.636007)
			(xy 95.873165 -331.825177) (xy 95.841152 -332.013165) (xy 95.801242 -332.199635) (xy 95.753507 -332.384258)
			(xy 95.698031 -332.566704) (xy 95.634913 -332.746649) (xy 95.564266 -332.923774) (xy 95.486214 -333.097762)
			(xy 95.400897 -333.268306) (xy 95.308467 -333.435101) (xy 95.209087 -333.597852) (xy 95.102934 -333.756268)
			(xy 94.990198 -333.910069) (xy 94.871078 -334.05898) (xy 94.745786 -334.202737) (xy 94.614545 -334.341085)
			(xy 94.477589 -334.473776) (xy 94.335161 -334.600577) (xy 94.187513 -334.72126) (xy 94.03491 -334.835612)
			(xy 93.877622 -334.943428) (xy 93.715928 -335.044519) (xy 93.550116 -335.138703) (xy 93.380481 -335.225813)
			(xy 93.207325 -335.305694) (xy 93.030955 -335.378205) (xy 92.851685 -335.443216) (xy 92.669834 -335.500612)
			(xy 92.485725 -335.550291) (xy 92.299685 -335.592164) (xy 92.112046 -335.626157) (xy 91.92314 -335.65221)
			(xy 91.733304 -335.670276) (xy 91.542875 -335.680323) (xy 91.352192 -335.682333) (xy 91.161593 -335.676303)
			(xy 90.971419 -335.662244) (xy 90.782006 -335.640179) (xy 90.593691 -335.61015) (xy 90.40681 -335.572208)
			(xy 90.221694 -335.526422) (xy 90.038674 -335.472873) (xy 89.858073 -335.411655) (xy 89.680214 -335.342879)
			(xy 89.505412 -335.266666) (xy 89.333978 -335.183152) (xy 89.166218 -335.092485) (xy 89.002429 -334.994826)
			(xy 88.842902 -334.890349) (xy 88.687921 -334.77924) (xy 88.537763 -334.661697) (xy 88.392693 -334.537927)
			(xy 88.252969 -334.408152) (xy 88.118841 -334.272603) (xy 87.990547 -334.131519) (xy 87.868313 -333.985152)
			(xy 87.752359 -333.833763) (xy 87.64289 -333.67762) (xy 87.540101 -333.517001) (xy 87.444175 -333.352191)
			(xy 87.355281 -333.183484) (xy 87.273579 -333.011179) (xy 87.199213 -332.835584) (xy 87.132315 -332.657009)
			(xy 87.073005 -332.475773) (xy 87.021388 -332.292198) (xy 86.977556 -332.10661) (xy 86.941587 -331.91934)
			(xy 86.913544 -331.730719) (xy 86.893478 -331.541084) (xy 86.881424 -331.350771) (xy 86.877404 -331.16012)
			(xy 78.583824 -331.16012) (xy 68.494304 -341.249762) (xy 72.868035 -341.249762) (xy 72.872042 -341.047012)
			(xy 72.884055 -340.844578) (xy 72.904056 -340.642777) (xy 72.932015 -340.441923) (xy 72.967886 -340.242331)
			(xy 73.011615 -340.044312) (xy 73.063133 -339.848175) (xy 73.122359 -339.654227) (xy 73.189201 -339.462769)
			(xy 73.263555 -339.274102) (xy 73.345304 -339.08852) (xy 73.434322 -338.906312) (xy 73.530468 -338.727763)
			(xy 73.633593 -338.553152) (xy 73.743536 -338.382752) (xy 73.860125 -338.216828) (xy 73.983178 -338.055639)
			(xy 74.112503 -337.899438) (xy 74.247898 -337.748468) (xy 74.389151 -337.602964) (xy 74.536043 -337.463155)
			(xy 74.688343 -337.329258) (xy 74.845814 -337.201483) (xy 75.008211 -337.080028) (xy 75.175278 -336.965084)
			(xy 75.346757 -336.85683) (xy 75.522378 -336.755435) (xy 75.701868 -336.661057) (xy 75.884946 -336.573845)
			(xy 76.071327 -336.493933) (xy 76.26072 -336.421446) (xy 76.452828 -336.356499) (xy 76.647352 -336.299191)
			(xy 76.843988 -336.249614) (xy 77.04243 -336.207843) (xy 77.242367 -336.173945) (xy 77.443486 -336.147973)
			(xy 77.645475 -336.129966) (xy 77.848018 -336.119953) (xy 78.050798 -336.117949) (xy 78.253499 -336.123959)
			(xy 78.455804 -336.137971) (xy 78.657398 -336.159966) (xy 78.857965 -336.189907) (xy 79.057193 -336.227748)
			(xy 79.254771 -336.273431) (xy 79.450389 -336.326884) (xy 79.643743 -336.388023) (xy 79.834531 -336.456754)
			(xy 80.022454 -336.532968) (xy 80.20722 -336.616547) (xy 80.388539 -336.70736) (xy 80.56613 -336.805265)
			(xy 80.739713 -336.91011) (xy 80.909019 -337.021731) (xy 81.073784 -337.139953) (xy 81.233749 -337.264593)
			(xy 81.388665 -337.395454) (xy 81.53829 -337.532334) (xy 81.68239 -337.675018) (xy 81.743189 -337.740174)
			(xy 88.87141 -337.740174) (xy 88.875302 -337.685822) (xy 88.886889 -337.632578) (xy 88.905936 -337.581524)
			(xy 88.932055 -337.533702) (xy 88.964715 -337.490083) (xy 89.00325 -337.451557) (xy 89.046876 -337.418907)
			(xy 89.094705 -337.392799) (xy 89.145763 -337.373764) (xy 89.19901 -337.362189) (xy 89.253362 -337.35831)
			(xy 89.307714 -337.362207) (xy 89.360957 -337.373799) (xy 89.412008 -337.392851) (xy 89.459829 -337.418975)
			(xy 89.481914 -337.434936) (xy 89.500926 -337.448532) (xy 89.542809 -337.469264) (xy 89.587777 -337.48199)
			(xy 89.634314 -337.48628) (xy 89.680851 -337.48199) (xy 89.725819 -337.469264) (xy 89.767702 -337.448532)
			(xy 89.786714 -337.434936) (xy 89.808761 -337.418918) (xy 89.856588 -337.392794) (xy 89.907646 -337.373742)
			(xy 89.960896 -337.362151) (xy 90.015254 -337.358257) (xy 90.069612 -337.362138) (xy 90.122865 -337.373716)
			(xy 90.173928 -337.392755) (xy 90.221761 -337.418868) (xy 90.265391 -337.451522) (xy 90.30393 -337.490053)
			(xy 90.336593 -337.533677) (xy 90.362715 -337.581506) (xy 90.381763 -337.632565) (xy 90.393352 -337.685816)
			(xy 90.397243 -337.740174) (xy 91.863003 -337.740174) (xy 91.866895 -337.68582) (xy 91.878482 -337.632574)
			(xy 91.89753 -337.58152) (xy 91.923651 -337.533696) (xy 91.956312 -337.490076) (xy 91.994848 -337.451549)
			(xy 92.038476 -337.418899) (xy 92.086307 -337.39279) (xy 92.137366 -337.373755) (xy 92.190615 -337.362181)
			(xy 92.244969 -337.358303) (xy 92.299322 -337.362201) (xy 92.352567 -337.373794) (xy 92.403619 -337.392848)
			(xy 92.45144 -337.418974) (xy 92.473526 -337.434936) (xy 92.492538 -337.448532) (xy 92.534421 -337.469264)
			(xy 92.579389 -337.48199) (xy 92.625926 -337.48628) (xy 92.672463 -337.48199) (xy 92.717431 -337.469264)
			(xy 92.759314 -337.448532) (xy 92.778326 -337.434936) (xy 92.800372 -337.418919) (xy 92.848199 -337.392797)
			(xy 92.899256 -337.373747) (xy 92.952504 -337.362157) (xy 93.00686 -337.358264) (xy 93.061217 -337.362146)
			(xy 93.114468 -337.373724) (xy 93.165529 -337.392764) (xy 93.213361 -337.418876) (xy 93.25699 -337.45153)
			(xy 93.295527 -337.49006) (xy 93.328188 -337.533683) (xy 93.354309 -337.581511) (xy 93.373357 -337.632568)
			(xy 93.384945 -337.685817) (xy 93.388836 -337.740174) (xy 93.384952 -337.79453) (xy 93.373372 -337.847781)
			(xy 93.354331 -337.898841) (xy 93.328217 -337.946672) (xy 93.295561 -337.9903) (xy 93.257029 -338.028836)
			(xy 93.213405 -338.061495) (xy 93.165577 -338.087614) (xy 93.114519 -338.106661) (xy 93.061269 -338.118247)
			(xy 93.006913 -338.122136) (xy 92.952557 -338.11825) (xy 92.899306 -338.106668) (xy 92.848247 -338.087625)
			(xy 92.800417 -338.06151) (xy 92.778326 -338.045552) (xy 92.759314 -338.031956) (xy 92.717431 -338.011224)
			(xy 92.672463 -337.998498) (xy 92.625926 -337.994208) (xy 92.579389 -337.998498) (xy 92.534421 -338.011224)
			(xy 92.492538 -338.031956) (xy 92.473526 -338.045552) (xy 92.451396 -338.061455) (xy 92.403571 -338.087574)
			(xy 92.352516 -338.106621) (xy 92.29927 -338.118207) (xy 92.244916 -338.122097) (xy 92.190563 -338.118212)
			(xy 92.137316 -338.10663) (xy 92.086259 -338.087588) (xy 92.038432 -338.061473) (xy 91.994808 -338.028816)
			(xy 91.956277 -337.990284) (xy 91.923622 -337.94666) (xy 91.897508 -337.898832) (xy 91.878467 -337.847775)
			(xy 91.866887 -337.794527) (xy 91.863003 -337.740174) (xy 90.397243 -337.740174) (xy 90.393359 -337.794532)
			(xy 90.381778 -337.847784) (xy 90.362737 -337.898846) (xy 90.336622 -337.946678) (xy 90.303965 -337.990307)
			(xy 90.265431 -338.028843) (xy 90.221806 -338.061504) (xy 90.173976 -338.087623) (xy 90.122915 -338.106669)
			(xy 90.069664 -338.118255) (xy 90.015306 -338.122143) (xy 89.960948 -338.118256) (xy 89.907697 -338.106673)
			(xy 89.856636 -338.087628) (xy 89.808805 -338.061511) (xy 89.786714 -338.045552) (xy 89.767702 -338.031956)
			(xy 89.725819 -338.011224) (xy 89.680851 -337.998498) (xy 89.634314 -337.994208) (xy 89.587777 -337.998498)
			(xy 89.542809 -338.011224) (xy 89.500926 -338.031956) (xy 89.481914 -338.045552) (xy 89.459784 -338.061454)
			(xy 89.41196 -338.087571) (xy 89.360906 -338.106616) (xy 89.307661 -338.118201) (xy 89.25331 -338.12209)
			(xy 89.198958 -338.118204) (xy 89.145712 -338.106621) (xy 89.094657 -338.087579) (xy 89.046832 -338.061464)
			(xy 89.00321 -338.028809) (xy 88.96468 -337.990277) (xy 88.932027 -337.946654) (xy 88.905914 -337.898828)
			(xy 88.886874 -337.847772) (xy 88.875294 -337.794526) (xy 88.87141 -337.740174) (xy 81.743189 -337.740174)
			(xy 81.820742 -337.823284) (xy 81.953127 -337.9769) (xy 82.079341 -338.135625) (xy 82.199185 -338.299214)
			(xy 82.312473 -338.467409) (xy 82.419028 -338.639948) (xy 82.518683 -338.816563) (xy 82.611283 -338.996976)
			(xy 82.696683 -339.180907) (xy 82.77475 -339.368068) (xy 82.845362 -339.558168) (xy 82.908408 -339.750908)
			(xy 82.963791 -339.945989) (xy 83.011423 -340.143106) (xy 83.051231 -340.34195) (xy 83.062258 -340.411128)
			(xy 88.871338 -340.411128) (xy 88.875223 -340.356765) (xy 88.886804 -340.303509) (xy 88.905848 -340.252444)
			(xy 88.931965 -340.204608) (xy 88.964625 -340.160977) (xy 89.003162 -340.122438) (xy 89.046792 -340.089776)
			(xy 89.094626 -340.063656) (xy 89.145691 -340.04461) (xy 89.198946 -340.033025) (xy 89.253308 -340.029138)
			(xy 89.30767 -340.033028) (xy 89.360925 -340.044615) (xy 89.411989 -340.063663) (xy 89.459822 -340.089785)
			(xy 89.481914 -340.105746) (xy 89.500926 -340.119342) (xy 89.542809 -340.140074) (xy 89.587777 -340.1528)
			(xy 89.634314 -340.15709) (xy 89.680851 -340.1528) (xy 89.725819 -340.140074) (xy 89.767702 -340.119342)
			(xy 89.786714 -340.105746) (xy 89.808845 -340.089849) (xy 89.856667 -340.063737) (xy 89.907718 -340.044696)
			(xy 89.96096 -340.033115) (xy 90.015308 -340.029229) (xy 90.069655 -340.033117) (xy 90.122896 -340.0447)
			(xy 90.173947 -340.063743) (xy 90.221768 -340.089857) (xy 90.265385 -340.122512) (xy 90.303911 -340.161041)
			(xy 90.336562 -340.204662) (xy 90.362672 -340.252485) (xy 90.38171 -340.303537) (xy 90.393288 -340.35678)
			(xy 90.397171 -340.411128) (xy 91.862931 -340.411128) (xy 91.866816 -340.356764) (xy 91.878398 -340.303506)
			(xy 91.897442 -340.252439) (xy 91.923561 -340.204602) (xy 91.956222 -340.16097) (xy 91.99476 -340.12243)
			(xy 92.038392 -340.089767) (xy 92.086228 -340.063647) (xy 92.137294 -340.044601) (xy 92.190551 -340.033017)
			(xy 92.244915 -340.029131) (xy 92.299279 -340.033022) (xy 92.352535 -340.04461) (xy 92.4036 -340.06366)
			(xy 92.451434 -340.089784) (xy 92.473526 -340.105746) (xy 92.492538 -340.119342) (xy 92.534421 -340.140074)
			(xy 92.579389 -340.1528) (xy 92.625926 -340.15709) (xy 92.672463 -340.1528) (xy 92.717431 -340.140074)
			(xy 92.759314 -340.119342) (xy 92.778326 -340.105746) (xy 92.800457 -340.08985) (xy 92.848278 -340.06374)
			(xy 92.899328 -340.044701) (xy 92.952568 -340.033121) (xy 93.006914 -340.029236) (xy 93.06126 -340.033125)
			(xy 93.1145 -340.044709) (xy 93.165548 -340.063752) (xy 93.213367 -340.089866) (xy 93.256983 -340.12252)
			(xy 93.295508 -340.161048) (xy 93.328157 -340.204668) (xy 93.354266 -340.25249) (xy 93.373303 -340.303541)
			(xy 93.384881 -340.356781) (xy 93.388764 -340.411128) (xy 93.384873 -340.465473) (xy 93.373287 -340.518712)
			(xy 93.354243 -340.56976) (xy 93.328127 -340.617579) (xy 93.295472 -340.661193) (xy 93.256941 -340.699716)
			(xy 93.213321 -340.732364) (xy 93.165498 -340.758471) (xy 93.114447 -340.777507) (xy 93.061206 -340.789083)
			(xy 93.006859 -340.792964) (xy 92.952513 -340.789071) (xy 92.899275 -340.777484) (xy 92.848227 -340.758437)
			(xy 92.80041 -340.73232) (xy 92.778326 -340.716362) (xy 92.759314 -340.702766) (xy 92.717431 -340.682034)
			(xy 92.672463 -340.669308) (xy 92.625926 -340.665018) (xy 92.579389 -340.669308) (xy 92.534421 -340.682034)
			(xy 92.492538 -340.702766) (xy 92.473526 -340.716362) (xy 92.45148 -340.732386) (xy 92.40365 -340.758517)
			(xy 92.352588 -340.777574) (xy 92.299333 -340.78917) (xy 92.24497 -340.793069) (xy 92.190606 -340.789191)
			(xy 92.137347 -340.777614) (xy 92.086278 -340.758576) (xy 92.038438 -340.732462) (xy 91.994802 -340.699806)
			(xy 91.956258 -340.661272) (xy 91.923591 -340.617644) (xy 91.897465 -340.569811) (xy 91.878413 -340.518747)
			(xy 91.866823 -340.465491) (xy 91.862931 -340.411128) (xy 90.397171 -340.411128) (xy 90.39328 -340.465475)
			(xy 90.381694 -340.518716) (xy 90.362649 -340.569765) (xy 90.336532 -340.617585) (xy 90.303875 -340.6612)
			(xy 90.265343 -340.699724) (xy 90.221721 -340.732372) (xy 90.173897 -340.75848) (xy 90.122843 -340.777515)
			(xy 90.069601 -340.789091) (xy 90.015252 -340.792971) (xy 89.960905 -340.789077) (xy 89.907665 -340.777488)
			(xy 89.856617 -340.75844) (xy 89.808799 -340.732321) (xy 89.786714 -340.716362) (xy 89.767702 -340.702766)
			(xy 89.725819 -340.682034) (xy 89.680851 -340.669308) (xy 89.634314 -340.665018) (xy 89.587777 -340.669308)
			(xy 89.542809 -340.682034) (xy 89.500926 -340.702766) (xy 89.481914 -340.716362) (xy 89.459869 -340.732385)
			(xy 89.412039 -340.758514) (xy 89.360978 -340.77757) (xy 89.307725 -340.789164) (xy 89.253364 -340.793062)
			(xy 89.199001 -340.789182) (xy 89.145744 -340.777606) (xy 89.094676 -340.758567) (xy 89.046838 -340.732454)
			(xy 89.003204 -340.699798) (xy 88.964661 -340.661265) (xy 88.931995 -340.617638) (xy 88.905871 -340.569807)
			(xy 88.88682 -340.518744) (xy 88.87523 -340.465489) (xy 88.871338 -340.411128) (xy 83.062258 -340.411128)
			(xy 83.083153 -340.542212) (xy 83.107137 -340.743578) (xy 83.123148 -340.945735) (xy 83.131159 -341.148367)
			(xy 83.13166 -341.249762) (xy 83.131159 -341.351157) (xy 83.123148 -341.553789) (xy 83.107137 -341.755946)
			(xy 83.083153 -341.957312) (xy 83.051231 -342.157574) (xy 83.011423 -342.356418) (xy 82.963791 -342.553535)
			(xy 82.908408 -342.748616) (xy 82.845362 -342.941356) (xy 82.794128 -343.079286) (xy 88.871394 -343.079286)
			(xy 88.875284 -343.024932) (xy 88.88687 -342.971685) (xy 88.905916 -342.920629) (xy 88.932035 -342.872803)
			(xy 88.964695 -342.829182) (xy 89.003231 -342.790653) (xy 89.046858 -342.758) (xy 89.094688 -342.731889)
			(xy 89.145747 -342.712852) (xy 89.198996 -342.701275) (xy 89.25335 -342.697394) (xy 89.307704 -342.701289)
			(xy 89.36095 -342.71288) (xy 89.412004 -342.731931) (xy 89.459827 -342.758055) (xy 89.481914 -342.774016)
			(xy 89.500926 -342.787612) (xy 89.542809 -342.808344) (xy 89.587777 -342.82107) (xy 89.634314 -342.82536)
			(xy 89.680851 -342.82107) (xy 89.725819 -342.808344) (xy 89.767702 -342.787612) (xy 89.786714 -342.774016)
			(xy 89.808779 -342.758025) (xy 89.856605 -342.731903) (xy 89.907662 -342.712854) (xy 89.96091 -342.701265)
			(xy 90.015266 -342.697373) (xy 90.069622 -342.701255) (xy 90.122872 -342.712835) (xy 90.173932 -342.731875)
			(xy 90.221763 -342.757988) (xy 90.26539 -342.790642) (xy 90.303926 -342.829173) (xy 90.336586 -342.872796)
			(xy 90.362705 -342.920624) (xy 90.381752 -342.971681) (xy 90.393338 -343.02493) (xy 90.397227 -343.079286)
			(xy 91.862987 -343.079286) (xy 91.866877 -343.02493) (xy 91.878464 -342.971681) (xy 91.897511 -342.920624)
			(xy 91.923631 -342.872797) (xy 91.956292 -342.829175) (xy 91.994829 -342.790645) (xy 92.038457 -342.757992)
			(xy 92.086289 -342.731881) (xy 92.13735 -342.712843) (xy 92.190601 -342.701267) (xy 92.244957 -342.697387)
			(xy 92.299312 -342.701283) (xy 92.35256 -342.712876) (xy 92.403615 -342.731928) (xy 92.451439 -342.758054)
			(xy 92.473526 -342.774016) (xy 92.492538 -342.787612) (xy 92.534421 -342.808344) (xy 92.579389 -342.82107)
			(xy 92.625926 -342.82536) (xy 92.672463 -342.82107) (xy 92.717431 -342.808344) (xy 92.759314 -342.787612)
			(xy 92.778326 -342.774016) (xy 92.800391 -342.758026) (xy 92.848216 -342.731906) (xy 92.899272 -342.712859)
			(xy 92.952519 -342.701271) (xy 93.006872 -342.69738) (xy 93.061227 -342.701263) (xy 93.114475 -342.712843)
			(xy 93.165533 -342.731883) (xy 93.213362 -342.757996) (xy 93.256988 -342.79065) (xy 93.295523 -342.82918)
			(xy 93.328181 -342.872802) (xy 93.354299 -342.920628) (xy 93.373345 -342.971685) (xy 93.384931 -343.024932)
			(xy 93.38882 -343.079286) (xy 93.384935 -343.13364) (xy 93.373353 -343.186888) (xy 93.354311 -343.237946)
			(xy 93.328197 -343.285774) (xy 93.295541 -343.329398) (xy 93.25701 -343.367931) (xy 93.213387 -343.400588)
			(xy 93.16556 -343.426705) (xy 93.114503 -343.445749) (xy 93.061255 -343.457332) (xy 93.006901 -343.46122)
			(xy 92.952547 -343.457333) (xy 92.899299 -343.445749) (xy 92.848242 -343.426706) (xy 92.800415 -343.40059)
			(xy 92.778326 -343.384632) (xy 92.759314 -343.371036) (xy 92.717431 -343.350304) (xy 92.672463 -343.337578)
			(xy 92.625926 -343.333288) (xy 92.579389 -343.337578) (xy 92.534421 -343.350304) (xy 92.492538 -343.371036)
			(xy 92.473526 -343.384632) (xy 92.451415 -343.400562) (xy 92.403589 -343.426684) (xy 92.352532 -343.445733)
			(xy 92.299284 -343.457321) (xy 92.244928 -343.461213) (xy 92.190572 -343.457329) (xy 92.137323 -343.445749)
			(xy 92.086263 -343.426707) (xy 92.038433 -343.400593) (xy 91.994807 -343.367936) (xy 91.956273 -343.329404)
			(xy 91.923615 -343.285779) (xy 91.897499 -343.23795) (xy 91.878455 -343.186891) (xy 91.866873 -343.133641)
			(xy 91.862987 -343.079286) (xy 90.397227 -343.079286) (xy 90.393342 -343.133641) (xy 90.38176 -343.186891)
			(xy 90.362717 -343.23795) (xy 90.336602 -343.28578) (xy 90.303945 -343.329405) (xy 90.265412 -343.367939)
			(xy 90.221787 -343.400597) (xy 90.173958 -343.426713) (xy 90.122899 -343.445757) (xy 90.06965 -343.45734)
			(xy 90.015294 -343.461227) (xy 89.960939 -343.457339) (xy 89.90769 -343.445754) (xy 89.856632 -343.426709)
			(xy 89.808804 -343.400591) (xy 89.786714 -343.384632) (xy 89.767702 -343.371036) (xy 89.725819 -343.350304)
			(xy 89.680851 -343.337578) (xy 89.634314 -343.333288) (xy 89.587777 -343.337578) (xy 89.542809 -343.350304)
			(xy 89.500926 -343.371036) (xy 89.481914 -343.384632) (xy 89.459803 -343.400561) (xy 89.411978 -343.426681)
			(xy 89.360922 -343.445728) (xy 89.307675 -343.457315) (xy 89.253322 -343.461206) (xy 89.198967 -343.457321)
			(xy 89.145719 -343.44574) (xy 89.094661 -343.426699) (xy 89.046833 -343.400584) (xy 89.003209 -343.367929)
			(xy 88.964676 -343.329397) (xy 88.93202 -343.285773) (xy 88.905904 -343.237945) (xy 88.886862 -343.186888)
			(xy 88.87528 -343.13364) (xy 88.871394 -343.079286) (xy 82.794128 -343.079286) (xy 82.77475 -343.131456)
			(xy 82.696683 -343.318617) (xy 82.611283 -343.502548) (xy 82.588369 -343.547192) (xy 94.503238 -343.547192)
			(xy 94.507309 -343.49157) (xy 94.519435 -343.437133) (xy 94.539358 -343.385042) (xy 94.566654 -343.336407)
			(xy 94.60074 -343.292264) (xy 94.640889 -343.253555) (xy 94.686247 -343.221104) (xy 94.735847 -343.195603)
			(xy 94.788631 -343.177596) (xy 94.843474 -343.167466) (xy 94.899208 -343.165429) (xy 94.954645 -343.171529)
			(xy 95.008602 -343.185635) (xy 95.059931 -343.207447) (xy 95.107537 -343.236501) (xy 95.150405 -343.272176)
			(xy 95.187622 -343.313713) (xy 95.218395 -343.360226) (xy 95.242067 -343.410723) (xy 95.258135 -343.46413)
			(xy 95.266255 -343.519306) (xy 95.266764 -343.547192) (xy 95.266255 -343.575078) (xy 95.258135 -343.630254)
			(xy 95.242067 -343.683661) (xy 95.218395 -343.734158) (xy 95.187622 -343.780671) (xy 95.150405 -343.822208)
			(xy 95.107537 -343.857883) (xy 95.059931 -343.886937) (xy 95.008602 -343.908749) (xy 94.954645 -343.922855)
			(xy 94.899208 -343.928955) (xy 94.843474 -343.926918) (xy 94.788631 -343.916788) (xy 94.735847 -343.898781)
			(xy 94.686247 -343.87328) (xy 94.640889 -343.840829) (xy 94.60074 -343.80212) (xy 94.566654 -343.757977)
			(xy 94.539358 -343.709342) (xy 94.519435 -343.657251) (xy 94.507309 -343.602814) (xy 94.503238 -343.547192)
			(xy 82.588369 -343.547192) (xy 82.518683 -343.682961) (xy 82.419028 -343.859576) (xy 82.312473 -344.032115)
			(xy 82.199185 -344.20031) (xy 82.079341 -344.363899) (xy 81.953127 -344.522624) (xy 81.820742 -344.67624)
			(xy 81.68239 -344.824506) (xy 81.53829 -344.96719) (xy 81.388665 -345.10407) (xy 81.233749 -345.234931)
			(xy 81.073784 -345.359571) (xy 80.946518 -345.450887) (xy 88.871393 -345.450887) (xy 88.875282 -345.396533)
			(xy 88.886868 -345.343285) (xy 88.905914 -345.292229) (xy 88.932033 -345.244403) (xy 88.964693 -345.200782)
			(xy 89.003229 -345.162252) (xy 89.046856 -345.1296) (xy 89.094686 -345.103489) (xy 89.145745 -345.084451)
			(xy 89.198994 -345.072873) (xy 89.253349 -345.068993) (xy 89.307703 -345.072887) (xy 89.360949 -345.084478)
			(xy 89.412004 -345.103529) (xy 89.459827 -345.129653) (xy 89.481914 -345.145614) (xy 89.500926 -345.15921)
			(xy 89.542809 -345.179942) (xy 89.587777 -345.192668) (xy 89.634314 -345.196958) (xy 89.680851 -345.192668)
			(xy 89.725819 -345.179942) (xy 89.767702 -345.15921) (xy 89.786714 -345.145614) (xy 89.808781 -345.129626)
			(xy 89.856607 -345.103504) (xy 89.907664 -345.084455) (xy 89.960912 -345.072867) (xy 90.015267 -345.068974)
			(xy 90.069623 -345.072857) (xy 90.122872 -345.084437) (xy 90.173932 -345.103477) (xy 90.221763 -345.12959)
			(xy 90.26539 -345.162244) (xy 90.303926 -345.200775) (xy 90.336585 -345.244398) (xy 90.362704 -345.292225)
			(xy 90.38175 -345.343283) (xy 90.393336 -345.396531) (xy 90.397226 -345.450887) (xy 91.862986 -345.450887)
			(xy 91.866875 -345.396531) (xy 91.878462 -345.343282) (xy 91.897509 -345.292224) (xy 91.923629 -345.244397)
			(xy 91.95629 -345.200775) (xy 91.994827 -345.162244) (xy 92.038455 -345.129591) (xy 92.086287 -345.10348)
			(xy 92.137349 -345.084442) (xy 92.1906 -345.072865) (xy 92.244956 -345.068986) (xy 92.299311 -345.072881)
			(xy 92.352559 -345.084474) (xy 92.403615 -345.103526) (xy 92.451439 -345.129652) (xy 92.473526 -345.145614)
			(xy 92.492538 -345.15921) (xy 92.534421 -345.179942) (xy 92.579389 -345.192668) (xy 92.625926 -345.196958)
			(xy 92.672463 -345.192668) (xy 92.717431 -345.179942) (xy 92.759314 -345.15921) (xy 92.778326 -345.145614)
			(xy 92.800393 -345.129627) (xy 92.848218 -345.103507) (xy 92.899273 -345.08446) (xy 92.95252 -345.072873)
			(xy 93.006874 -345.068981) (xy 93.061228 -345.072865) (xy 93.114476 -345.084445) (xy 93.165534 -345.103485)
			(xy 93.213363 -345.129598) (xy 93.256988 -345.162252) (xy 93.295522 -345.200782) (xy 93.328181 -345.244404)
			(xy 93.354298 -345.29223) (xy 93.373344 -345.343286) (xy 93.384929 -345.396533) (xy 93.388819 -345.450887)
			(xy 93.384933 -345.505241) (xy 93.373351 -345.558489) (xy 93.354309 -345.609546) (xy 93.328195 -345.657374)
			(xy 93.295539 -345.700998) (xy 93.257008 -345.739531) (xy 93.213385 -345.772188) (xy 93.165558 -345.798304)
			(xy 93.114501 -345.817348) (xy 93.061254 -345.828931) (xy 93.0069 -345.832819) (xy 92.952546 -345.828931)
			(xy 92.899299 -345.817347) (xy 92.848242 -345.798304) (xy 92.800415 -345.772188) (xy 92.778326 -345.75623)
			(xy 92.759314 -345.742634) (xy 92.717431 -345.721902) (xy 92.672463 -345.709176) (xy 92.625926 -345.704886)
			(xy 92.579389 -345.709176) (xy 92.534421 -345.721902) (xy 92.492538 -345.742634) (xy 92.473526 -345.75623)
			(xy 92.451417 -345.772162) (xy 92.403591 -345.798284) (xy 92.352534 -345.817334) (xy 92.299285 -345.828922)
			(xy 92.24493 -345.832814) (xy 92.190573 -345.828931) (xy 92.137323 -345.81735) (xy 92.086263 -345.798309)
			(xy 92.038433 -345.772195) (xy 91.994807 -345.739538) (xy 91.956272 -345.701006) (xy 91.923614 -345.657381)
			(xy 91.897498 -345.609552) (xy 91.878454 -345.558493) (xy 91.866872 -345.505243) (xy 91.862986 -345.450887)
			(xy 90.397226 -345.450887) (xy 90.39334 -345.505242) (xy 90.381758 -345.558492) (xy 90.362715 -345.609551)
			(xy 90.3366 -345.65738) (xy 90.303943 -345.701005) (xy 90.26541 -345.739539) (xy 90.221785 -345.772196)
			(xy 90.173956 -345.798312) (xy 90.122898 -345.817356) (xy 90.069649 -345.828939) (xy 90.015293 -345.832826)
			(xy 89.960938 -345.828937) (xy 89.907689 -345.817352) (xy 89.856631 -345.798307) (xy 89.808803 -345.772189)
			(xy 89.786714 -345.75623) (xy 89.767702 -345.742634) (xy 89.725819 -345.721902) (xy 89.680851 -345.709176)
			(xy 89.634314 -345.704886) (xy 89.587777 -345.709176) (xy 89.542809 -345.721902) (xy 89.500926 -345.742634)
			(xy 89.481914 -345.75623) (xy 89.459805 -345.772161) (xy 89.41198 -345.798282) (xy 89.360924 -345.817329)
			(xy 89.307677 -345.828916) (xy 89.253323 -345.832807) (xy 89.198968 -345.828923) (xy 89.14572 -345.817342)
			(xy 89.094662 -345.7983) (xy 89.046833 -345.772186) (xy 89.003209 -345.73953) (xy 88.964676 -345.700998)
			(xy 88.932019 -345.657375) (xy 88.905903 -345.609547) (xy 88.886861 -345.558489) (xy 88.875279 -345.505241)
			(xy 88.871393 -345.450887) (xy 80.946518 -345.450887) (xy 80.909019 -345.477793) (xy 80.739713 -345.589414)
			(xy 80.56613 -345.694259) (xy 80.388539 -345.792164) (xy 80.20722 -345.882977) (xy 80.022454 -345.966556)
			(xy 79.834531 -346.04277) (xy 79.643743 -346.111501) (xy 79.450389 -346.17264) (xy 79.254771 -346.226093)
			(xy 79.057193 -346.271776) (xy 78.857965 -346.309617) (xy 78.657398 -346.339558) (xy 78.455804 -346.361553)
			(xy 78.253499 -346.375565) (xy 78.050798 -346.381575) (xy 77.848018 -346.379571) (xy 77.645475 -346.369558)
			(xy 77.443486 -346.351551) (xy 77.242367 -346.325579) (xy 77.04243 -346.291681) (xy 76.843988 -346.24991)
			(xy 76.647352 -346.200333) (xy 76.452828 -346.143025) (xy 76.26072 -346.078078) (xy 76.071327 -346.005591)
			(xy 75.884946 -345.925679) (xy 75.701868 -345.838467) (xy 75.522378 -345.744089) (xy 75.346757 -345.642694)
			(xy 75.175278 -345.53444) (xy 75.008211 -345.419496) (xy 74.845814 -345.298041) (xy 74.688343 -345.170266)
			(xy 74.536043 -345.036369) (xy 74.389151 -344.89656) (xy 74.247898 -344.751056) (xy 74.112503 -344.600086)
			(xy 73.983178 -344.443885) (xy 73.860125 -344.282696) (xy 73.743536 -344.116772) (xy 73.633593 -343.946372)
			(xy 73.530468 -343.771761) (xy 73.434322 -343.593212) (xy 73.345304 -343.411004) (xy 73.263555 -343.225422)
			(xy 73.189201 -343.036755) (xy 73.122359 -342.845297) (xy 73.063133 -342.651349) (xy 73.011615 -342.455212)
			(xy 72.967886 -342.257193) (xy 72.932015 -342.057601) (xy 72.904056 -341.856747) (xy 72.884055 -341.654946)
			(xy 72.872042 -341.452512) (xy 72.868035 -341.249762) (xy 68.494304 -341.249762) (xy 62.33036 -347.41378)
			(xy 88.871402 -347.41378) (xy 88.875293 -347.359427) (xy 88.886879 -347.306181) (xy 88.905926 -347.255126)
			(xy 88.932045 -347.207302) (xy 88.964705 -347.163682) (xy 89.00324 -347.125155) (xy 89.046867 -347.092504)
			(xy 89.094696 -347.066394) (xy 89.145755 -347.047358) (xy 89.199003 -347.035782) (xy 89.253356 -347.031902)
			(xy 89.307709 -347.035798) (xy 89.360953 -347.04739) (xy 89.412006 -347.066441) (xy 89.459828 -347.092565)
			(xy 89.481914 -347.108526) (xy 89.500926 -347.122122) (xy 89.542809 -347.142854) (xy 89.587777 -347.15558)
			(xy 89.634314 -347.15987) (xy 89.680851 -347.15558) (xy 89.725819 -347.142854) (xy 89.767702 -347.122122)
			(xy 89.786714 -347.108526) (xy 89.80877 -347.092521) (xy 89.856597 -347.066398) (xy 89.907654 -347.047348)
			(xy 89.960903 -347.035758) (xy 90.01526 -347.031865) (xy 90.069617 -347.035747) (xy 90.122868 -347.047325)
			(xy 90.17393 -347.066365) (xy 90.221762 -347.092478) (xy 90.265391 -347.125132) (xy 90.303928 -347.163663)
			(xy 90.336589 -347.207287) (xy 90.36271 -347.255115) (xy 90.381758 -347.306173) (xy 90.393345 -347.359423)
			(xy 90.397235 -347.41378) (xy 91.862995 -347.41378) (xy 91.866886 -347.359425) (xy 91.878473 -347.306178)
			(xy 91.89752 -347.255122) (xy 91.923641 -347.207296) (xy 91.956302 -347.163675) (xy 91.994839 -347.125147)
			(xy 92.038467 -347.092495) (xy 92.086298 -347.066386) (xy 92.137358 -347.047349) (xy 92.190608 -347.035774)
			(xy 92.244963 -347.031895) (xy 92.299317 -347.035792) (xy 92.352563 -347.047385) (xy 92.403617 -347.066438)
			(xy 92.45144 -347.092564) (xy 92.473526 -347.108526) (xy 92.492538 -347.122122) (xy 92.534421 -347.142854)
			(xy 92.579389 -347.15558) (xy 92.625926 -347.15987) (xy 92.672463 -347.15558) (xy 92.717431 -347.142854)
			(xy 92.759314 -347.122122) (xy 92.778326 -347.108526) (xy 92.800382 -347.092522) (xy 92.848207 -347.066401)
			(xy 92.899264 -347.047353) (xy 92.952511 -347.035764) (xy 93.006866 -347.031872) (xy 93.061222 -347.035755)
			(xy 93.114472 -347.047334) (xy 93.165531 -347.066373) (xy 93.213362 -347.092486) (xy 93.256989 -347.12514)
			(xy 93.295525 -347.16367) (xy 93.328185 -347.207293) (xy 93.354304 -347.255119) (xy 93.373351 -347.306177)
			(xy 93.384938 -347.359425) (xy 93.388828 -347.41378) (xy 93.384943 -347.468135) (xy 93.373362 -347.521384)
			(xy 93.354321 -347.572443) (xy 93.328207 -347.620273) (xy 93.295551 -347.663899) (xy 93.25702 -347.702433)
			(xy 93.213396 -347.735092) (xy 93.165568 -347.76121) (xy 93.114511 -347.780255) (xy 93.061262 -347.791839)
			(xy 93.006907 -347.795728) (xy 92.952552 -347.791842) (xy 92.899303 -347.780259) (xy 92.848245 -347.761216)
			(xy 92.800416 -347.7351) (xy 92.778326 -347.719142) (xy 92.759314 -347.705546) (xy 92.717431 -347.684814)
			(xy 92.672463 -347.672088) (xy 92.625926 -347.667798) (xy 92.579389 -347.672088) (xy 92.534421 -347.684814)
			(xy 92.492538 -347.705546) (xy 92.473526 -347.719142) (xy 92.451405 -347.735058) (xy 92.40358 -347.761179)
			(xy 92.352524 -347.780227) (xy 92.299277 -347.791814) (xy 92.244922 -347.795705) (xy 92.190568 -347.79182)
			(xy 92.137319 -347.780239) (xy 92.086261 -347.761197) (xy 92.038432 -347.735083) (xy 91.994808 -347.702426)
			(xy 91.956275 -347.663894) (xy 91.923619 -347.620269) (xy 91.897503 -347.572441) (xy 91.878461 -347.521383)
			(xy 91.86688 -347.468134) (xy 91.862995 -347.41378) (xy 90.397235 -347.41378) (xy 90.39335 -347.468137)
			(xy 90.381769 -347.521388) (xy 90.362727 -347.572448) (xy 90.336612 -347.620279) (xy 90.303955 -347.663906)
			(xy 90.265422 -347.702441) (xy 90.221796 -347.7351) (xy 90.173967 -347.761218) (xy 90.122907 -347.780263)
			(xy 90.069657 -347.791847) (xy 90.0153 -347.795735) (xy 89.960943 -347.791848) (xy 89.907693 -347.780263)
			(xy 89.856634 -347.761218) (xy 89.808804 -347.735101) (xy 89.786714 -347.719142) (xy 89.767702 -347.705546)
			(xy 89.725819 -347.684814) (xy 89.680851 -347.672088) (xy 89.634314 -347.667798) (xy 89.587777 -347.672088)
			(xy 89.542809 -347.684814) (xy 89.500926 -347.705546) (xy 89.481914 -347.719142) (xy 89.459794 -347.735057)
			(xy 89.411969 -347.761176) (xy 89.360914 -347.780222) (xy 89.307668 -347.791808) (xy 89.253316 -347.795698)
			(xy 89.198962 -347.791812) (xy 89.145716 -347.780231) (xy 89.094659 -347.761189) (xy 89.046833 -347.735074)
			(xy 89.00321 -347.702419) (xy 88.964678 -347.663887) (xy 88.932023 -347.620263) (xy 88.905909 -347.572436)
			(xy 88.886868 -347.52138) (xy 88.875287 -347.468133) (xy 88.871402 -347.41378) (xy 62.33036 -347.41378)
			(xy 60.589157 -349.155004) (xy 68.345048 -349.155004) (xy 68.349119 -349.099382) (xy 68.361245 -349.044945)
			(xy 68.381168 -348.992854) (xy 68.408464 -348.944219) (xy 68.44255 -348.900076) (xy 68.482699 -348.861367)
			(xy 68.528057 -348.828916) (xy 68.577657 -348.803415) (xy 68.630441 -348.785408) (xy 68.685284 -348.775278)
			(xy 68.741018 -348.773241) (xy 68.796455 -348.779341) (xy 68.850412 -348.793447) (xy 68.901741 -348.815259)
			(xy 68.949347 -348.844313) (xy 68.992215 -348.879988) (xy 69.029432 -348.921525) (xy 69.060205 -348.968038)
			(xy 69.083877 -349.018535) (xy 69.099945 -349.071942) (xy 69.108065 -349.127118) (xy 69.108574 -349.155004)
			(xy 69.108161 -349.17761) (xy 69.48119 -349.17761) (xy 69.485261 -349.121988) (xy 69.497387 -349.067551)
			(xy 69.51731 -349.01546) (xy 69.544606 -348.966825) (xy 69.578692 -348.922682) (xy 69.618841 -348.883973)
			(xy 69.664199 -348.851522) (xy 69.713799 -348.826021) (xy 69.766583 -348.808014) (xy 69.821426 -348.797884)
			(xy 69.87716 -348.795847) (xy 69.932597 -348.801947) (xy 69.986554 -348.816053) (xy 70.037883 -348.837865)
			(xy 70.085489 -348.866919) (xy 70.128357 -348.902594) (xy 70.165574 -348.944131) (xy 70.196347 -348.990644)
			(xy 70.220019 -349.041141) (xy 70.236087 -349.094548) (xy 70.241881 -349.133922) (xy 70.615554 -349.133922)
			(xy 70.619625 -349.0783) (xy 70.631751 -349.023863) (xy 70.651674 -348.971772) (xy 70.67897 -348.923137)
			(xy 70.713056 -348.878994) (xy 70.753205 -348.840285) (xy 70.798563 -348.807834) (xy 70.848163 -348.782333)
			(xy 70.900947 -348.764326) (xy 70.95579 -348.754196) (xy 71.011524 -348.752159) (xy 71.066961 -348.758259)
			(xy 71.120918 -348.772365) (xy 71.172247 -348.794177) (xy 71.219853 -348.823231) (xy 71.262721 -348.858906)
			(xy 71.299938 -348.900443) (xy 71.330711 -348.946956) (xy 71.354383 -348.997453) (xy 71.370451 -349.05086)
			(xy 71.378571 -349.106036) (xy 71.37908 -349.133922) (xy 71.379075 -349.134176) (xy 71.814942 -349.134176)
			(xy 71.819013 -349.078554) (xy 71.831139 -349.024117) (xy 71.851062 -348.972026) (xy 71.878358 -348.923391)
			(xy 71.912444 -348.879248) (xy 71.952593 -348.840539) (xy 71.997951 -348.808088) (xy 72.047551 -348.782587)
			(xy 72.100335 -348.76458) (xy 72.155178 -348.75445) (xy 72.210912 -348.752413) (xy 72.266349 -348.758513)
			(xy 72.320306 -348.772619) (xy 72.371635 -348.794431) (xy 72.419241 -348.823485) (xy 72.462109 -348.85916)
			(xy 72.499326 -348.900697) (xy 72.530099 -348.94721) (xy 72.553771 -348.997707) (xy 72.569839 -349.051114)
			(xy 72.577959 -349.10629) (xy 72.578468 -349.134176) (xy 72.577959 -349.162062) (xy 72.569839 -349.217238)
			(xy 72.553771 -349.270645) (xy 72.530099 -349.321142) (xy 72.499326 -349.367655) (xy 72.462109 -349.409192)
			(xy 72.419241 -349.444867) (xy 72.371635 -349.473921) (xy 72.320306 -349.495733) (xy 72.266349 -349.509839)
			(xy 72.210912 -349.515939) (xy 72.155178 -349.513902) (xy 72.100335 -349.503772) (xy 72.047551 -349.485765)
			(xy 71.997951 -349.460264) (xy 71.952593 -349.427813) (xy 71.912444 -349.389104) (xy 71.878358 -349.344961)
			(xy 71.851062 -349.296326) (xy 71.831139 -349.244235) (xy 71.819013 -349.189798) (xy 71.814942 -349.134176)
			(xy 71.379075 -349.134176) (xy 71.378571 -349.161808) (xy 71.370451 -349.216984) (xy 71.354383 -349.270391)
			(xy 71.330711 -349.320888) (xy 71.299938 -349.367401) (xy 71.262721 -349.408938) (xy 71.219853 -349.444613)
			(xy 71.172247 -349.473667) (xy 71.120918 -349.495479) (xy 71.066961 -349.509585) (xy 71.011524 -349.515685)
			(xy 70.95579 -349.513648) (xy 70.900947 -349.503518) (xy 70.848163 -349.485511) (xy 70.798563 -349.46001)
			(xy 70.753205 -349.427559) (xy 70.713056 -349.38885) (xy 70.67897 -349.344707) (xy 70.651674 -349.296072)
			(xy 70.631751 -349.243981) (xy 70.619625 -349.189544) (xy 70.615554 -349.133922) (xy 70.241881 -349.133922)
			(xy 70.244207 -349.149724) (xy 70.244716 -349.17761) (xy 70.244207 -349.205496) (xy 70.236087 -349.260672)
			(xy 70.220019 -349.314079) (xy 70.196347 -349.364576) (xy 70.165574 -349.411089) (xy 70.128357 -349.452626)
			(xy 70.085489 -349.488301) (xy 70.037883 -349.517355) (xy 69.986554 -349.539167) (xy 69.932597 -349.553273)
			(xy 69.896218 -349.557276) (xy 88.871407 -349.557276) (xy 88.875298 -349.502924) (xy 88.886885 -349.449679)
			(xy 88.905932 -349.398625) (xy 88.932051 -349.350802) (xy 88.964711 -349.307183) (xy 89.003246 -349.268656)
			(xy 89.046873 -349.236006) (xy 89.094702 -349.209897) (xy 89.14576 -349.190861) (xy 89.199007 -349.179286)
			(xy 89.25336 -349.175407) (xy 89.307712 -349.179303) (xy 89.360956 -349.190895) (xy 89.412008 -349.209947)
			(xy 89.459828 -349.236071) (xy 89.481914 -349.252032) (xy 89.500926 -349.265628) (xy 89.542809 -349.28636)
			(xy 89.587777 -349.299086) (xy 89.634314 -349.303376) (xy 89.680851 -349.299086) (xy 89.725819 -349.28636)
			(xy 89.767702 -349.265628) (xy 89.786714 -349.252032) (xy 89.808764 -349.236019) (xy 89.856591 -349.209896)
			(xy 89.907649 -349.190845) (xy 89.960899 -349.179254) (xy 90.015256 -349.17536) (xy 90.069614 -349.179241)
			(xy 90.122866 -349.19082) (xy 90.173929 -349.209859) (xy 90.221761 -349.235972) (xy 90.265391 -349.268626)
			(xy 90.303929 -349.307157) (xy 90.336592 -349.350781) (xy 90.362713 -349.39861) (xy 90.381761 -349.449668)
			(xy 90.393349 -349.502919) (xy 90.39724 -349.557276) (xy 91.863 -349.557276) (xy 91.866891 -349.502922)
			(xy 91.878479 -349.449676) (xy 91.897526 -349.398621) (xy 91.923647 -349.350796) (xy 91.956308 -349.307176)
			(xy 91.994844 -349.268648) (xy 92.038472 -349.235997) (xy 92.086303 -349.209889) (xy 92.137363 -349.190853)
			(xy 92.190612 -349.179278) (xy 92.244967 -349.1754) (xy 92.29932 -349.179297) (xy 92.352565 -349.190891)
			(xy 92.403618 -349.209944) (xy 92.45144 -349.23607) (xy 92.473526 -349.252032) (xy 92.492538 -349.265628)
			(xy 92.534421 -349.28636) (xy 92.579389 -349.299086) (xy 92.625926 -349.303376) (xy 92.672463 -349.299086)
			(xy 92.717431 -349.28636) (xy 92.759314 -349.265628) (xy 92.778326 -349.252032) (xy 92.800376 -349.23602)
			(xy 92.848202 -349.209899) (xy 92.899259 -349.190849) (xy 92.952507 -349.17926) (xy 93.006863 -349.175367)
			(xy 93.061219 -349.179249) (xy 93.11447 -349.190828) (xy 93.16553 -349.209868) (xy 93.213361 -349.23598)
			(xy 93.256989 -349.268634) (xy 93.295526 -349.307164) (xy 93.328187 -349.350787) (xy 93.354307 -349.398614)
			(xy 93.373355 -349.449672) (xy 93.384942 -349.50292) (xy 93.388833 -349.557276) (xy 93.384949 -349.611632)
			(xy 93.373368 -349.664882) (xy 93.354327 -349.715942) (xy 93.328213 -349.763772) (xy 93.295557 -349.807399)
			(xy 93.257026 -349.845935) (xy 93.213402 -349.878594) (xy 93.165574 -349.904712) (xy 93.114516 -349.923758)
			(xy 93.061267 -349.935344) (xy 93.006911 -349.939233) (xy 92.952555 -349.935347) (xy 92.899305 -349.923764)
			(xy 92.848246 -349.904721) (xy 92.800416 -349.878606) (xy 92.778326 -349.862648) (xy 92.759314 -349.849052)
			(xy 92.717431 -349.82832) (xy 92.672463 -349.815594) (xy 92.625926 -349.811304) (xy 92.579389 -349.815594)
			(xy 92.534421 -349.82832) (xy 92.492538 -349.849052) (xy 92.473526 -349.862648) (xy 92.4514 -349.878556)
			(xy 92.403575 -349.904676) (xy 92.352519 -349.923723) (xy 92.299273 -349.93531) (xy 92.244919 -349.9392)
			(xy 92.190565 -349.935315) (xy 92.137317 -349.923734) (xy 92.086259 -349.904692) (xy 92.038432 -349.878577)
			(xy 91.994808 -349.84592) (xy 91.956276 -349.807388) (xy 91.923621 -349.763764) (xy 91.897506 -349.715936)
			(xy 91.878465 -349.664878) (xy 91.866884 -349.61163) (xy 91.863 -349.557276) (xy 90.39724 -349.557276)
			(xy 90.393356 -349.611634) (xy 90.381775 -349.664885) (xy 90.362733 -349.715947) (xy 90.336618 -349.763778)
			(xy 90.303961 -349.807406) (xy 90.265427 -349.845943) (xy 90.221802 -349.878602) (xy 90.173972 -349.904721)
			(xy 90.122912 -349.923767) (xy 90.069661 -349.935352) (xy 90.015304 -349.93924) (xy 89.960946 -349.935353)
			(xy 89.907695 -349.923769) (xy 89.856635 -349.904724) (xy 89.808805 -349.878607) (xy 89.786714 -349.862648)
			(xy 89.767702 -349.849052) (xy 89.725819 -349.82832) (xy 89.680851 -349.815594) (xy 89.634314 -349.811304)
			(xy 89.587777 -349.815594) (xy 89.542809 -349.82832) (xy 89.500926 -349.849052) (xy 89.481914 -349.862648)
			(xy 89.459788 -349.878555) (xy 89.411964 -349.904673) (xy 89.360909 -349.923718) (xy 89.307664 -349.935304)
			(xy 89.253312 -349.939193) (xy 89.19896 -349.935307) (xy 89.145714 -349.923725) (xy 89.094658 -349.904683)
			(xy 89.046832 -349.878568) (xy 89.00321 -349.845913) (xy 88.96468 -349.807381) (xy 88.932025 -349.763758)
			(xy 88.905912 -349.715931) (xy 88.886872 -349.664875) (xy 88.875291 -349.611629) (xy 88.871407 -349.557276)
			(xy 69.896218 -349.557276) (xy 69.87716 -349.559373) (xy 69.821426 -349.557336) (xy 69.766583 -349.547206)
			(xy 69.713799 -349.529199) (xy 69.664199 -349.503698) (xy 69.618841 -349.471247) (xy 69.578692 -349.432538)
			(xy 69.544606 -349.388395) (xy 69.51731 -349.33976) (xy 69.497387 -349.287669) (xy 69.485261 -349.233232)
			(xy 69.48119 -349.17761) (xy 69.108161 -349.17761) (xy 69.108065 -349.18289) (xy 69.099945 -349.238066)
			(xy 69.083877 -349.291473) (xy 69.060205 -349.34197) (xy 69.029432 -349.388483) (xy 68.992215 -349.43002)
			(xy 68.949347 -349.465695) (xy 68.901741 -349.494749) (xy 68.850412 -349.516561) (xy 68.796455 -349.530667)
			(xy 68.741018 -349.536767) (xy 68.685284 -349.53473) (xy 68.630441 -349.5246) (xy 68.577657 -349.506593)
			(xy 68.528057 -349.481092) (xy 68.482699 -349.448641) (xy 68.44255 -349.409932) (xy 68.408464 -349.365789)
			(xy 68.381168 -349.317154) (xy 68.361245 -349.265063) (xy 68.349119 -349.210626) (xy 68.345048 -349.155004)
			(xy 60.589157 -349.155004) (xy 60.35548 -349.388684) (xy 47.65675 -349.388684) (xy 46.239515 -350.805919)
			(xy 47.574698 -350.805919) (xy 47.574698 -350.724809) (xy 47.582648 -350.64409) (xy 47.598471 -350.564539)
			(xy 47.622016 -350.486923) (xy 47.653055 -350.411987) (xy 47.69129 -350.340455) (xy 47.736352 -350.273015)
			(xy 47.787807 -350.210316) (xy 47.84516 -350.152963) (xy 47.907859 -350.101508) (xy 47.975299 -350.056446)
			(xy 48.046831 -350.018211) (xy 48.121767 -349.987172) (xy 48.199383 -349.963627) (xy 48.278934 -349.947804)
			(xy 48.359653 -349.939854) (xy 48.440763 -349.939854) (xy 48.521482 -349.947804) (xy 48.601033 -349.963627)
			(xy 48.678649 -349.987172) (xy 48.753585 -350.018211) (xy 48.825117 -350.056446) (xy 48.892557 -350.101508)
			(xy 48.955256 -350.152963) (xy 49.012609 -350.210316) (xy 49.064064 -350.273015) (xy 49.109126 -350.340455)
			(xy 49.147361 -350.411987) (xy 49.1784 -350.486923) (xy 49.201945 -350.564539) (xy 49.217768 -350.64409)
			(xy 49.225718 -350.724809) (xy 49.226216 -350.765364) (xy 49.225718 -350.805919) (xy 51.074818 -350.805919)
			(xy 51.074818 -350.724809) (xy 51.082768 -350.64409) (xy 51.098591 -350.564539) (xy 51.122136 -350.486923)
			(xy 51.153175 -350.411987) (xy 51.19141 -350.340455) (xy 51.236472 -350.273015) (xy 51.287927 -350.210316)
			(xy 51.34528 -350.152963) (xy 51.407979 -350.101508) (xy 51.475419 -350.056446) (xy 51.546951 -350.018211)
			(xy 51.621887 -349.987172) (xy 51.699503 -349.963627) (xy 51.779054 -349.947804) (xy 51.859773 -349.939854)
			(xy 51.940883 -349.939854) (xy 52.021602 -349.947804) (xy 52.101153 -349.963627) (xy 52.178769 -349.987172)
			(xy 52.253705 -350.018211) (xy 52.325237 -350.056446) (xy 52.392677 -350.101508) (xy 52.455376 -350.152963)
			(xy 52.512729 -350.210316) (xy 52.564184 -350.273015) (xy 52.609246 -350.340455) (xy 52.647481 -350.411987)
			(xy 52.67852 -350.486923) (xy 52.702065 -350.564539) (xy 52.717888 -350.64409) (xy 52.725838 -350.724809)
			(xy 52.726336 -350.765364) (xy 52.725838 -350.805919) (xy 52.717888 -350.886638) (xy 52.702065 -350.966189)
			(xy 52.67852 -351.043805) (xy 52.647481 -351.118741) (xy 52.609246 -351.190273) (xy 52.564184 -351.257713)
			(xy 52.512729 -351.320412) (xy 52.455376 -351.377765) (xy 52.392677 -351.42922) (xy 52.325237 -351.474282)
			(xy 52.253705 -351.512517) (xy 52.178769 -351.543556) (xy 52.101153 -351.567101) (xy 52.021602 -351.582924)
			(xy 51.940883 -351.590874) (xy 51.859773 -351.590874) (xy 51.779054 -351.582924) (xy 51.699503 -351.567101)
			(xy 51.621887 -351.543556) (xy 51.546951 -351.512517) (xy 51.475419 -351.474282) (xy 51.407979 -351.42922)
			(xy 51.34528 -351.377765) (xy 51.287927 -351.320412) (xy 51.236472 -351.257713) (xy 51.19141 -351.190273)
			(xy 51.153175 -351.118741) (xy 51.122136 -351.043805) (xy 51.098591 -350.966189) (xy 51.082768 -350.886638)
			(xy 51.074818 -350.805919) (xy 49.225718 -350.805919) (xy 49.217768 -350.886638) (xy 49.201945 -350.966189)
			(xy 49.1784 -351.043805) (xy 49.147361 -351.118741) (xy 49.109126 -351.190273) (xy 49.064064 -351.257713)
			(xy 49.012609 -351.320412) (xy 48.955256 -351.377765) (xy 48.892557 -351.42922) (xy 48.825117 -351.474282)
			(xy 48.753585 -351.512517) (xy 48.678649 -351.543556) (xy 48.601033 -351.567101) (xy 48.521482 -351.582924)
			(xy 48.440763 -351.590874) (xy 48.359653 -351.590874) (xy 48.278934 -351.582924) (xy 48.199383 -351.567101)
			(xy 48.121767 -351.543556) (xy 48.046831 -351.512517) (xy 47.975299 -351.474282) (xy 47.907859 -351.42922)
			(xy 47.84516 -351.377765) (xy 47.787807 -351.320412) (xy 47.736352 -351.257713) (xy 47.69129 -351.190273)
			(xy 47.653055 -351.118741) (xy 47.622016 -351.043805) (xy 47.598471 -350.966189) (xy 47.582648 -350.886638)
			(xy 47.574698 -350.805919) (xy 46.239515 -350.805919) (xy 44.795186 -352.250248) (xy 44.773537 -352.250678)
			(xy 44.730863 -352.258005) (xy 44.690049 -352.272462) (xy 44.652278 -352.293629) (xy 44.618643 -352.320894)
			(xy 44.590117 -352.353468) (xy 44.567528 -352.390406) (xy 44.551528 -352.43064) (xy 44.542583 -352.473004)
			(xy 44.54095 -352.516272) (xy 44.543472 -352.537776) (xy 46.483524 -354.477828) (xy 89.811606 -354.477828)
			(xy 94.4753 -349.814134) (xy 94.4753 -347.03766) (xy 94.84106 -346.6719) (xy 94.848426 -346.66047)
			(xy 94.863602 -346.637862) (xy 94.899344 -346.596784) (xy 94.940561 -346.561204) (xy 94.986418 -346.531844)
			(xy 95.035982 -346.5093) (xy 95.088247 -346.494029) (xy 95.142152 -346.486343) (xy 95.196602 -346.486397)
			(xy 95.250492 -346.49419) (xy 95.302727 -346.509563) (xy 95.352246 -346.532206) (xy 95.398044 -346.561657)
			(xy 95.439191 -346.597318) (xy 95.474852 -346.638467) (xy 95.504301 -346.684266) (xy 95.526941 -346.733786)
			(xy 95.542313 -346.786021) (xy 95.550104 -346.839911) (xy 95.550156 -346.894362) (xy 95.542468 -346.948267)
			(xy 95.527196 -347.000531) (xy 95.50465 -347.050094) (xy 95.475288 -347.09595) (xy 95.439706 -347.137166)
			(xy 95.398627 -347.172906) (xy 95.375984 -347.188028) (xy 95.364554 -347.195394) (xy 95.215456 -347.344492)
			(xy 95.215456 -350.120966) (xy 90.118438 -355.217984) (xy 87.459312 -355.217984) (xy 87.442365 -355.231475)
			(xy 87.412896 -355.26322) (xy 87.389239 -355.299503) (xy 87.372081 -355.339274) (xy 87.361918 -355.38138)
			(xy 87.359045 -355.424599) (xy 87.363546 -355.467678) (xy 87.37529 -355.50937) (xy 87.393936 -355.548466)
			(xy 87.418944 -355.583831) (xy 87.433912 -355.599492) (xy 87.482934 -355.648514) (xy 87.51443 -355.657404)
			(xy 87.540797 -355.665488) (xy 87.591054 -355.688192) (xy 87.637519 -355.717894) (xy 87.679226 -355.753974)
			(xy 87.715306 -355.795681) (xy 87.745008 -355.842146) (xy 87.767712 -355.892403) (xy 87.775796 -355.91877)
			(xy 87.784686 -355.950266) (xy 88.279986 -356.445566) (xy 88.296086 -356.461003) (xy 88.332646 -356.486547)
			(xy 88.373104 -356.505317) (xy 88.416217 -356.516739) (xy 88.460661 -356.520461) (xy 88.505073 -356.516368)
			(xy 88.548089 -356.504588) (xy 88.588389 -356.485481) (xy 88.624735 -356.459633) (xy 88.656013 -356.427839)
			(xy 88.681261 -356.391074) (xy 88.699706 -356.350467) (xy 88.70569 -356.32898) (xy 88.71305 -356.302258)
			(xy 88.734433 -356.251123) (xy 88.762989 -356.20362) (xy 88.798118 -356.160749) (xy 88.83908 -356.123411)
			(xy 88.885013 -356.092393) (xy 88.934951 -356.068348) (xy 88.987842 -356.05178) (xy 89.042574 -356.04304)
			(xy 89.097995 -356.04231) (xy 89.152938 -356.049607) (xy 89.206247 -356.064776) (xy 89.256801 -356.087499)
			(xy 89.303534 -356.117298) (xy 89.345465 -356.153544) (xy 89.38171 -356.195476) (xy 89.411507 -356.242211)
			(xy 89.434228 -356.292765) (xy 89.449396 -356.346075) (xy 89.456691 -356.401018) (xy 89.455959 -356.456439)
			(xy 89.447217 -356.51117) (xy 89.430648 -356.564061) (xy 89.4066 -356.613998) (xy 89.375581 -356.65993)
			(xy 89.338242 -356.700891) (xy 89.295369 -356.736018) (xy 89.247865 -356.764573) (xy 89.19673 -356.785954)
			(xy 89.170002 -356.793292) (xy 89.14851 -356.799268) (xy 89.107888 -356.817695) (xy 89.071108 -356.842933)
			(xy 89.039301 -356.874206) (xy 89.013444 -356.910553) (xy 88.994332 -356.950857) (xy 88.982553 -356.993879)
			(xy 88.978468 -357.038298) (xy 88.982203 -357.082747) (xy 88.993643 -357.125861) (xy 89.012436 -357.166315)
			(xy 89.038006 -357.202864) (xy 89.053416 -357.218996) (xy 91.711018 -359.876598) (xy 91.721399 -359.886474)
			(xy 91.745642 -359.901736) (xy 91.772675 -359.911217) (xy 91.801141 -359.91444) (xy 91.815412 -359.913174)
			(xy 91.82989 -359.911396) (xy 91.83624 -359.909872) (xy 91.872921 -359.902244) (xy 91.947371 -359.893823)
			(xy 92.022293 -359.893268) (xy 92.096859 -359.900586) (xy 92.170245 -359.915695) (xy 92.241637 -359.938428)
			(xy 92.310247 -359.968534) (xy 92.375316 -360.00568) (xy 92.436122 -360.049454) (xy 92.491995 -360.099373)
			(xy 92.542316 -360.154885) (xy 92.586528 -360.215375) (xy 92.624142 -360.280173) (xy 92.654741 -360.348565)
			(xy 92.677989 -360.419791) (xy 92.693626 -360.493066) (xy 92.701481 -360.567578) (xy 92.701466 -360.642502)
			(xy 92.693582 -360.717011) (xy 92.677916 -360.790279) (xy 92.654641 -360.861497) (xy 92.624014 -360.929876)
			(xy 92.586374 -360.99466) (xy 92.542139 -361.055132) (xy 92.491796 -361.110624) (xy 92.435904 -361.160521)
			(xy 92.37508 -361.204272) (xy 92.309997 -361.241392) (xy 92.241375 -361.271471) (xy 92.20581 -361.28325)
			(xy 92.163138 -361.295442) (xy 92.120466 -361.30611) (xy 92.067126 -361.37469) (xy 92.067126 -362.37545)
			(xy 92.120466 -362.44403) (xy 92.163138 -362.454698) (xy 92.199471 -362.464313) (xy 92.270041 -362.49018)
			(xy 92.337492 -362.523339) (xy 92.401072 -362.563423) (xy 92.460074 -362.609983) (xy 92.513841 -362.662503)
			(xy 92.561773 -362.720397) (xy 92.603337 -362.783019) (xy 92.6211 -362.81614) (xy 92.639231 -362.852143)
			(xy 92.668166 -362.927385) (xy 92.688406 -363.005416) (xy 92.699691 -363.085236) (xy 92.701364 -363.125512)
			(xy 92.701826 -363.147826) (xy 92.700299 -363.192436) (xy 92.698316 -363.214666) (xy 92.693744 -363.255371)
			(xy 92.676432 -363.335435) (xy 92.650031 -363.412978) (xy 92.614892 -363.486972) (xy 92.593668 -363.522006)
			(xy 92.579237 -363.544622) (xy 92.547452 -363.587848) (xy 92.530168 -363.608366) (xy 92.506426 -363.635336)
			(xy 92.454369 -363.684867) (xy 92.397586 -363.728903) (xy 92.367354 -363.74832) (xy 92.35396 -363.757253)
			(xy 92.331812 -363.780607) (xy 92.316216 -363.808761) (xy 92.308163 -363.839923) (xy 92.307664 -363.856016)
			(xy 92.307664 -363.86008) (xy 93.154506 -363.86008) (xy 93.158522 -363.74381) (xy 93.170549 -363.628095)
			(xy 93.190531 -363.513485) (xy 93.218373 -363.400526) (xy 93.253942 -363.289758) (xy 93.297068 -363.181707)
			(xy 93.347545 -363.076889) (xy 93.405134 -362.975804) (xy 93.46956 -362.878932) (xy 93.540515 -362.786736)
			(xy 93.617662 -362.699655) (xy 93.700633 -362.618104) (xy 93.789033 -362.542472) (xy 93.88244 -362.473118)
			(xy 93.980409 -362.410375) (xy 94.082473 -362.354539) (xy 94.188147 -362.305878) (xy 94.296926 -362.264624)
			(xy 94.408291 -362.230973) (xy 94.521714 -362.205085) (xy 94.636651 -362.187084) (xy 94.752557 -362.177055)
			(xy 94.868879 -362.175047) (xy 94.985062 -362.181069) (xy 95.100553 -362.195092) (xy 95.214801 -362.21705)
			(xy 95.327262 -362.246837) (xy 95.4374 -362.284312) (xy 95.54469 -362.329297) (xy 95.648621 -362.381576)
			(xy 95.748697 -362.440901) (xy 95.844443 -362.506989) (xy 95.9354 -362.579525) (xy 96.021136 -362.658164)
			(xy 96.101243 -362.74253) (xy 96.175339 -362.832222) (xy 96.243069 -362.926812) (xy 96.304113 -363.02585)
			(xy 96.358178 -363.128863) (xy 96.405008 -363.23536) (xy 96.444379 -363.344835) (xy 96.476103 -363.456765)
			(xy 96.500029 -363.570617) (xy 96.516043 -363.685849) (xy 96.52407 -363.801911) (xy 96.524572 -363.86008)
			(xy 96.52407 -363.918249) (xy 96.516043 -364.034311) (xy 96.500029 -364.149543) (xy 96.476103 -364.263395)
			(xy 96.444379 -364.375325) (xy 96.405008 -364.4848) (xy 96.358178 -364.591297) (xy 96.304113 -364.69431)
			(xy 96.243069 -364.793348) (xy 96.175339 -364.887938) (xy 96.101243 -364.97763) (xy 96.021136 -365.061996)
			(xy 95.9354 -365.140635) (xy 95.844443 -365.213171) (xy 95.748697 -365.279259) (xy 95.648621 -365.338584)
			(xy 95.54469 -365.390863) (xy 95.4374 -365.435848) (xy 95.327262 -365.473323) (xy 95.214801 -365.50311)
			(xy 95.100553 -365.525068) (xy 94.985062 -365.539091) (xy 94.868879 -365.545113) (xy 94.752557 -365.543105)
			(xy 94.636651 -365.533076) (xy 94.521714 -365.515075) (xy 94.408291 -365.489187) (xy 94.296926 -365.455536)
			(xy 94.188147 -365.414282) (xy 94.082473 -365.365621) (xy 93.980409 -365.309785) (xy 93.88244 -365.247042)
			(xy 93.789033 -365.177688) (xy 93.700633 -365.102056) (xy 93.617662 -365.020505) (xy 93.540515 -364.933424)
			(xy 93.46956 -364.841228) (xy 93.405134 -364.744356) (xy 93.347545 -364.643271) (xy 93.297068 -364.538453)
			(xy 93.253942 -364.430402) (xy 93.218373 -364.319634) (xy 93.190531 -364.206675) (xy 93.170549 -364.092065)
			(xy 93.158522 -363.97635) (xy 93.154506 -363.86008) (xy 92.307664 -363.86008) (xy 92.307664 -364.712758)
			(xy 91.507056 -365.513366) (xy 91.406472 -365.614204) (xy 90.841576 -366.1791) (xy 84.953602 -366.1791)
			(xy 84.90712 -366.132618) (xy 84.890936 -366.117045) (xy 84.854149 -366.091284) (xy 84.813409 -366.072384)
			(xy 84.769983 -366.060932) (xy 84.725221 -366.057286) (xy 84.680515 -366.061557) (xy 84.637253 -366.073614)
			(xy 84.596781 -366.093081) (xy 84.560358 -366.119353) (xy 84.529114 -366.151614) (xy 84.504022 -366.188861)
			(xy 84.485861 -366.229935) (xy 84.475197 -366.273561) (xy 84.473288 -366.29594) (xy 84.473288 -375.61012)
			(xy 86.877404 -375.61012) (xy 86.881424 -375.419469) (xy 86.893478 -375.229156) (xy 86.913544 -375.039521)
			(xy 86.941587 -374.8509) (xy 86.977556 -374.66363) (xy 87.021388 -374.478042) (xy 87.073005 -374.294467)
			(xy 87.132315 -374.113231) (xy 87.199213 -373.934656) (xy 87.273579 -373.759061) (xy 87.355281 -373.586756)
			(xy 87.444175 -373.418049) (xy 87.540101 -373.253239) (xy 87.64289 -373.09262) (xy 87.752359 -372.936477)
			(xy 87.868313 -372.785088) (xy 87.990547 -372.638721) (xy 88.118841 -372.497637) (xy 88.252969 -372.362088)
			(xy 88.392693 -372.232313) (xy 88.537763 -372.108543) (xy 88.687921 -371.991) (xy 88.842902 -371.879891)
			(xy 89.002429 -371.775414) (xy 89.166218 -371.677755) (xy 89.333978 -371.587088) (xy 89.505412 -371.503574)
			(xy 89.680214 -371.427361) (xy 89.858073 -371.358585) (xy 90.038674 -371.297367) (xy 90.221694 -371.243818)
			(xy 90.40681 -371.198032) (xy 90.593691 -371.16009) (xy 90.782006 -371.130061) (xy 90.971419 -371.107996)
			(xy 91.161593 -371.093937) (xy 91.352192 -371.087907) (xy 91.542875 -371.089917) (xy 91.733304 -371.099964)
			(xy 91.92314 -371.11803) (xy 92.112046 -371.144083) (xy 92.299685 -371.178076) (xy 92.485725 -371.219949)
			(xy 92.669834 -371.269628) (xy 92.851685 -371.327024) (xy 93.030955 -371.392035) (xy 93.207325 -371.464546)
			(xy 93.380481 -371.544427) (xy 93.550116 -371.631537) (xy 93.715928 -371.725721) (xy 93.877622 -371.826812)
			(xy 94.03491 -371.934628) (xy 94.187513 -372.04898) (xy 94.335161 -372.169663) (xy 94.477589 -372.296464)
			(xy 94.614545 -372.429155) (xy 94.745786 -372.567503) (xy 94.871078 -372.71126) (xy 94.990198 -372.860171)
			(xy 95.102934 -373.013972) (xy 95.209087 -373.172388) (xy 95.308467 -373.335139) (xy 95.400897 -373.501934)
			(xy 95.486214 -373.672478) (xy 95.564266 -373.846466) (xy 95.634913 -374.023591) (xy 95.698031 -374.203536)
			(xy 95.753507 -374.385982) (xy 95.801242 -374.570605) (xy 95.841152 -374.757075) (xy 95.873165 -374.945063)
			(xy 95.897225 -375.134233) (xy 95.913288 -375.324249) (xy 95.921327 -375.514773) (xy 95.92183 -375.61012)
			(xy 95.921327 -375.705467) (xy 95.913288 -375.895991) (xy 95.897225 -376.086007) (xy 95.873165 -376.275177)
			(xy 95.841152 -376.463165) (xy 95.801242 -376.649635) (xy 95.753507 -376.834258) (xy 95.698031 -377.016704)
			(xy 95.634913 -377.196649) (xy 95.564266 -377.373774) (xy 95.486214 -377.547762) (xy 95.400897 -377.718306)
			(xy 95.308467 -377.885101) (xy 95.209087 -378.047852) (xy 95.102934 -378.206268) (xy 94.990198 -378.360069)
			(xy 94.871078 -378.50898) (xy 94.745786 -378.652737) (xy 94.614545 -378.791085) (xy 94.477589 -378.923776)
			(xy 94.335161 -379.050577) (xy 94.187513 -379.17126) (xy 94.03491 -379.285612) (xy 93.877622 -379.393428)
			(xy 93.715928 -379.494519) (xy 93.550116 -379.588703) (xy 93.380481 -379.675813) (xy 93.207325 -379.755694)
			(xy 93.030955 -379.828205) (xy 92.851685 -379.893216) (xy 92.669834 -379.950612) (xy 92.485725 -380.000291)
			(xy 92.299685 -380.042164) (xy 92.112046 -380.076157) (xy 91.92314 -380.10221) (xy 91.733304 -380.120276)
			(xy 91.542875 -380.130323) (xy 91.352192 -380.132333) (xy 91.161593 -380.126303) (xy 90.971419 -380.112244)
			(xy 90.782006 -380.090179) (xy 90.593691 -380.06015) (xy 90.40681 -380.022208) (xy 90.221694 -379.976422)
			(xy 90.038674 -379.922873) (xy 89.858073 -379.861655) (xy 89.680214 -379.792879) (xy 89.505412 -379.716666)
			(xy 89.333978 -379.633152) (xy 89.166218 -379.542485) (xy 89.002429 -379.444826) (xy 88.842902 -379.340349)
			(xy 88.687921 -379.22924) (xy 88.537763 -379.111697) (xy 88.392693 -378.987927) (xy 88.252969 -378.858152)
			(xy 88.118841 -378.722603) (xy 87.990547 -378.581519) (xy 87.868313 -378.435152) (xy 87.752359 -378.283763)
			(xy 87.64289 -378.12762) (xy 87.540101 -377.967001) (xy 87.444175 -377.802191) (xy 87.355281 -377.633484)
			(xy 87.273579 -377.461179) (xy 87.199213 -377.285584) (xy 87.132315 -377.107009) (xy 87.073005 -376.925773)
			(xy 87.021388 -376.742198) (xy 86.977556 -376.55661) (xy 86.941587 -376.36934) (xy 86.913544 -376.180719)
			(xy 86.893478 -375.991084) (xy 86.881424 -375.800771) (xy 86.877404 -375.61012) (xy 84.473288 -375.61012)
			(xy 84.473288 -397.259556) (xy 84.77631 -397.562578) (xy 84.807806 -397.571468) (xy 84.834172 -397.579551)
			(xy 84.884428 -397.602256) (xy 84.930892 -397.631958) (xy 84.972596 -397.668039) (xy 85.008672 -397.709748)
			(xy 85.038368 -397.756216) (xy 85.054273 -397.791432) (xy 93.046548 -397.791432) (xy 93.050619 -397.73581)
			(xy 93.062745 -397.681373) (xy 93.082668 -397.629282) (xy 93.109964 -397.580647) (xy 93.14405 -397.536504)
			(xy 93.184199 -397.497795) (xy 93.229557 -397.465344) (xy 93.279157 -397.439843) (xy 93.331941 -397.421836)
			(xy 93.386784 -397.411706) (xy 93.442518 -397.409669) (xy 93.497955 -397.415769) (xy 93.551912 -397.429875)
			(xy 93.603241 -397.451687) (xy 93.650847 -397.480741) (xy 93.693715 -397.516416) (xy 93.730932 -397.557953)
			(xy 93.761705 -397.604466) (xy 93.785377 -397.654963) (xy 93.801445 -397.70837) (xy 93.809565 -397.763546)
			(xy 93.810074 -397.791432) (xy 93.809565 -397.819318) (xy 93.801445 -397.874494) (xy 93.785377 -397.927901)
			(xy 93.761705 -397.978398) (xy 93.730932 -398.024911) (xy 93.693715 -398.066448) (xy 93.650847 -398.102123)
			(xy 93.603241 -398.131177) (xy 93.551912 -398.152989) (xy 93.497955 -398.167095) (xy 93.442518 -398.173195)
			(xy 93.386784 -398.171158) (xy 93.331941 -398.161028) (xy 93.279157 -398.143021) (xy 93.229557 -398.11752)
			(xy 93.184199 -398.085069) (xy 93.14405 -398.04636) (xy 93.109964 -398.002217) (xy 93.082668 -397.953582)
			(xy 93.062745 -397.901491) (xy 93.050619 -397.847054) (xy 93.046548 -397.791432) (xy 85.054273 -397.791432)
			(xy 85.061066 -397.806474) (xy 85.069172 -397.832834) (xy 85.078062 -397.86433) (xy 86.04123 -398.827498)
			(xy 88.190322 -398.827498) (xy 88.194393 -398.771876) (xy 88.206519 -398.717439) (xy 88.226442 -398.665348)
			(xy 88.253738 -398.616713) (xy 88.287824 -398.57257) (xy 88.327973 -398.533861) (xy 88.373331 -398.50141)
			(xy 88.422931 -398.475909) (xy 88.475715 -398.457902) (xy 88.530558 -398.447772) (xy 88.586292 -398.445735)
			(xy 88.641729 -398.451835) (xy 88.695686 -398.465941) (xy 88.747015 -398.487753) (xy 88.763903 -398.49806)
			(xy 91.314776 -398.49806) (xy 91.318847 -398.442438) (xy 91.330973 -398.388001) (xy 91.350896 -398.33591)
			(xy 91.378192 -398.287275) (xy 91.412278 -398.243132) (xy 91.452427 -398.204423) (xy 91.497785 -398.171972)
			(xy 91.547385 -398.146471) (xy 91.600169 -398.128464) (xy 91.655012 -398.118334) (xy 91.710746 -398.116297)
			(xy 91.766183 -398.122397) (xy 91.82014 -398.136503) (xy 91.871469 -398.158315) (xy 91.919075 -398.187369)
			(xy 91.961943 -398.223044) (xy 91.99916 -398.264581) (xy 92.029933 -398.311094) (xy 92.053605 -398.361591)
			(xy 92.069673 -398.414998) (xy 92.077793 -398.470174) (xy 92.078302 -398.49806) (xy 92.077793 -398.525946)
			(xy 92.069673 -398.581122) (xy 92.053605 -398.634529) (xy 92.029933 -398.685026) (xy 91.99916 -398.731539)
			(xy 91.961943 -398.773076) (xy 91.919075 -398.808751) (xy 91.871469 -398.837805) (xy 91.82014 -398.859617)
			(xy 91.766183 -398.873723) (xy 91.710746 -398.879823) (xy 91.655012 -398.877786) (xy 91.600169 -398.867656)
			(xy 91.547385 -398.849649) (xy 91.497785 -398.824148) (xy 91.452427 -398.791697) (xy 91.412278 -398.752988)
			(xy 91.378192 -398.708845) (xy 91.350896 -398.66021) (xy 91.330973 -398.608119) (xy 91.318847 -398.553682)
			(xy 91.314776 -398.49806) (xy 88.763903 -398.49806) (xy 88.794621 -398.516807) (xy 88.837489 -398.552482)
			(xy 88.874706 -398.594019) (xy 88.905479 -398.640532) (xy 88.929151 -398.691029) (xy 88.945219 -398.744436)
			(xy 88.953339 -398.799612) (xy 88.953848 -398.827498) (xy 88.953339 -398.855384) (xy 88.945219 -398.91056)
			(xy 88.929151 -398.963967) (xy 88.905479 -399.014464) (xy 88.894234 -399.03146) (xy 89.880438 -399.03146)
			(xy 89.884509 -398.975838) (xy 89.896635 -398.921401) (xy 89.916558 -398.86931) (xy 89.943854 -398.820675)
			(xy 89.97794 -398.776532) (xy 90.018089 -398.737823) (xy 90.063447 -398.705372) (xy 90.113047 -398.679871)
			(xy 90.165831 -398.661864) (xy 90.220674 -398.651734) (xy 90.276408 -398.649697) (xy 90.331845 -398.655797)
			(xy 90.385802 -398.669903) (xy 90.437131 -398.691715) (xy 90.484737 -398.720769) (xy 90.527605 -398.756444)
			(xy 90.564822 -398.797981) (xy 90.595595 -398.844494) (xy 90.619267 -398.894991) (xy 90.635335 -398.948398)
			(xy 90.643455 -399.003574) (xy 90.643964 -399.03146) (xy 90.643455 -399.059346) (xy 90.635335 -399.114522)
			(xy 90.619267 -399.167929) (xy 90.595595 -399.218426) (xy 90.564822 -399.264939) (xy 90.527605 -399.306476)
			(xy 90.484737 -399.342151) (xy 90.437131 -399.371205) (xy 90.385802 -399.393017) (xy 90.331845 -399.407123)
			(xy 90.276408 -399.413223) (xy 90.220674 -399.411186) (xy 90.165831 -399.401056) (xy 90.113047 -399.383049)
			(xy 90.063447 -399.357548) (xy 90.018089 -399.325097) (xy 89.97794 -399.286388) (xy 89.943854 -399.242245)
			(xy 89.916558 -399.19361) (xy 89.896635 -399.141519) (xy 89.884509 -399.087082) (xy 89.880438 -399.03146)
			(xy 88.894234 -399.03146) (xy 88.874706 -399.060977) (xy 88.837489 -399.102514) (xy 88.794621 -399.138189)
			(xy 88.747015 -399.167243) (xy 88.695686 -399.189055) (xy 88.641729 -399.203161) (xy 88.586292 -399.209261)
			(xy 88.530558 -399.207224) (xy 88.475715 -399.197094) (xy 88.422931 -399.179087) (xy 88.373331 -399.153586)
			(xy 88.327973 -399.121135) (xy 88.287824 -399.082426) (xy 88.253738 -399.038283) (xy 88.226442 -398.989648)
			(xy 88.206519 -398.937557) (xy 88.194393 -398.88312) (xy 88.190322 -398.827498) (xy 86.04123 -398.827498)
			(xy 86.45779 -399.244058) (xy 86.474171 -399.259738) (xy 86.511412 -399.285602) (xy 86.552653 -399.304443)
			(xy 86.596584 -399.315662) (xy 86.641809 -399.318902) (xy 86.68689 -399.31406) (xy 86.730396 -399.301291)
			(xy 86.770943 -399.281001) (xy 86.807243 -399.253833) (xy 86.838143 -399.220651) (xy 86.86266 -399.18251)
			(xy 86.87181 -399.161762) (xy 86.882923 -399.136342) (xy 86.911423 -399.088745) (xy 86.946515 -399.045777)
			(xy 86.987461 -399.008345) (xy 87.033395 -398.977236) (xy 87.083351 -398.953108) (xy 87.136274 -398.936469)
			(xy 87.191049 -398.92767) (xy 87.24652 -398.926896) (xy 87.301519 -398.934164) (xy 87.354886 -398.94932)
			(xy 87.405495 -398.972045) (xy 87.45228 -399.00186) (xy 87.494253 -399.038136) (xy 87.530531 -399.080108)
			(xy 87.560347 -399.126891) (xy 87.583075 -399.1775) (xy 87.598233 -399.230866) (xy 87.605503 -399.285864)
			(xy 87.604731 -399.341336) (xy 87.595934 -399.396111) (xy 87.579297 -399.449035) (xy 87.555171 -399.498992)
			(xy 87.524065 -399.544928) (xy 87.486634 -399.585874) (xy 87.443667 -399.620969) (xy 87.396072 -399.64947)
			(xy 87.370666 -399.660618) (xy 87.349925 -399.669772) (xy 87.31181 -399.694311) (xy 87.278652 -399.725222)
			(xy 87.251504 -399.761524) (xy 87.231226 -399.802067) (xy 87.218461 -399.845564) (xy 87.213615 -399.890636)
			(xy 87.216842 -399.935852) (xy 87.228038 -399.979779) (xy 87.246849 -400.021023) (xy 87.272679 -400.058276)
			(xy 87.28837 -400.074638) (xy 87.324944 -400.111214) (xy 88.072212 -400.111214) (xy 88.076283 -400.055592)
			(xy 88.088409 -400.001155) (xy 88.108332 -399.949064) (xy 88.135628 -399.900429) (xy 88.169714 -399.856286)
			(xy 88.209863 -399.817577) (xy 88.255221 -399.785126) (xy 88.304821 -399.759625) (xy 88.357605 -399.741618)
			(xy 88.412448 -399.731488) (xy 88.468182 -399.729451) (xy 88.523619 -399.735551) (xy 88.577576 -399.749657)
			(xy 88.628905 -399.771469) (xy 88.676511 -399.800523) (xy 88.719379 -399.836198) (xy 88.756596 -399.877735)
			(xy 88.787369 -399.924248) (xy 88.811041 -399.974745) (xy 88.827109 -400.028152) (xy 88.835229 -400.083328)
			(xy 88.835738 -400.111214) (xy 88.835229 -400.1391) (xy 88.827109 -400.194276) (xy 88.811041 -400.247683)
			(xy 88.787369 -400.29818) (xy 88.756596 -400.344693) (xy 88.719379 -400.38623) (xy 88.676511 -400.421905)
			(xy 88.628905 -400.450959) (xy 88.577576 -400.472771) (xy 88.523619 -400.486877) (xy 88.468182 -400.492977)
			(xy 88.412448 -400.49094) (xy 88.357605 -400.48081) (xy 88.304821 -400.462803) (xy 88.255221 -400.437302)
			(xy 88.209863 -400.404851) (xy 88.169714 -400.366142) (xy 88.135628 -400.321999) (xy 88.108332 -400.273364)
			(xy 88.088409 -400.221273) (xy 88.076283 -400.166836) (xy 88.072212 -400.111214) (xy 87.324944 -400.111214)
			(xy 91.41206 -404.198582) (xy 91.41206 -404.34768) (xy 91.4125 -404.36279) (xy 91.419625 -404.392158)
			(xy 91.433456 -404.419027) (xy 91.453218 -404.44189) (xy 91.477802 -404.459465) (xy 91.505829 -404.470766)
			(xy 91.535728 -404.47516) (xy 91.565821 -404.472399) (xy 91.594422 -404.46264) (xy 91.607386 -404.454868)
			(xy 91.640961 -404.434086) (xy 91.711828 -404.399254) (xy 91.786116 -404.372482) (xy 91.862912 -404.354101)
			(xy 91.902026 -404.348696) (xy 91.940838 -404.344401) (xy 92.018921 -404.3433) (xy 92.096655 -404.350755)
			(xy 92.173106 -404.366676) (xy 92.247354 -404.390872) (xy 92.318507 -404.42305) (xy 92.385709 -404.462826)
			(xy 92.448152 -404.50972) (xy 92.505085 -404.563168) (xy 92.555825 -404.622529) (xy 92.599761 -404.687088)
			(xy 92.61856 -404.721314) (xy 92.63442 -404.75206) (xy 92.660782 -404.816026) (xy 92.680805 -404.882251)
			(xy 92.694301 -404.950107) (xy 92.701143 -405.018954) (xy 92.701618 -405.053546) (xy 92.701187 -405.09198)
			(xy 92.69307 -405.168416) (xy 92.676764 -405.243533) (xy 92.652458 -405.316455) (xy 92.620435 -405.386333)
			(xy 92.581068 -405.452353) (xy 92.534815 -405.513746) (xy 92.482217 -405.569797) (xy 92.423884 -405.619854)
			(xy 92.360496 -405.663333) (xy 92.292792 -405.699728) (xy 92.221561 -405.728615) (xy 92.184728 -405.7396)
			(xy 92.153815 -405.748043) (xy 92.090854 -405.759999) (xy 92.058998 -405.763476) (xy 92.035757 -405.766283)
			(xy 91.990792 -405.779288) (xy 91.948968 -405.800305) (xy 91.911698 -405.828624) (xy 91.880244 -405.863288)
			(xy 91.855669 -405.903125) (xy 91.838802 -405.946789) (xy 91.830215 -405.992802) (xy 91.829636 -406.016206)
			(xy 91.829636 -406.633934) (xy 91.830165 -406.657344) (xy 91.838733 -406.703374) (xy 91.855592 -406.747055)
			(xy 91.880169 -406.786906) (xy 91.911634 -406.821578) (xy 91.948919 -406.849897) (xy 91.990763 -406.870903)
			(xy 92.035747 -406.883886) (xy 92.058998 -406.886664) (xy 92.096445 -406.8908) (xy 92.170243 -406.905973)
			(xy 92.242026 -406.928856) (xy 92.310991 -406.959194) (xy 92.376365 -406.996646) (xy 92.437417 -407.040794)
			(xy 92.493465 -407.091144) (xy 92.54388 -407.147132) (xy 92.5881 -407.208133) (xy 92.625629 -407.273463)
			(xy 92.656048 -407.342392) (xy 92.679015 -407.414148) (xy 92.694275 -407.487928) (xy 92.701656 -407.562908)
			(xy 92.701075 -407.638248) (xy 92.69254 -407.713105) (xy 92.676146 -407.786642) (xy 92.652076 -407.858036)
			(xy 92.620599 -407.926488) (xy 92.582069 -407.991232) (xy 92.536915 -408.051544) (xy 92.485642 -408.10675)
			(xy 92.428826 -408.15623) (xy 92.367101 -408.199433) (xy 92.301158 -408.235874) (xy 92.231734 -408.265145)
			(xy 92.159607 -408.28692) (xy 92.085584 -408.300954) (xy 92.048076 -408.304492) (xy 92.024556 -408.306958)
			(xy 92.013201 -408.31008) (xy 93.154506 -408.31008) (xy 93.158522 -408.19381) (xy 93.170549 -408.078095)
			(xy 93.190531 -407.963485) (xy 93.218373 -407.850526) (xy 93.253942 -407.739758) (xy 93.297068 -407.631707)
			(xy 93.347545 -407.526889) (xy 93.405134 -407.425804) (xy 93.46956 -407.328932) (xy 93.540515 -407.236736)
			(xy 93.617662 -407.149655) (xy 93.700633 -407.068104) (xy 93.789033 -406.992472) (xy 93.88244 -406.923118)
			(xy 93.980409 -406.860375) (xy 94.082473 -406.804539) (xy 94.188147 -406.755878) (xy 94.296926 -406.714624)
			(xy 94.408291 -406.680973) (xy 94.521714 -406.655085) (xy 94.636651 -406.637084) (xy 94.752557 -406.627055)
			(xy 94.868879 -406.625047) (xy 94.985062 -406.631069) (xy 95.100553 -406.645092) (xy 95.214801 -406.66705)
			(xy 95.327262 -406.696837) (xy 95.4374 -406.734312) (xy 95.54469 -406.779297) (xy 95.648621 -406.831576)
			(xy 95.748697 -406.890901) (xy 95.844443 -406.956989) (xy 95.9354 -407.029525) (xy 96.021136 -407.108164)
			(xy 96.101243 -407.19253) (xy 96.175339 -407.282222) (xy 96.243069 -407.376812) (xy 96.304113 -407.47585)
			(xy 96.358178 -407.578863) (xy 96.405008 -407.68536) (xy 96.444379 -407.794835) (xy 96.476103 -407.906765)
			(xy 96.500029 -408.020617) (xy 96.516043 -408.135849) (xy 96.52407 -408.251911) (xy 96.524572 -408.31008)
			(xy 96.52407 -408.368249) (xy 96.516043 -408.484311) (xy 96.500029 -408.599543) (xy 96.476103 -408.713395)
			(xy 96.444379 -408.825325) (xy 96.405008 -408.9348) (xy 96.358178 -409.041297) (xy 96.304113 -409.14431)
			(xy 96.243069 -409.243348) (xy 96.175339 -409.337938) (xy 96.101243 -409.42763) (xy 96.021136 -409.511996)
			(xy 95.9354 -409.590635) (xy 95.844443 -409.663171) (xy 95.748697 -409.729259) (xy 95.648621 -409.788584)
			(xy 95.54469 -409.840863) (xy 95.4374 -409.885848) (xy 95.327262 -409.923323) (xy 95.214801 -409.95311)
			(xy 95.100553 -409.975068) (xy 94.985062 -409.989091) (xy 94.868879 -409.995113) (xy 94.752557 -409.993105)
			(xy 94.636651 -409.983076) (xy 94.521714 -409.965075) (xy 94.408291 -409.939187) (xy 94.296926 -409.905536)
			(xy 94.188147 -409.864282) (xy 94.082473 -409.815621) (xy 93.980409 -409.759785) (xy 93.88244 -409.697042)
			(xy 93.789033 -409.627688) (xy 93.700633 -409.552056) (xy 93.617662 -409.470505) (xy 93.540515 -409.383424)
			(xy 93.46956 -409.291228) (xy 93.405134 -409.194356) (xy 93.347545 -409.093271) (xy 93.297068 -408.988453)
			(xy 93.253942 -408.880402) (xy 93.218373 -408.769634) (xy 93.190531 -408.656675) (xy 93.170549 -408.542065)
			(xy 93.158522 -408.42635) (xy 93.154506 -408.31008) (xy 92.013201 -408.31008) (xy 91.978961 -408.319494)
			(xy 91.936469 -408.34024) (xy 91.898542 -408.368482) (xy 91.866489 -408.403248) (xy 91.841414 -408.443338)
			(xy 91.82418 -408.487372) (xy 91.815381 -408.533833) (xy 91.814904 -408.557476) (xy 91.814904 -409.522676)
			(xy 91.491816 -409.845764) (xy 91.241626 -410.0957) (xy 86.421214 -410.0957) (xy 86.174072 -409.848812)
			(xy 85.918802 -409.593542) (xy 85.908417 -409.583677) (xy 85.884171 -409.568437) (xy 85.857141 -409.558978)
			(xy 85.828683 -409.555774) (xy 85.814408 -409.556966) (xy 85.79993 -409.558744) (xy 85.79358 -409.560268)
			(xy 85.757002 -409.56788) (xy 85.682759 -409.576303) (xy 85.608044 -409.576901) (xy 85.533676 -409.56967)
			(xy 85.460475 -409.554689) (xy 85.389246 -409.532122) (xy 85.320773 -409.502218) (xy 85.255809 -409.465306)
			(xy 85.19507 -409.421791) (xy 85.139222 -409.372154) (xy 85.088882 -409.316939) (xy 85.044602 -409.256755)
			(xy 85.00687 -409.192264) (xy 84.976102 -409.124175) (xy 84.952635 -409.053237) (xy 84.936728 -408.980232)
			(xy 84.928556 -408.905962) (xy 84.928209 -408.831244) (xy 84.935691 -408.756901) (xy 84.950919 -408.683751)
			(xy 84.973726 -408.612599) (xy 85.003861 -408.544227) (xy 85.040992 -408.479388) (xy 85.084711 -408.418796)
			(xy 85.134537 -408.363116) (xy 85.189921 -408.312962) (xy 85.219794 -408.290522) (xy 85.239217 -408.276579)
			(xy 85.279637 -408.251028) (xy 85.300566 -408.239468) (xy 85.320756 -408.227515) (xy 85.356757 -408.197435)
			(xy 85.386632 -408.161264) (xy 85.409368 -408.120228) (xy 85.424195 -408.075719) (xy 85.430609 -408.029246)
			(xy 85.428392 -407.982385) (xy 85.417621 -407.936724) (xy 85.39866 -407.893813) (xy 85.372152 -407.855106)
			(xy 85.355938 -407.838148) (xy 83.856068 -406.338278) (xy 83.856068 -405.309324) (xy 79.193898 -400.647154)
			(xy 79.162402 -400.63801) (xy 79.136202 -400.630004) (xy 79.086241 -400.607526) (xy 79.040009 -400.578134)
			(xy 78.998455 -400.542432) (xy 78.962433 -400.501155) (xy 78.932685 -400.455151) (xy 78.909821 -400.405366)
			(xy 78.894312 -400.352823) (xy 78.886476 -400.298602) (xy 78.886475 -400.243817) (xy 78.894308 -400.189596)
			(xy 78.909815 -400.137052) (xy 78.932676 -400.087265) (xy 78.962422 -400.04126) (xy 78.998441 -399.999981)
			(xy 79.039994 -399.964278) (xy 79.086225 -399.934883) (xy 79.136184 -399.912402) (xy 79.162402 -399.904458)
			(xy 79.193898 -399.895314) (xy 82.812128 -396.277084) (xy 82.812128 -360.820716) (xy 81.791556 -359.800144)
			(xy 41.675558 -359.800144) (xy 38.824154 -356.94874) (xy 24.901906 -356.94874) (xy 22.020276 -354.06711)
			(xy 22.003574 -354.052188) (xy 21.965973 -354.027864) (xy 21.924693 -354.010503) (xy 21.881009 -354.000642)
			(xy 21.836273 -353.998587) (xy 21.791869 -354.004401) (xy 21.749171 -354.017904) (xy 21.709498 -354.038678)
			(xy 21.674078 -354.066081) (xy 21.644006 -354.099265) (xy 21.620213 -354.137205) (xy 21.603434 -354.178725)
			(xy 21.594189 -354.222544) (xy 21.593048 -354.24491) (xy 21.593048 -358.233488) (xy 29.519874 -358.233488)
			(xy 29.519874 -358.146588) (xy 29.527892 -358.060059) (xy 29.54386 -357.974639) (xy 29.567641 -357.891057)
			(xy 29.599033 -357.810025) (xy 29.637767 -357.732236) (xy 29.683514 -357.658352) (xy 29.735883 -357.589005)
			(xy 29.794427 -357.524785) (xy 29.858647 -357.466241) (xy 29.927994 -357.413872) (xy 30.001878 -357.368125)
			(xy 30.079667 -357.329391) (xy 30.160699 -357.297999) (xy 30.244281 -357.274218) (xy 30.329701 -357.25825)
			(xy 30.41623 -357.250232) (xy 30.50313 -357.250232) (xy 30.589659 -357.25825) (xy 30.675079 -357.274218)
			(xy 30.758661 -357.297999) (xy 30.839693 -357.329391) (xy 30.917482 -357.368125) (xy 30.991366 -357.413872)
			(xy 31.060713 -357.466241) (xy 31.124933 -357.524785) (xy 31.183477 -357.589005) (xy 31.235846 -357.658352)
			(xy 31.281593 -357.732236) (xy 31.320327 -357.810025) (xy 31.351719 -357.891057) (xy 31.3755 -357.974639)
			(xy 31.391468 -358.060059) (xy 31.399486 -358.146588) (xy 31.399988 -358.190038) (xy 31.399486 -358.233488)
			(xy 34.599874 -358.233488) (xy 34.599874 -358.146588) (xy 34.607892 -358.060059) (xy 34.62386 -357.974639)
			(xy 34.647641 -357.891057) (xy 34.679033 -357.810025) (xy 34.717767 -357.732236) (xy 34.763514 -357.658352)
			(xy 34.815883 -357.589005) (xy 34.874427 -357.524785) (xy 34.938647 -357.466241) (xy 35.007994 -357.413872)
			(xy 35.081878 -357.368125) (xy 35.159667 -357.329391) (xy 35.240699 -357.297999) (xy 35.324281 -357.274218)
			(xy 35.409701 -357.25825) (xy 35.49623 -357.250232) (xy 35.58313 -357.250232) (xy 35.669659 -357.25825)
			(xy 35.755079 -357.274218) (xy 35.838661 -357.297999) (xy 35.919693 -357.329391) (xy 35.997482 -357.368125)
			(xy 36.071366 -357.413872) (xy 36.140713 -357.466241) (xy 36.204933 -357.524785) (xy 36.263477 -357.589005)
			(xy 36.315846 -357.658352) (xy 36.361593 -357.732236) (xy 36.400327 -357.810025) (xy 36.431719 -357.891057)
			(xy 36.4555 -357.974639) (xy 36.471468 -358.060059) (xy 36.479486 -358.146588) (xy 36.479988 -358.190038)
			(xy 36.479486 -358.233488) (xy 36.471468 -358.320017) (xy 36.4555 -358.405437) (xy 36.431719 -358.489019)
			(xy 36.400327 -358.570051) (xy 36.361593 -358.64784) (xy 36.315846 -358.721724) (xy 36.263477 -358.791071)
			(xy 36.204933 -358.855291) (xy 36.140713 -358.913835) (xy 36.071366 -358.966204) (xy 35.997482 -359.011951)
			(xy 35.919693 -359.050685) (xy 35.838661 -359.082077) (xy 35.755079 -359.105858) (xy 35.669659 -359.121826)
			(xy 35.58313 -359.129844) (xy 35.49623 -359.129844) (xy 35.409701 -359.121826) (xy 35.324281 -359.105858)
			(xy 35.240699 -359.082077) (xy 35.159667 -359.050685) (xy 35.081878 -359.011951) (xy 35.007994 -358.966204)
			(xy 34.938647 -358.913835) (xy 34.874427 -358.855291) (xy 34.815883 -358.791071) (xy 34.763514 -358.721724)
			(xy 34.717767 -358.64784) (xy 34.679033 -358.570051) (xy 34.647641 -358.489019) (xy 34.62386 -358.405437)
			(xy 34.607892 -358.320017) (xy 34.599874 -358.233488) (xy 31.399486 -358.233488) (xy 31.391468 -358.320017)
			(xy 31.3755 -358.405437) (xy 31.351719 -358.489019) (xy 31.320327 -358.570051) (xy 31.281593 -358.64784)
			(xy 31.235846 -358.721724) (xy 31.183477 -358.791071) (xy 31.124933 -358.855291) (xy 31.060713 -358.913835)
			(xy 30.991366 -358.966204) (xy 30.917482 -359.011951) (xy 30.839693 -359.050685) (xy 30.758661 -359.082077)
			(xy 30.675079 -359.105858) (xy 30.589659 -359.121826) (xy 30.50313 -359.129844) (xy 30.41623 -359.129844)
			(xy 30.329701 -359.121826) (xy 30.244281 -359.105858) (xy 30.160699 -359.082077) (xy 30.079667 -359.050685)
			(xy 30.001878 -359.011951) (xy 29.927994 -358.966204) (xy 29.858647 -358.913835) (xy 29.794427 -358.855291)
			(xy 29.735883 -358.791071) (xy 29.683514 -358.721724) (xy 29.637767 -358.64784) (xy 29.599033 -358.570051)
			(xy 29.567641 -358.489019) (xy 29.54386 -358.405437) (xy 29.527892 -358.320017) (xy 29.519874 -358.233488)
			(xy 21.593048 -358.233488) (xy 21.593048 -360.550968) (xy 24.465532 -360.550968) (xy 24.469603 -360.495346)
			(xy 24.481729 -360.440909) (xy 24.501652 -360.388818) (xy 24.528948 -360.340183) (xy 24.563034 -360.29604)
			(xy 24.603183 -360.257331) (xy 24.648541 -360.22488) (xy 24.698141 -360.199379) (xy 24.750925 -360.181372)
			(xy 24.805768 -360.171242) (xy 24.861502 -360.169205) (xy 24.916939 -360.175305) (xy 24.970896 -360.189411)
			(xy 25.022225 -360.211223) (xy 25.069831 -360.240277) (xy 25.112699 -360.275952) (xy 25.149916 -360.317489)
			(xy 25.180689 -360.364002) (xy 25.204361 -360.414499) (xy 25.220429 -360.467906) (xy 25.228549 -360.523082)
			(xy 25.229058 -360.550968) (xy 26.775916 -360.550968) (xy 26.779987 -360.495346) (xy 26.792113 -360.440909)
			(xy 26.812036 -360.388818) (xy 26.839332 -360.340183) (xy 26.873418 -360.29604) (xy 26.913567 -360.257331)
			(xy 26.958925 -360.22488) (xy 27.008525 -360.199379) (xy 27.061309 -360.181372) (xy 27.116152 -360.171242)
			(xy 27.171886 -360.169205) (xy 27.227323 -360.175305) (xy 27.28128 -360.189411) (xy 27.332609 -360.211223)
			(xy 27.380215 -360.240277) (xy 27.423083 -360.275952) (xy 27.4603 -360.317489) (xy 27.491073 -360.364002)
			(xy 27.514745 -360.414499) (xy 27.530813 -360.467906) (xy 27.538933 -360.523082) (xy 27.539442 -360.550968)
			(xy 27.538933 -360.578854) (xy 27.530813 -360.63403) (xy 27.514745 -360.687437) (xy 27.491073 -360.737934)
			(xy 27.46755 -360.773488) (xy 29.519874 -360.773488) (xy 29.519874 -360.686588) (xy 29.527892 -360.600059)
			(xy 29.54386 -360.514639) (xy 29.567641 -360.431057) (xy 29.599033 -360.350025) (xy 29.637767 -360.272236)
			(xy 29.683514 -360.198352) (xy 29.735883 -360.129005) (xy 29.794427 -360.064785) (xy 29.858647 -360.006241)
			(xy 29.927994 -359.953872) (xy 30.001878 -359.908125) (xy 30.079667 -359.869391) (xy 30.160699 -359.837999)
			(xy 30.244281 -359.814218) (xy 30.329701 -359.79825) (xy 30.41623 -359.790232) (xy 30.50313 -359.790232)
			(xy 30.589659 -359.79825) (xy 30.675079 -359.814218) (xy 30.758661 -359.837999) (xy 30.839693 -359.869391)
			(xy 30.917482 -359.908125) (xy 30.991366 -359.953872) (xy 31.060713 -360.006241) (xy 31.124933 -360.064785)
			(xy 31.183477 -360.129005) (xy 31.235846 -360.198352) (xy 31.281593 -360.272236) (xy 31.320327 -360.350025)
			(xy 31.351719 -360.431057) (xy 31.3755 -360.514639) (xy 31.391468 -360.600059) (xy 31.399486 -360.686588)
			(xy 31.399988 -360.730038) (xy 31.399486 -360.773488) (xy 34.599874 -360.773488) (xy 34.599874 -360.686588)
			(xy 34.607892 -360.600059) (xy 34.62386 -360.514639) (xy 34.647641 -360.431057) (xy 34.679033 -360.350025)
			(xy 34.717767 -360.272236) (xy 34.763514 -360.198352) (xy 34.815883 -360.129005) (xy 34.874427 -360.064785)
			(xy 34.938647 -360.006241) (xy 35.007994 -359.953872) (xy 35.081878 -359.908125) (xy 35.159667 -359.869391)
			(xy 35.240699 -359.837999) (xy 35.324281 -359.814218) (xy 35.409701 -359.79825) (xy 35.49623 -359.790232)
			(xy 35.58313 -359.790232) (xy 35.669659 -359.79825) (xy 35.755079 -359.814218) (xy 35.838661 -359.837999)
			(xy 35.919693 -359.869391) (xy 35.997482 -359.908125) (xy 36.071366 -359.953872) (xy 36.140713 -360.006241)
			(xy 36.204933 -360.064785) (xy 36.263477 -360.129005) (xy 36.315846 -360.198352) (xy 36.361593 -360.272236)
			(xy 36.400327 -360.350025) (xy 36.431719 -360.431057) (xy 36.4555 -360.514639) (xy 36.471468 -360.600059)
			(xy 36.479486 -360.686588) (xy 36.479988 -360.730038) (xy 36.479486 -360.773488) (xy 36.471468 -360.860017)
			(xy 36.4555 -360.945437) (xy 36.431719 -361.029019) (xy 36.400327 -361.110051) (xy 36.361593 -361.18784)
			(xy 36.315846 -361.261724) (xy 36.263477 -361.331071) (xy 36.204933 -361.395291) (xy 36.140713 -361.453835)
			(xy 36.071366 -361.506204) (xy 35.997482 -361.551951) (xy 35.919693 -361.590685) (xy 35.838661 -361.622077)
			(xy 35.755079 -361.645858) (xy 35.669659 -361.661826) (xy 35.58313 -361.669844) (xy 35.49623 -361.669844)
			(xy 35.409701 -361.661826) (xy 35.324281 -361.645858) (xy 35.240699 -361.622077) (xy 35.159667 -361.590685)
			(xy 35.081878 -361.551951) (xy 35.007994 -361.506204) (xy 34.938647 -361.453835) (xy 34.874427 -361.395291)
			(xy 34.815883 -361.331071) (xy 34.763514 -361.261724) (xy 34.717767 -361.18784) (xy 34.679033 -361.110051)
			(xy 34.647641 -361.029019) (xy 34.62386 -360.945437) (xy 34.607892 -360.860017) (xy 34.599874 -360.773488)
			(xy 31.399486 -360.773488) (xy 31.391468 -360.860017) (xy 31.3755 -360.945437) (xy 31.351719 -361.029019)
			(xy 31.320327 -361.110051) (xy 31.281593 -361.18784) (xy 31.235846 -361.261724) (xy 31.183477 -361.331071)
			(xy 31.124933 -361.395291) (xy 31.060713 -361.453835) (xy 30.991366 -361.506204) (xy 30.917482 -361.551951)
			(xy 30.839693 -361.590685) (xy 30.758661 -361.622077) (xy 30.675079 -361.645858) (xy 30.589659 -361.661826)
			(xy 30.50313 -361.669844) (xy 30.41623 -361.669844) (xy 30.329701 -361.661826) (xy 30.244281 -361.645858)
			(xy 30.160699 -361.622077) (xy 30.079667 -361.590685) (xy 30.001878 -361.551951) (xy 29.927994 -361.506204)
			(xy 29.858647 -361.453835) (xy 29.794427 -361.395291) (xy 29.735883 -361.331071) (xy 29.683514 -361.261724)
			(xy 29.637767 -361.18784) (xy 29.599033 -361.110051) (xy 29.567641 -361.029019) (xy 29.54386 -360.945437)
			(xy 29.527892 -360.860017) (xy 29.519874 -360.773488) (xy 27.46755 -360.773488) (xy 27.4603 -360.784447)
			(xy 27.423083 -360.825984) (xy 27.380215 -360.861659) (xy 27.332609 -360.890713) (xy 27.28128 -360.912525)
			(xy 27.227323 -360.926631) (xy 27.171886 -360.932731) (xy 27.116152 -360.930694) (xy 27.061309 -360.920564)
			(xy 27.008525 -360.902557) (xy 26.958925 -360.877056) (xy 26.913567 -360.844605) (xy 26.873418 -360.805896)
			(xy 26.839332 -360.761753) (xy 26.812036 -360.713118) (xy 26.792113 -360.661027) (xy 26.779987 -360.60659)
			(xy 26.775916 -360.550968) (xy 25.229058 -360.550968) (xy 25.228549 -360.578854) (xy 25.220429 -360.63403)
			(xy 25.204361 -360.687437) (xy 25.180689 -360.737934) (xy 25.149916 -360.784447) (xy 25.112699 -360.825984)
			(xy 25.069831 -360.861659) (xy 25.022225 -360.890713) (xy 24.970896 -360.912525) (xy 24.916939 -360.926631)
			(xy 24.861502 -360.932731) (xy 24.805768 -360.930694) (xy 24.750925 -360.920564) (xy 24.698141 -360.902557)
			(xy 24.648541 -360.877056) (xy 24.603183 -360.844605) (xy 24.563034 -360.805896) (xy 24.528948 -360.761753)
			(xy 24.501652 -360.713118) (xy 24.481729 -360.661027) (xy 24.469603 -360.60659) (xy 24.465532 -360.550968)
			(xy 21.593048 -360.550968) (xy 21.593048 -361.78236) (xy 24.358344 -361.78236) (xy 24.362415 -361.726738)
			(xy 24.374541 -361.672301) (xy 24.394464 -361.62021) (xy 24.42176 -361.571575) (xy 24.455846 -361.527432)
			(xy 24.495995 -361.488723) (xy 24.541353 -361.456272) (xy 24.590953 -361.430771) (xy 24.643737 -361.412764)
			(xy 24.69858 -361.402634) (xy 24.754314 -361.400597) (xy 24.809751 -361.406697) (xy 24.863708 -361.420803)
			(xy 24.915037 -361.442615) (xy 24.962643 -361.471669) (xy 25.005511 -361.507344) (xy 25.042728 -361.548881)
			(xy 25.073501 -361.595394) (xy 25.097173 -361.645891) (xy 25.113241 -361.699298) (xy 25.121361 -361.754474)
			(xy 25.12187 -361.78236) (xy 25.121361 -361.810246) (xy 25.113241 -361.865422) (xy 25.097173 -361.918829)
			(xy 25.073501 -361.969326) (xy 25.042728 -362.015839) (xy 25.005511 -362.057376) (xy 24.962643 -362.093051)
			(xy 24.915037 -362.122105) (xy 24.863708 -362.143917) (xy 24.809751 -362.158023) (xy 24.754314 -362.164123)
			(xy 24.69858 -362.162086) (xy 24.643737 -362.151956) (xy 24.590953 -362.133949) (xy 24.541353 -362.108448)
			(xy 24.495995 -362.075997) (xy 24.455846 -362.037288) (xy 24.42176 -361.993145) (xy 24.394464 -361.94451)
			(xy 24.374541 -361.892419) (xy 24.362415 -361.837982) (xy 24.358344 -361.78236) (xy 21.593048 -361.78236)
			(xy 21.593048 -363.313488) (xy 29.519874 -363.313488) (xy 29.519874 -363.226588) (xy 29.527892 -363.140059)
			(xy 29.54386 -363.054639) (xy 29.567641 -362.971057) (xy 29.599033 -362.890025) (xy 29.637767 -362.812236)
			(xy 29.683514 -362.738352) (xy 29.735883 -362.669005) (xy 29.794427 -362.604785) (xy 29.858647 -362.546241)
			(xy 29.927994 -362.493872) (xy 30.001878 -362.448125) (xy 30.079667 -362.409391) (xy 30.160699 -362.377999)
			(xy 30.244281 -362.354218) (xy 30.329701 -362.33825) (xy 30.41623 -362.330232) (xy 30.50313 -362.330232)
			(xy 30.589659 -362.33825) (xy 30.675079 -362.354218) (xy 30.758661 -362.377999) (xy 30.839693 -362.409391)
			(xy 30.917482 -362.448125) (xy 30.991366 -362.493872) (xy 31.060713 -362.546241) (xy 31.124933 -362.604785)
			(xy 31.183477 -362.669005) (xy 31.235846 -362.738352) (xy 31.281593 -362.812236) (xy 31.320327 -362.890025)
			(xy 31.351719 -362.971057) (xy 31.3755 -363.054639) (xy 31.391468 -363.140059) (xy 31.399486 -363.226588)
			(xy 31.399988 -363.270038) (xy 31.399486 -363.313488) (xy 34.599874 -363.313488) (xy 34.599874 -363.226588)
			(xy 34.607892 -363.140059) (xy 34.62386 -363.054639) (xy 34.647641 -362.971057) (xy 34.679033 -362.890025)
			(xy 34.717767 -362.812236) (xy 34.763514 -362.738352) (xy 34.815883 -362.669005) (xy 34.874427 -362.604785)
			(xy 34.938647 -362.546241) (xy 35.007994 -362.493872) (xy 35.081878 -362.448125) (xy 35.159667 -362.409391)
			(xy 35.240699 -362.377999) (xy 35.324281 -362.354218) (xy 35.409701 -362.33825) (xy 35.49623 -362.330232)
			(xy 35.58313 -362.330232) (xy 35.669659 -362.33825) (xy 35.755079 -362.354218) (xy 35.838661 -362.377999)
			(xy 35.919693 -362.409391) (xy 35.997482 -362.448125) (xy 36.071366 -362.493872) (xy 36.092815 -362.51007)
			(xy 39.818564 -362.51007) (xy 39.819058 -362.452661) (xy 39.826902 -362.338113) (xy 39.842544 -362.224366)
			(xy 39.865911 -362.111952) (xy 39.896896 -362.001394) (xy 39.935352 -361.893209) (xy 39.981101 -361.7879)
			(xy 40.03393 -361.685958) (xy 40.093592 -361.587859) (xy 40.159809 -361.49406) (xy 40.232272 -361.404998)
			(xy 40.310645 -361.321089) (xy 40.39456 -361.242723) (xy 40.483627 -361.170266) (xy 40.577431 -361.104056)
			(xy 40.675535 -361.044402) (xy 40.777481 -360.991581) (xy 40.882793 -360.945839) (xy 40.990981 -360.907391)
			(xy 41.101541 -360.876415) (xy 41.213957 -360.853056) (xy 41.327705 -360.837423) (xy 41.442254 -360.829588)
			(xy 41.557072 -360.829588) (xy 41.671621 -360.837423) (xy 41.785369 -360.853056) (xy 41.897785 -360.876415)
			(xy 42.008345 -360.907391) (xy 42.116533 -360.945839) (xy 42.221845 -360.991581) (xy 42.323791 -361.044402)
			(xy 42.421895 -361.104056) (xy 42.501239 -361.16006) (xy 43.327577 -361.16006) (xy 43.331612 -361.084356)
			(xy 43.343671 -361.009511) (xy 43.363617 -360.93637) (xy 43.391224 -360.865765) (xy 43.42618 -360.798494)
			(xy 43.468088 -360.735319) (xy 43.516474 -360.676957) (xy 43.57079 -360.624069) (xy 43.630419 -360.577254)
			(xy 43.694687 -360.537042) (xy 43.762864 -360.50389) (xy 43.83418 -360.478172) (xy 43.907825 -360.46018)
			(xy 43.982965 -360.450118) (xy 44.058749 -360.448099) (xy 44.134319 -360.454148) (xy 44.208817 -360.468195)
			(xy 44.2814 -360.490081) (xy 44.351246 -360.519558) (xy 44.417563 -360.556293) (xy 44.479599 -360.599868)
			(xy 44.536652 -360.64979) (xy 44.588076 -360.705494) (xy 44.633287 -360.766349) (xy 44.671774 -360.831664)
			(xy 44.7031 -360.9007) (xy 44.72691 -360.972675) (xy 44.742935 -361.046773) (xy 44.750994 -361.122154)
			(xy 44.751498 -361.16006) (xy 45.867577 -361.16006) (xy 45.871612 -361.084356) (xy 45.883671 -361.009511)
			(xy 45.903617 -360.93637) (xy 45.931224 -360.865765) (xy 45.96618 -360.798494) (xy 46.008088 -360.735319)
			(xy 46.056474 -360.676957) (xy 46.11079 -360.624069) (xy 46.170419 -360.577254) (xy 46.234687 -360.537042)
			(xy 46.302864 -360.50389) (xy 46.37418 -360.478172) (xy 46.447825 -360.46018) (xy 46.522965 -360.450118)
			(xy 46.598749 -360.448099) (xy 46.674319 -360.454148) (xy 46.748817 -360.468195) (xy 46.8214 -360.490081)
			(xy 46.891246 -360.519558) (xy 46.957563 -360.556293) (xy 47.019599 -360.599868) (xy 47.076652 -360.64979)
			(xy 47.128076 -360.705494) (xy 47.173287 -360.766349) (xy 47.211774 -360.831664) (xy 47.2431 -360.9007)
			(xy 47.26691 -360.972675) (xy 47.282935 -361.046773) (xy 47.290994 -361.122154) (xy 47.291498 -361.16006)
			(xy 48.407577 -361.16006) (xy 48.411612 -361.084356) (xy 48.423671 -361.009511) (xy 48.443617 -360.93637)
			(xy 48.471224 -360.865765) (xy 48.50618 -360.798494) (xy 48.548088 -360.735319) (xy 48.596474 -360.676957)
			(xy 48.65079 -360.624069) (xy 48.710419 -360.577254) (xy 48.774687 -360.537042) (xy 48.842864 -360.50389)
			(xy 48.91418 -360.478172) (xy 48.987825 -360.46018) (xy 49.062965 -360.450118) (xy 49.138749 -360.448099)
			(xy 49.214319 -360.454148) (xy 49.288817 -360.468195) (xy 49.3614 -360.490081) (xy 49.431246 -360.519558)
			(xy 49.497563 -360.556293) (xy 49.559599 -360.599868) (xy 49.616652 -360.64979) (xy 49.668076 -360.705494)
			(xy 49.713287 -360.766349) (xy 49.751774 -360.831664) (xy 49.7831 -360.9007) (xy 49.80691 -360.972675)
			(xy 49.822935 -361.046773) (xy 49.830994 -361.122154) (xy 49.831498 -361.16006) (xy 50.947577 -361.16006)
			(xy 50.951612 -361.084356) (xy 50.963671 -361.009511) (xy 50.983617 -360.93637) (xy 51.011224 -360.865765)
			(xy 51.04618 -360.798494) (xy 51.088088 -360.735319) (xy 51.136474 -360.676957) (xy 51.19079 -360.624069)
			(xy 51.250419 -360.577254) (xy 51.314687 -360.537042) (xy 51.382864 -360.50389) (xy 51.45418 -360.478172)
			(xy 51.527825 -360.46018) (xy 51.602965 -360.450118) (xy 51.678749 -360.448099) (xy 51.754319 -360.454148)
			(xy 51.828817 -360.468195) (xy 51.9014 -360.490081) (xy 51.971246 -360.519558) (xy 52.037563 -360.556293)
			(xy 52.099599 -360.599868) (xy 52.156652 -360.64979) (xy 52.208076 -360.705494) (xy 52.253287 -360.766349)
			(xy 52.291774 -360.831664) (xy 52.3231 -360.9007) (xy 52.34691 -360.972675) (xy 52.362935 -361.046773)
			(xy 52.370994 -361.122154) (xy 52.371498 -361.16006) (xy 53.487577 -361.16006) (xy 53.491612 -361.084356)
			(xy 53.503671 -361.009511) (xy 53.523617 -360.93637) (xy 53.551224 -360.865765) (xy 53.58618 -360.798494)
			(xy 53.628088 -360.735319) (xy 53.676474 -360.676957) (xy 53.73079 -360.624069) (xy 53.790419 -360.577254)
			(xy 53.854687 -360.537042) (xy 53.922864 -360.50389) (xy 53.99418 -360.478172) (xy 54.067825 -360.46018)
			(xy 54.142965 -360.450118) (xy 54.218749 -360.448099) (xy 54.294319 -360.454148) (xy 54.368817 -360.468195)
			(xy 54.4414 -360.490081) (xy 54.511246 -360.519558) (xy 54.577563 -360.556293) (xy 54.639599 -360.599868)
			(xy 54.696652 -360.64979) (xy 54.748076 -360.705494) (xy 54.793287 -360.766349) (xy 54.831774 -360.831664)
			(xy 54.8631 -360.9007) (xy 54.88691 -360.972675) (xy 54.902935 -361.046773) (xy 54.910994 -361.122154)
			(xy 54.911498 -361.16006) (xy 56.027577 -361.16006) (xy 56.031612 -361.084356) (xy 56.043671 -361.009511)
			(xy 56.063617 -360.93637) (xy 56.091224 -360.865765) (xy 56.12618 -360.798494) (xy 56.168088 -360.735319)
			(xy 56.216474 -360.676957) (xy 56.27079 -360.624069) (xy 56.330419 -360.577254) (xy 56.394687 -360.537042)
			(xy 56.462864 -360.50389) (xy 56.53418 -360.478172) (xy 56.607825 -360.46018) (xy 56.682965 -360.450118)
			(xy 56.758749 -360.448099) (xy 56.834319 -360.454148) (xy 56.908817 -360.468195) (xy 56.9814 -360.490081)
			(xy 57.051246 -360.519558) (xy 57.117563 -360.556293) (xy 57.179599 -360.599868) (xy 57.236652 -360.64979)
			(xy 57.288076 -360.705494) (xy 57.333287 -360.766349) (xy 57.371774 -360.831664) (xy 57.4031 -360.9007)
			(xy 57.42691 -360.972675) (xy 57.442935 -361.046773) (xy 57.450994 -361.122154) (xy 57.451498 -361.16006)
			(xy 58.567577 -361.16006) (xy 58.571612 -361.084356) (xy 58.583671 -361.009511) (xy 58.603617 -360.93637)
			(xy 58.631224 -360.865765) (xy 58.66618 -360.798494) (xy 58.708088 -360.735319) (xy 58.756474 -360.676957)
			(xy 58.81079 -360.624069) (xy 58.870419 -360.577254) (xy 58.934687 -360.537042) (xy 59.002864 -360.50389)
			(xy 59.07418 -360.478172) (xy 59.147825 -360.46018) (xy 59.222965 -360.450118) (xy 59.298749 -360.448099)
			(xy 59.374319 -360.454148) (xy 59.448817 -360.468195) (xy 59.5214 -360.490081) (xy 59.591246 -360.519558)
			(xy 59.657563 -360.556293) (xy 59.719599 -360.599868) (xy 59.776652 -360.64979) (xy 59.828076 -360.705494)
			(xy 59.873287 -360.766349) (xy 59.911774 -360.831664) (xy 59.9431 -360.9007) (xy 59.96691 -360.972675)
			(xy 59.982935 -361.046773) (xy 59.990994 -361.122154) (xy 59.991498 -361.16006) (xy 61.107577 -361.16006)
			(xy 61.111612 -361.084356) (xy 61.123671 -361.009511) (xy 61.143617 -360.93637) (xy 61.171224 -360.865765)
			(xy 61.20618 -360.798494) (xy 61.248088 -360.735319) (xy 61.296474 -360.676957) (xy 61.35079 -360.624069)
			(xy 61.410419 -360.577254) (xy 61.474687 -360.537042) (xy 61.542864 -360.50389) (xy 61.61418 -360.478172)
			(xy 61.687825 -360.46018) (xy 61.762965 -360.450118) (xy 61.838749 -360.448099) (xy 61.914319 -360.454148)
			(xy 61.988817 -360.468195) (xy 62.0614 -360.490081) (xy 62.131246 -360.519558) (xy 62.197563 -360.556293)
			(xy 62.259599 -360.599868) (xy 62.316652 -360.64979) (xy 62.368076 -360.705494) (xy 62.413287 -360.766349)
			(xy 62.451774 -360.831664) (xy 62.4831 -360.9007) (xy 62.50691 -360.972675) (xy 62.522935 -361.046773)
			(xy 62.530994 -361.122154) (xy 62.531498 -361.16006) (xy 62.530994 -361.197966) (xy 62.522935 -361.273347)
			(xy 62.50691 -361.347445) (xy 62.4831 -361.41942) (xy 62.451774 -361.488456) (xy 62.413287 -361.553771)
			(xy 62.368076 -361.614626) (xy 62.316652 -361.67033) (xy 62.259599 -361.720252) (xy 62.197563 -361.763827)
			(xy 62.131246 -361.800562) (xy 62.0614 -361.830039) (xy 61.988817 -361.851925) (xy 61.914319 -361.865972)
			(xy 61.838749 -361.872021) (xy 61.762965 -361.870002) (xy 61.687825 -361.85994) (xy 61.61418 -361.841948)
			(xy 61.542864 -361.81623) (xy 61.474687 -361.783078) (xy 61.410419 -361.742866) (xy 61.35079 -361.696051)
			(xy 61.296474 -361.643163) (xy 61.248088 -361.584801) (xy 61.20618 -361.521626) (xy 61.171224 -361.454355)
			(xy 61.143617 -361.38375) (xy 61.123671 -361.310609) (xy 61.111612 -361.235764) (xy 61.107577 -361.16006)
			(xy 59.991498 -361.16006) (xy 59.990994 -361.197966) (xy 59.982935 -361.273347) (xy 59.96691 -361.347445)
			(xy 59.9431 -361.41942) (xy 59.911774 -361.488456) (xy 59.873287 -361.553771) (xy 59.828076 -361.614626)
			(xy 59.776652 -361.67033) (xy 59.719599 -361.720252) (xy 59.657563 -361.763827) (xy 59.591246 -361.800562)
			(xy 59.5214 -361.830039) (xy 59.448817 -361.851925) (xy 59.374319 -361.865972) (xy 59.298749 -361.872021)
			(xy 59.222965 -361.870002) (xy 59.147825 -361.85994) (xy 59.07418 -361.841948) (xy 59.002864 -361.81623)
			(xy 58.934687 -361.783078) (xy 58.870419 -361.742866) (xy 58.81079 -361.696051) (xy 58.756474 -361.643163)
			(xy 58.708088 -361.584801) (xy 58.66618 -361.521626) (xy 58.631224 -361.454355) (xy 58.603617 -361.38375)
			(xy 58.583671 -361.310609) (xy 58.571612 -361.235764) (xy 58.567577 -361.16006) (xy 57.451498 -361.16006)
			(xy 57.450994 -361.197966) (xy 57.442935 -361.273347) (xy 57.42691 -361.347445) (xy 57.4031 -361.41942)
			(xy 57.371774 -361.488456) (xy 57.333287 -361.553771) (xy 57.288076 -361.614626) (xy 57.236652 -361.67033)
			(xy 57.179599 -361.720252) (xy 57.117563 -361.763827) (xy 57.051246 -361.800562) (xy 56.9814 -361.830039)
			(xy 56.908817 -361.851925) (xy 56.834319 -361.865972) (xy 56.758749 -361.872021) (xy 56.682965 -361.870002)
			(xy 56.607825 -361.85994) (xy 56.53418 -361.841948) (xy 56.462864 -361.81623) (xy 56.394687 -361.783078)
			(xy 56.330419 -361.742866) (xy 56.27079 -361.696051) (xy 56.216474 -361.643163) (xy 56.168088 -361.584801)
			(xy 56.12618 -361.521626) (xy 56.091224 -361.454355) (xy 56.063617 -361.38375) (xy 56.043671 -361.310609)
			(xy 56.031612 -361.235764) (xy 56.027577 -361.16006) (xy 54.911498 -361.16006) (xy 54.910994 -361.197966)
			(xy 54.902935 -361.273347) (xy 54.88691 -361.347445) (xy 54.8631 -361.41942) (xy 54.831774 -361.488456)
			(xy 54.793287 -361.553771) (xy 54.748076 -361.614626) (xy 54.696652 -361.67033) (xy 54.639599 -361.720252)
			(xy 54.577563 -361.763827) (xy 54.511246 -361.800562) (xy 54.4414 -361.830039) (xy 54.368817 -361.851925)
			(xy 54.294319 -361.865972) (xy 54.218749 -361.872021) (xy 54.142965 -361.870002) (xy 54.067825 -361.85994)
			(xy 53.99418 -361.841948) (xy 53.922864 -361.81623) (xy 53.854687 -361.783078) (xy 53.790419 -361.742866)
			(xy 53.73079 -361.696051) (xy 53.676474 -361.643163) (xy 53.628088 -361.584801) (xy 53.58618 -361.521626)
			(xy 53.551224 -361.454355) (xy 53.523617 -361.38375) (xy 53.503671 -361.310609) (xy 53.491612 -361.235764)
			(xy 53.487577 -361.16006) (xy 52.371498 -361.16006) (xy 52.370994 -361.197966) (xy 52.362935 -361.273347)
			(xy 52.34691 -361.347445) (xy 52.3231 -361.41942) (xy 52.291774 -361.488456) (xy 52.253287 -361.553771)
			(xy 52.208076 -361.614626) (xy 52.156652 -361.67033) (xy 52.099599 -361.720252) (xy 52.037563 -361.763827)
			(xy 51.971246 -361.800562) (xy 51.9014 -361.830039) (xy 51.828817 -361.851925) (xy 51.754319 -361.865972)
			(xy 51.678749 -361.872021) (xy 51.602965 -361.870002) (xy 51.527825 -361.85994) (xy 51.45418 -361.841948)
			(xy 51.382864 -361.81623) (xy 51.314687 -361.783078) (xy 51.250419 -361.742866) (xy 51.19079 -361.696051)
			(xy 51.136474 -361.643163) (xy 51.088088 -361.584801) (xy 51.04618 -361.521626) (xy 51.011224 -361.454355)
			(xy 50.983617 -361.38375) (xy 50.963671 -361.310609) (xy 50.951612 -361.235764) (xy 50.947577 -361.16006)
			(xy 49.831498 -361.16006) (xy 49.830994 -361.197966) (xy 49.822935 -361.273347) (xy 49.80691 -361.347445)
			(xy 49.7831 -361.41942) (xy 49.751774 -361.488456) (xy 49.713287 -361.553771) (xy 49.668076 -361.614626)
			(xy 49.616652 -361.67033) (xy 49.559599 -361.720252) (xy 49.497563 -361.763827) (xy 49.431246 -361.800562)
			(xy 49.3614 -361.830039) (xy 49.288817 -361.851925) (xy 49.214319 -361.865972) (xy 49.138749 -361.872021)
			(xy 49.062965 -361.870002) (xy 48.987825 -361.85994) (xy 48.91418 -361.841948) (xy 48.842864 -361.81623)
			(xy 48.774687 -361.783078) (xy 48.710419 -361.742866) (xy 48.65079 -361.696051) (xy 48.596474 -361.643163)
			(xy 48.548088 -361.584801) (xy 48.50618 -361.521626) (xy 48.471224 -361.454355) (xy 48.443617 -361.38375)
			(xy 48.423671 -361.310609) (xy 48.411612 -361.235764) (xy 48.407577 -361.16006) (xy 47.291498 -361.16006)
			(xy 47.290994 -361.197966) (xy 47.282935 -361.273347) (xy 47.26691 -361.347445) (xy 47.2431 -361.41942)
			(xy 47.211774 -361.488456) (xy 47.173287 -361.553771) (xy 47.128076 -361.614626) (xy 47.076652 -361.67033)
			(xy 47.019599 -361.720252) (xy 46.957563 -361.763827) (xy 46.891246 -361.800562) (xy 46.8214 -361.830039)
			(xy 46.748817 -361.851925) (xy 46.674319 -361.865972) (xy 46.598749 -361.872021) (xy 46.522965 -361.870002)
			(xy 46.447825 -361.85994) (xy 46.37418 -361.841948) (xy 46.302864 -361.81623) (xy 46.234687 -361.783078)
			(xy 46.170419 -361.742866) (xy 46.11079 -361.696051) (xy 46.056474 -361.643163) (xy 46.008088 -361.584801)
			(xy 45.96618 -361.521626) (xy 45.931224 -361.454355) (xy 45.903617 -361.38375) (xy 45.883671 -361.310609)
			(xy 45.871612 -361.235764) (xy 45.867577 -361.16006) (xy 44.751498 -361.16006) (xy 44.750994 -361.197966)
			(xy 44.742935 -361.273347) (xy 44.72691 -361.347445) (xy 44.7031 -361.41942) (xy 44.671774 -361.488456)
			(xy 44.633287 -361.553771) (xy 44.588076 -361.614626) (xy 44.536652 -361.67033) (xy 44.479599 -361.720252)
			(xy 44.417563 -361.763827) (xy 44.351246 -361.800562) (xy 44.2814 -361.830039) (xy 44.208817 -361.851925)
			(xy 44.134319 -361.865972) (xy 44.058749 -361.872021) (xy 43.982965 -361.870002) (xy 43.907825 -361.85994)
			(xy 43.83418 -361.841948) (xy 43.762864 -361.81623) (xy 43.694687 -361.783078) (xy 43.630419 -361.742866)
			(xy 43.57079 -361.696051) (xy 43.516474 -361.643163) (xy 43.468088 -361.584801) (xy 43.42618 -361.521626)
			(xy 43.391224 -361.454355) (xy 43.363617 -361.38375) (xy 43.343671 -361.310609) (xy 43.331612 -361.235764)
			(xy 43.327577 -361.16006) (xy 42.501239 -361.16006) (xy 42.515699 -361.170266) (xy 42.604766 -361.242723)
			(xy 42.688681 -361.321089) (xy 42.767054 -361.404998) (xy 42.839517 -361.49406) (xy 42.905734 -361.587859)
			(xy 42.965396 -361.685958) (xy 43.018225 -361.7879) (xy 43.063974 -361.893209) (xy 43.10243 -362.001394)
			(xy 43.133415 -362.111952) (xy 43.156782 -362.224366) (xy 43.172424 -362.338113) (xy 43.180268 -362.452661)
			(xy 43.180762 -362.51007) (xy 43.180576 -362.543253) (xy 43.177909 -362.609567) (xy 43.175428 -362.642658)
			(xy 43.170272 -362.700942) (xy 43.152948 -362.816671) (xy 43.127616 -362.930914) (xy 43.094401 -363.043119)
			(xy 43.053462 -363.152742) (xy 43.004999 -363.259253) (xy 42.949245 -363.362135) (xy 42.886471 -363.460891)
			(xy 42.816981 -363.555042) (xy 42.741111 -363.644132) (xy 42.659229 -363.727729) (xy 42.571732 -363.80543)
			(xy 42.500813 -363.86008) (xy 43.327577 -363.86008) (xy 43.331612 -363.784376) (xy 43.343671 -363.709531)
			(xy 43.363617 -363.63639) (xy 43.391224 -363.565785) (xy 43.42618 -363.498514) (xy 43.468088 -363.435339)
			(xy 43.516474 -363.376977) (xy 43.57079 -363.324089) (xy 43.630419 -363.277274) (xy 43.694687 -363.237062)
			(xy 43.762864 -363.20391) (xy 43.83418 -363.178192) (xy 43.907825 -363.1602) (xy 43.982965 -363.150138)
			(xy 44.058749 -363.148119) (xy 44.134319 -363.154168) (xy 44.208817 -363.168215) (xy 44.2814 -363.190101)
			(xy 44.351246 -363.219578) (xy 44.417563 -363.256313) (xy 44.479599 -363.299888) (xy 44.536652 -363.34981)
			(xy 44.588076 -363.405514) (xy 44.633287 -363.466369) (xy 44.671774 -363.531684) (xy 44.7031 -363.60072)
			(xy 44.72691 -363.672695) (xy 44.742935 -363.746793) (xy 44.750994 -363.822174) (xy 44.751498 -363.86008)
			(xy 45.867577 -363.86008) (xy 45.871612 -363.784376) (xy 45.883671 -363.709531) (xy 45.903617 -363.63639)
			(xy 45.931224 -363.565785) (xy 45.96618 -363.498514) (xy 46.008088 -363.435339) (xy 46.056474 -363.376977)
			(xy 46.11079 -363.324089) (xy 46.170419 -363.277274) (xy 46.234687 -363.237062) (xy 46.302864 -363.20391)
			(xy 46.37418 -363.178192) (xy 46.447825 -363.1602) (xy 46.522965 -363.150138) (xy 46.598749 -363.148119)
			(xy 46.674319 -363.154168) (xy 46.748817 -363.168215) (xy 46.8214 -363.190101) (xy 46.891246 -363.219578)
			(xy 46.957563 -363.256313) (xy 47.019599 -363.299888) (xy 47.076652 -363.34981) (xy 47.128076 -363.405514)
			(xy 47.173287 -363.466369) (xy 47.211774 -363.531684) (xy 47.2431 -363.60072) (xy 47.26691 -363.672695)
			(xy 47.282935 -363.746793) (xy 47.290994 -363.822174) (xy 47.291498 -363.86008) (xy 48.407577 -363.86008)
			(xy 48.411612 -363.784376) (xy 48.423671 -363.709531) (xy 48.443617 -363.63639) (xy 48.471224 -363.565785)
			(xy 48.50618 -363.498514) (xy 48.548088 -363.435339) (xy 48.596474 -363.376977) (xy 48.65079 -363.324089)
			(xy 48.710419 -363.277274) (xy 48.774687 -363.237062) (xy 48.842864 -363.20391) (xy 48.91418 -363.178192)
			(xy 48.987825 -363.1602) (xy 49.062965 -363.150138) (xy 49.138749 -363.148119) (xy 49.214319 -363.154168)
			(xy 49.288817 -363.168215) (xy 49.3614 -363.190101) (xy 49.431246 -363.219578) (xy 49.497563 -363.256313)
			(xy 49.559599 -363.299888) (xy 49.616652 -363.34981) (xy 49.668076 -363.405514) (xy 49.713287 -363.466369)
			(xy 49.751774 -363.531684) (xy 49.7831 -363.60072) (xy 49.80691 -363.672695) (xy 49.822935 -363.746793)
			(xy 49.830994 -363.822174) (xy 49.831498 -363.86008) (xy 50.947577 -363.86008) (xy 50.951612 -363.784376)
			(xy 50.963671 -363.709531) (xy 50.983617 -363.63639) (xy 51.011224 -363.565785) (xy 51.04618 -363.498514)
			(xy 51.088088 -363.435339) (xy 51.136474 -363.376977) (xy 51.19079 -363.324089) (xy 51.250419 -363.277274)
			(xy 51.314687 -363.237062) (xy 51.382864 -363.20391) (xy 51.45418 -363.178192) (xy 51.527825 -363.1602)
			(xy 51.602965 -363.150138) (xy 51.678749 -363.148119) (xy 51.754319 -363.154168) (xy 51.828817 -363.168215)
			(xy 51.9014 -363.190101) (xy 51.971246 -363.219578) (xy 52.037563 -363.256313) (xy 52.099599 -363.299888)
			(xy 52.156652 -363.34981) (xy 52.208076 -363.405514) (xy 52.253287 -363.466369) (xy 52.291774 -363.531684)
			(xy 52.3231 -363.60072) (xy 52.34691 -363.672695) (xy 52.362935 -363.746793) (xy 52.370994 -363.822174)
			(xy 52.371498 -363.86008) (xy 53.487577 -363.86008) (xy 53.491612 -363.784376) (xy 53.503671 -363.709531)
			(xy 53.523617 -363.63639) (xy 53.551224 -363.565785) (xy 53.58618 -363.498514) (xy 53.628088 -363.435339)
			(xy 53.676474 -363.376977) (xy 53.73079 -363.324089) (xy 53.790419 -363.277274) (xy 53.854687 -363.237062)
			(xy 53.922864 -363.20391) (xy 53.99418 -363.178192) (xy 54.067825 -363.1602) (xy 54.142965 -363.150138)
			(xy 54.218749 -363.148119) (xy 54.294319 -363.154168) (xy 54.368817 -363.168215) (xy 54.4414 -363.190101)
			(xy 54.511246 -363.219578) (xy 54.577563 -363.256313) (xy 54.639599 -363.299888) (xy 54.696652 -363.34981)
			(xy 54.748076 -363.405514) (xy 54.793287 -363.466369) (xy 54.831774 -363.531684) (xy 54.8631 -363.60072)
			(xy 54.88691 -363.672695) (xy 54.902935 -363.746793) (xy 54.910994 -363.822174) (xy 54.911498 -363.86008)
			(xy 56.027577 -363.86008) (xy 56.031612 -363.784376) (xy 56.043671 -363.709531) (xy 56.063617 -363.63639)
			(xy 56.091224 -363.565785) (xy 56.12618 -363.498514) (xy 56.168088 -363.435339) (xy 56.216474 -363.376977)
			(xy 56.27079 -363.324089) (xy 56.330419 -363.277274) (xy 56.394687 -363.237062) (xy 56.462864 -363.20391)
			(xy 56.53418 -363.178192) (xy 56.607825 -363.1602) (xy 56.682965 -363.150138) (xy 56.758749 -363.148119)
			(xy 56.834319 -363.154168) (xy 56.908817 -363.168215) (xy 56.9814 -363.190101) (xy 57.051246 -363.219578)
			(xy 57.117563 -363.256313) (xy 57.179599 -363.299888) (xy 57.236652 -363.34981) (xy 57.288076 -363.405514)
			(xy 57.333287 -363.466369) (xy 57.371774 -363.531684) (xy 57.4031 -363.60072) (xy 57.42691 -363.672695)
			(xy 57.442935 -363.746793) (xy 57.450994 -363.822174) (xy 57.451498 -363.86008) (xy 58.567577 -363.86008)
			(xy 58.571612 -363.784376) (xy 58.583671 -363.709531) (xy 58.603617 -363.63639) (xy 58.631224 -363.565785)
			(xy 58.66618 -363.498514) (xy 58.708088 -363.435339) (xy 58.756474 -363.376977) (xy 58.81079 -363.324089)
			(xy 58.870419 -363.277274) (xy 58.934687 -363.237062) (xy 59.002864 -363.20391) (xy 59.07418 -363.178192)
			(xy 59.147825 -363.1602) (xy 59.222965 -363.150138) (xy 59.298749 -363.148119) (xy 59.374319 -363.154168)
			(xy 59.448817 -363.168215) (xy 59.5214 -363.190101) (xy 59.591246 -363.219578) (xy 59.657563 -363.256313)
			(xy 59.719599 -363.299888) (xy 59.776652 -363.34981) (xy 59.828076 -363.405514) (xy 59.873287 -363.466369)
			(xy 59.911774 -363.531684) (xy 59.9431 -363.60072) (xy 59.96691 -363.672695) (xy 59.982935 -363.746793)
			(xy 59.990994 -363.822174) (xy 59.991498 -363.86008) (xy 61.107577 -363.86008) (xy 61.111612 -363.784376)
			(xy 61.123671 -363.709531) (xy 61.143617 -363.63639) (xy 61.171224 -363.565785) (xy 61.20618 -363.498514)
			(xy 61.248088 -363.435339) (xy 61.296474 -363.376977) (xy 61.35079 -363.324089) (xy 61.410419 -363.277274)
			(xy 61.474687 -363.237062) (xy 61.542864 -363.20391) (xy 61.61418 -363.178192) (xy 61.687825 -363.1602)
			(xy 61.762965 -363.150138) (xy 61.838749 -363.148119) (xy 61.914319 -363.154168) (xy 61.988817 -363.168215)
			(xy 62.0614 -363.190101) (xy 62.131246 -363.219578) (xy 62.197563 -363.256313) (xy 62.259599 -363.299888)
			(xy 62.316652 -363.34981) (xy 62.368076 -363.405514) (xy 62.413287 -363.466369) (xy 62.451774 -363.531684)
			(xy 62.4831 -363.60072) (xy 62.50691 -363.672695) (xy 62.522935 -363.746793) (xy 62.530994 -363.822174)
			(xy 62.531498 -363.86008) (xy 62.530994 -363.897986) (xy 62.522935 -363.973367) (xy 62.50691 -364.047465)
			(xy 62.4831 -364.11944) (xy 62.451774 -364.188476) (xy 62.413287 -364.253791) (xy 62.368076 -364.314646)
			(xy 62.316652 -364.37035) (xy 62.259599 -364.420272) (xy 62.197563 -364.463847) (xy 62.131246 -364.500582)
			(xy 62.0614 -364.530059) (xy 61.988817 -364.551945) (xy 61.914319 -364.565992) (xy 61.838749 -364.572041)
			(xy 61.762965 -364.570022) (xy 61.687825 -364.55996) (xy 61.61418 -364.541968) (xy 61.542864 -364.51625)
			(xy 61.474687 -364.483098) (xy 61.410419 -364.442886) (xy 61.35079 -364.396071) (xy 61.296474 -364.343183)
			(xy 61.248088 -364.284821) (xy 61.20618 -364.221646) (xy 61.171224 -364.154375) (xy 61.143617 -364.08377)
			(xy 61.123671 -364.010629) (xy 61.111612 -363.935784) (xy 61.107577 -363.86008) (xy 59.991498 -363.86008)
			(xy 59.990994 -363.897986) (xy 59.982935 -363.973367) (xy 59.96691 -364.047465) (xy 59.9431 -364.11944)
			(xy 59.911774 -364.188476) (xy 59.873287 -364.253791) (xy 59.828076 -364.314646) (xy 59.776652 -364.37035)
			(xy 59.719599 -364.420272) (xy 59.657563 -364.463847) (xy 59.591246 -364.500582) (xy 59.5214 -364.530059)
			(xy 59.448817 -364.551945) (xy 59.374319 -364.565992) (xy 59.298749 -364.572041) (xy 59.222965 -364.570022)
			(xy 59.147825 -364.55996) (xy 59.07418 -364.541968) (xy 59.002864 -364.51625) (xy 58.934687 -364.483098)
			(xy 58.870419 -364.442886) (xy 58.81079 -364.396071) (xy 58.756474 -364.343183) (xy 58.708088 -364.284821)
			(xy 58.66618 -364.221646) (xy 58.631224 -364.154375) (xy 58.603617 -364.08377) (xy 58.583671 -364.010629)
			(xy 58.571612 -363.935784) (xy 58.567577 -363.86008) (xy 57.451498 -363.86008) (xy 57.450994 -363.897986)
			(xy 57.442935 -363.973367) (xy 57.42691 -364.047465) (xy 57.4031 -364.11944) (xy 57.371774 -364.188476)
			(xy 57.333287 -364.253791) (xy 57.288076 -364.314646) (xy 57.236652 -364.37035) (xy 57.179599 -364.420272)
			(xy 57.117563 -364.463847) (xy 57.051246 -364.500582) (xy 56.9814 -364.530059) (xy 56.908817 -364.551945)
			(xy 56.834319 -364.565992) (xy 56.758749 -364.572041) (xy 56.682965 -364.570022) (xy 56.607825 -364.55996)
			(xy 56.53418 -364.541968) (xy 56.462864 -364.51625) (xy 56.394687 -364.483098) (xy 56.330419 -364.442886)
			(xy 56.27079 -364.396071) (xy 56.216474 -364.343183) (xy 56.168088 -364.284821) (xy 56.12618 -364.221646)
			(xy 56.091224 -364.154375) (xy 56.063617 -364.08377) (xy 56.043671 -364.010629) (xy 56.031612 -363.935784)
			(xy 56.027577 -363.86008) (xy 54.911498 -363.86008) (xy 54.910994 -363.897986) (xy 54.902935 -363.973367)
			(xy 54.88691 -364.047465) (xy 54.8631 -364.11944) (xy 54.831774 -364.188476) (xy 54.793287 -364.253791)
			(xy 54.748076 -364.314646) (xy 54.696652 -364.37035) (xy 54.639599 -364.420272) (xy 54.577563 -364.463847)
			(xy 54.511246 -364.500582) (xy 54.4414 -364.530059) (xy 54.368817 -364.551945) (xy 54.294319 -364.565992)
			(xy 54.218749 -364.572041) (xy 54.142965 -364.570022) (xy 54.067825 -364.55996) (xy 53.99418 -364.541968)
			(xy 53.922864 -364.51625) (xy 53.854687 -364.483098) (xy 53.790419 -364.442886) (xy 53.73079 -364.396071)
			(xy 53.676474 -364.343183) (xy 53.628088 -364.284821) (xy 53.58618 -364.221646) (xy 53.551224 -364.154375)
			(xy 53.523617 -364.08377) (xy 53.503671 -364.010629) (xy 53.491612 -363.935784) (xy 53.487577 -363.86008)
			(xy 52.371498 -363.86008) (xy 52.370994 -363.897986) (xy 52.362935 -363.973367) (xy 52.34691 -364.047465)
			(xy 52.3231 -364.11944) (xy 52.291774 -364.188476) (xy 52.253287 -364.253791) (xy 52.208076 -364.314646)
			(xy 52.156652 -364.37035) (xy 52.099599 -364.420272) (xy 52.037563 -364.463847) (xy 51.971246 -364.500582)
			(xy 51.9014 -364.530059) (xy 51.828817 -364.551945) (xy 51.754319 -364.565992) (xy 51.678749 -364.572041)
			(xy 51.602965 -364.570022) (xy 51.527825 -364.55996) (xy 51.45418 -364.541968) (xy 51.382864 -364.51625)
			(xy 51.314687 -364.483098) (xy 51.250419 -364.442886) (xy 51.19079 -364.396071) (xy 51.136474 -364.343183)
			(xy 51.088088 -364.284821) (xy 51.04618 -364.221646) (xy 51.011224 -364.154375) (xy 50.983617 -364.08377)
			(xy 50.963671 -364.010629) (xy 50.951612 -363.935784) (xy 50.947577 -363.86008) (xy 49.831498 -363.86008)
			(xy 49.830994 -363.897986) (xy 49.822935 -363.973367) (xy 49.80691 -364.047465) (xy 49.7831 -364.11944)
			(xy 49.751774 -364.188476) (xy 49.713287 -364.253791) (xy 49.668076 -364.314646) (xy 49.616652 -364.37035)
			(xy 49.559599 -364.420272) (xy 49.497563 -364.463847) (xy 49.431246 -364.500582) (xy 49.3614 -364.530059)
			(xy 49.288817 -364.551945) (xy 49.214319 -364.565992) (xy 49.138749 -364.572041) (xy 49.062965 -364.570022)
			(xy 48.987825 -364.55996) (xy 48.91418 -364.541968) (xy 48.842864 -364.51625) (xy 48.774687 -364.483098)
			(xy 48.710419 -364.442886) (xy 48.65079 -364.396071) (xy 48.596474 -364.343183) (xy 48.548088 -364.284821)
			(xy 48.50618 -364.221646) (xy 48.471224 -364.154375) (xy 48.443617 -364.08377) (xy 48.423671 -364.010629)
			(xy 48.411612 -363.935784) (xy 48.407577 -363.86008) (xy 47.291498 -363.86008) (xy 47.290994 -363.897986)
			(xy 47.282935 -363.973367) (xy 47.26691 -364.047465) (xy 47.2431 -364.11944) (xy 47.211774 -364.188476)
			(xy 47.173287 -364.253791) (xy 47.128076 -364.314646) (xy 47.076652 -364.37035) (xy 47.019599 -364.420272)
			(xy 46.957563 -364.463847) (xy 46.891246 -364.500582) (xy 46.8214 -364.530059) (xy 46.748817 -364.551945)
			(xy 46.674319 -364.565992) (xy 46.598749 -364.572041) (xy 46.522965 -364.570022) (xy 46.447825 -364.55996)
			(xy 46.37418 -364.541968) (xy 46.302864 -364.51625) (xy 46.234687 -364.483098) (xy 46.170419 -364.442886)
			(xy 46.11079 -364.396071) (xy 46.056474 -364.343183) (xy 46.008088 -364.284821) (xy 45.96618 -364.221646)
			(xy 45.931224 -364.154375) (xy 45.903617 -364.08377) (xy 45.883671 -364.010629) (xy 45.871612 -363.935784)
			(xy 45.867577 -363.86008) (xy 44.751498 -363.86008) (xy 44.750994 -363.897986) (xy 44.742935 -363.973367)
			(xy 44.72691 -364.047465) (xy 44.7031 -364.11944) (xy 44.671774 -364.188476) (xy 44.633287 -364.253791)
			(xy 44.588076 -364.314646) (xy 44.536652 -364.37035) (xy 44.479599 -364.420272) (xy 44.417563 -364.463847)
			(xy 44.351246 -364.500582) (xy 44.2814 -364.530059) (xy 44.208817 -364.551945) (xy 44.134319 -364.565992)
			(xy 44.058749 -364.572041) (xy 43.982965 -364.570022) (xy 43.907825 -364.55996) (xy 43.83418 -364.541968)
			(xy 43.762864 -364.51625) (xy 43.694687 -364.483098) (xy 43.630419 -364.442886) (xy 43.57079 -364.396071)
			(xy 43.516474 -364.343183) (xy 43.468088 -364.284821) (xy 43.42618 -364.221646) (xy 43.391224 -364.154375)
			(xy 43.363617 -364.08377) (xy 43.343671 -364.010629) (xy 43.331612 -363.935784) (xy 43.327577 -363.86008)
			(xy 42.500813 -363.86008) (xy 42.479042 -363.876857) (xy 42.381609 -363.941665) (xy 42.279905 -363.99954)
			(xy 42.174422 -364.050202) (xy 42.065671 -364.093404) (xy 41.954179 -364.128939) (xy 41.840485 -364.156634)
			(xy 41.725141 -364.176354) (xy 41.608704 -364.188005) (xy 41.491739 -364.19153) (xy 41.374812 -364.186912)
			(xy 41.258489 -364.174173) (xy 41.143334 -364.153375) (xy 41.029905 -364.124618) (xy 40.91875 -364.088042)
			(xy 40.810407 -364.043825) (xy 40.705403 -363.992179) (xy 40.604244 -363.933356) (xy 40.507421 -363.86764)
			(xy 40.415403 -363.795349) (xy 40.328636 -363.716834) (xy 40.247539 -363.632474) (xy 40.172506 -363.542679)
			(xy 40.103899 -363.447883) (xy 40.042051 -363.348544) (xy 39.987262 -363.245145) (xy 39.939796 -363.138186)
			(xy 39.899884 -363.028185) (xy 39.86772 -362.915674) (xy 39.843457 -362.801199) (xy 39.827215 -362.685313)
			(xy 39.819072 -362.568579) (xy 39.818564 -362.51007) (xy 36.092815 -362.51007) (xy 36.140713 -362.546241)
			(xy 36.204933 -362.604785) (xy 36.263477 -362.669005) (xy 36.315846 -362.738352) (xy 36.361593 -362.812236)
			(xy 36.400327 -362.890025) (xy 36.431719 -362.971057) (xy 36.4555 -363.054639) (xy 36.471468 -363.140059)
			(xy 36.479486 -363.226588) (xy 36.479988 -363.270038) (xy 36.479486 -363.313488) (xy 36.471468 -363.400017)
			(xy 36.4555 -363.485437) (xy 36.431719 -363.569019) (xy 36.400327 -363.650051) (xy 36.361593 -363.72784)
			(xy 36.315846 -363.801724) (xy 36.263477 -363.871071) (xy 36.204933 -363.935291) (xy 36.140713 -363.993835)
			(xy 36.071366 -364.046204) (xy 35.997482 -364.091951) (xy 35.919693 -364.130685) (xy 35.838661 -364.162077)
			(xy 35.755079 -364.185858) (xy 35.669659 -364.201826) (xy 35.58313 -364.209844) (xy 35.49623 -364.209844)
			(xy 35.409701 -364.201826) (xy 35.324281 -364.185858) (xy 35.240699 -364.162077) (xy 35.159667 -364.130685)
			(xy 35.081878 -364.091951) (xy 35.007994 -364.046204) (xy 34.938647 -363.993835) (xy 34.874427 -363.935291)
			(xy 34.815883 -363.871071) (xy 34.763514 -363.801724) (xy 34.717767 -363.72784) (xy 34.679033 -363.650051)
			(xy 34.647641 -363.569019) (xy 34.62386 -363.485437) (xy 34.607892 -363.400017) (xy 34.599874 -363.313488)
			(xy 31.399486 -363.313488) (xy 31.391468 -363.400017) (xy 31.3755 -363.485437) (xy 31.351719 -363.569019)
			(xy 31.320327 -363.650051) (xy 31.281593 -363.72784) (xy 31.235846 -363.801724) (xy 31.183477 -363.871071)
			(xy 31.124933 -363.935291) (xy 31.060713 -363.993835) (xy 30.991366 -364.046204) (xy 30.917482 -364.091951)
			(xy 30.839693 -364.130685) (xy 30.758661 -364.162077) (xy 30.675079 -364.185858) (xy 30.589659 -364.201826)
			(xy 30.50313 -364.209844) (xy 30.41623 -364.209844) (xy 30.329701 -364.201826) (xy 30.244281 -364.185858)
			(xy 30.160699 -364.162077) (xy 30.079667 -364.130685) (xy 30.001878 -364.091951) (xy 29.927994 -364.046204)
			(xy 29.858647 -363.993835) (xy 29.794427 -363.935291) (xy 29.735883 -363.871071) (xy 29.683514 -363.801724)
			(xy 29.637767 -363.72784) (xy 29.599033 -363.650051) (xy 29.567641 -363.569019) (xy 29.54386 -363.485437)
			(xy 29.527892 -363.400017) (xy 29.519874 -363.313488) (xy 21.593048 -363.313488) (xy 21.593048 -364.246414)
			(xy 26.78633 -364.246414) (xy 26.790401 -364.190792) (xy 26.802527 -364.136355) (xy 26.82245 -364.084264)
			(xy 26.849746 -364.035629) (xy 26.883832 -363.991486) (xy 26.923981 -363.952777) (xy 26.969339 -363.920326)
			(xy 27.018939 -363.894825) (xy 27.071723 -363.876818) (xy 27.126566 -363.866688) (xy 27.1823 -363.864651)
			(xy 27.237737 -363.870751) (xy 27.291694 -363.884857) (xy 27.343023 -363.906669) (xy 27.390629 -363.935723)
			(xy 27.433497 -363.971398) (xy 27.470714 -364.012935) (xy 27.501487 -364.059448) (xy 27.525159 -364.109945)
			(xy 27.541227 -364.163352) (xy 27.549347 -364.218528) (xy 27.549856 -364.246414) (xy 27.549347 -364.2743)
			(xy 27.541227 -364.329476) (xy 27.525159 -364.382883) (xy 27.501487 -364.43338) (xy 27.470714 -364.479893)
			(xy 27.433497 -364.52143) (xy 27.390629 -364.557105) (xy 27.343023 -364.586159) (xy 27.291694 -364.607971)
			(xy 27.237737 -364.622077) (xy 27.1823 -364.628177) (xy 27.126566 -364.62614) (xy 27.071723 -364.61601)
			(xy 27.018939 -364.598003) (xy 26.969339 -364.572502) (xy 26.923981 -364.540051) (xy 26.883832 -364.501342)
			(xy 26.849746 -364.457199) (xy 26.82245 -364.408564) (xy 26.802527 -364.356473) (xy 26.790401 -364.302036)
			(xy 26.78633 -364.246414) (xy 21.593048 -364.246414) (xy 21.593048 -365.50092) (xy 24.254966 -365.50092)
			(xy 24.259037 -365.445298) (xy 24.271163 -365.390861) (xy 24.291086 -365.33877) (xy 24.318382 -365.290135)
			(xy 24.352468 -365.245992) (xy 24.392617 -365.207283) (xy 24.437975 -365.174832) (xy 24.487575 -365.149331)
			(xy 24.540359 -365.131324) (xy 24.595202 -365.121194) (xy 24.650936 -365.119157) (xy 24.706373 -365.125257)
			(xy 24.76033 -365.139363) (xy 24.811659 -365.161175) (xy 24.859265 -365.190229) (xy 24.902133 -365.225904)
			(xy 24.93935 -365.267441) (xy 24.970123 -365.313954) (xy 24.993795 -365.364451) (xy 25.009863 -365.417858)
			(xy 25.017983 -365.473034) (xy 25.018492 -365.50092) (xy 25.017983 -365.528806) (xy 25.009863 -365.583982)
			(xy 24.993795 -365.637389) (xy 24.970123 -365.687886) (xy 24.93935 -365.734399) (xy 24.902133 -365.775936)
			(xy 24.859265 -365.811611) (xy 24.811659 -365.840665) (xy 24.781483 -365.853488) (xy 29.519874 -365.853488)
			(xy 29.519874 -365.766588) (xy 29.527892 -365.680059) (xy 29.54386 -365.594639) (xy 29.567641 -365.511057)
			(xy 29.599033 -365.430025) (xy 29.637767 -365.352236) (xy 29.683514 -365.278352) (xy 29.735883 -365.209005)
			(xy 29.794427 -365.144785) (xy 29.858647 -365.086241) (xy 29.927994 -365.033872) (xy 30.001878 -364.988125)
			(xy 30.079667 -364.949391) (xy 30.160699 -364.917999) (xy 30.244281 -364.894218) (xy 30.329701 -364.87825)
			(xy 30.41623 -364.870232) (xy 30.50313 -364.870232) (xy 30.589659 -364.87825) (xy 30.675079 -364.894218)
			(xy 30.758661 -364.917999) (xy 30.839693 -364.949391) (xy 30.917482 -364.988125) (xy 30.991366 -365.033872)
			(xy 31.060713 -365.086241) (xy 31.124933 -365.144785) (xy 31.183477 -365.209005) (xy 31.235846 -365.278352)
			(xy 31.281593 -365.352236) (xy 31.320327 -365.430025) (xy 31.351719 -365.511057) (xy 31.3755 -365.594639)
			(xy 31.391468 -365.680059) (xy 31.399486 -365.766588) (xy 31.399988 -365.810038) (xy 31.399486 -365.853488)
			(xy 34.599874 -365.853488) (xy 34.599874 -365.766588) (xy 34.607892 -365.680059) (xy 34.62386 -365.594639)
			(xy 34.647641 -365.511057) (xy 34.679033 -365.430025) (xy 34.717767 -365.352236) (xy 34.763514 -365.278352)
			(xy 34.815883 -365.209005) (xy 34.874427 -365.144785) (xy 34.938647 -365.086241) (xy 35.007994 -365.033872)
			(xy 35.081878 -364.988125) (xy 35.159667 -364.949391) (xy 35.240699 -364.917999) (xy 35.324281 -364.894218)
			(xy 35.409701 -364.87825) (xy 35.49623 -364.870232) (xy 35.58313 -364.870232) (xy 35.669659 -364.87825)
			(xy 35.755079 -364.894218) (xy 35.838661 -364.917999) (xy 35.919693 -364.949391) (xy 35.997482 -364.988125)
			(xy 36.071366 -365.033872) (xy 36.140713 -365.086241) (xy 36.204933 -365.144785) (xy 36.263477 -365.209005)
			(xy 36.315846 -365.278352) (xy 36.361593 -365.352236) (xy 36.400327 -365.430025) (xy 36.431719 -365.511057)
			(xy 36.4555 -365.594639) (xy 36.471468 -365.680059) (xy 36.479486 -365.766588) (xy 36.479988 -365.810038)
			(xy 36.479486 -365.853488) (xy 36.471468 -365.940017) (xy 36.4555 -366.025437) (xy 36.431719 -366.109019)
			(xy 36.400327 -366.190051) (xy 36.361593 -366.26784) (xy 36.315846 -366.341724) (xy 36.263477 -366.411071)
			(xy 36.204933 -366.475291) (xy 36.140713 -366.533835) (xy 36.071366 -366.586204) (xy 35.997482 -366.631951)
			(xy 35.919693 -366.670685) (xy 35.838661 -366.702077) (xy 35.755079 -366.725858) (xy 35.669659 -366.741826)
			(xy 35.58313 -366.749844) (xy 35.49623 -366.749844) (xy 35.409701 -366.741826) (xy 35.324281 -366.725858)
			(xy 35.240699 -366.702077) (xy 35.159667 -366.670685) (xy 35.081878 -366.631951) (xy 35.007994 -366.586204)
			(xy 34.938647 -366.533835) (xy 34.874427 -366.475291) (xy 34.815883 -366.411071) (xy 34.763514 -366.341724)
			(xy 34.717767 -366.26784) (xy 34.679033 -366.190051) (xy 34.647641 -366.109019) (xy 34.62386 -366.025437)
			(xy 34.607892 -365.940017) (xy 34.599874 -365.853488) (xy 31.399486 -365.853488) (xy 31.391468 -365.940017)
			(xy 31.3755 -366.025437) (xy 31.351719 -366.109019) (xy 31.320327 -366.190051) (xy 31.281593 -366.26784)
			(xy 31.235846 -366.341724) (xy 31.183477 -366.411071) (xy 31.124933 -366.475291) (xy 31.060713 -366.533835)
			(xy 30.991366 -366.586204) (xy 30.917482 -366.631951) (xy 30.839693 -366.670685) (xy 30.758661 -366.702077)
			(xy 30.675079 -366.725858) (xy 30.589659 -366.741826) (xy 30.50313 -366.749844) (xy 30.41623 -366.749844)
			(xy 30.329701 -366.741826) (xy 30.244281 -366.725858) (xy 30.160699 -366.702077) (xy 30.079667 -366.670685)
			(xy 30.001878 -366.631951) (xy 29.927994 -366.586204) (xy 29.858647 -366.533835) (xy 29.794427 -366.475291)
			(xy 29.735883 -366.411071) (xy 29.683514 -366.341724) (xy 29.637767 -366.26784) (xy 29.599033 -366.190051)
			(xy 29.567641 -366.109019) (xy 29.54386 -366.025437) (xy 29.527892 -365.940017) (xy 29.519874 -365.853488)
			(xy 24.781483 -365.853488) (xy 24.76033 -365.862477) (xy 24.706373 -365.876583) (xy 24.650936 -365.882683)
			(xy 24.595202 -365.880646) (xy 24.540359 -365.870516) (xy 24.487575 -365.852509) (xy 24.437975 -365.827008)
			(xy 24.392617 -365.794557) (xy 24.352468 -365.755848) (xy 24.318382 -365.711705) (xy 24.291086 -365.66307)
			(xy 24.271163 -365.610979) (xy 24.259037 -365.556542) (xy 24.254966 -365.50092) (xy 21.593048 -365.50092)
			(xy 21.593048 -366.710722) (xy 24.254204 -366.710722) (xy 24.258275 -366.6551) (xy 24.270401 -366.600663)
			(xy 24.290324 -366.548572) (xy 24.31762 -366.499937) (xy 24.351706 -366.455794) (xy 24.391855 -366.417085)
			(xy 24.437213 -366.384634) (xy 24.486813 -366.359133) (xy 24.539597 -366.341126) (xy 24.59444 -366.330996)
			(xy 24.650174 -366.328959) (xy 24.705611 -366.335059) (xy 24.759568 -366.349165) (xy 24.810897 -366.370977)
			(xy 24.858503 -366.400031) (xy 24.901371 -366.435706) (xy 24.938588 -366.477243) (xy 24.969361 -366.523756)
			(xy 24.993033 -366.574253) (xy 25.009101 -366.62766) (xy 25.017221 -366.682836) (xy 25.01773 -366.710722)
			(xy 25.017221 -366.738608) (xy 25.009101 -366.793784) (xy 24.993033 -366.847191) (xy 24.969361 -366.897688)
			(xy 24.94921 -366.928146) (xy 26.735784 -366.928146) (xy 26.739855 -366.872524) (xy 26.751981 -366.818087)
			(xy 26.771904 -366.765996) (xy 26.7992 -366.717361) (xy 26.833286 -366.673218) (xy 26.873435 -366.634509)
			(xy 26.918793 -366.602058) (xy 26.968393 -366.576557) (xy 27.021177 -366.55855) (xy 27.07602 -366.54842)
			(xy 27.131754 -366.546383) (xy 27.187191 -366.552483) (xy 27.241148 -366.566589) (xy 27.292477 -366.588401)
			(xy 27.340083 -366.617455) (xy 27.382951 -366.65313) (xy 27.420168 -366.694667) (xy 27.450941 -366.74118)
			(xy 27.474613 -366.791677) (xy 27.490681 -366.845084) (xy 27.498801 -366.90026) (xy 27.49931 -366.928146)
			(xy 27.498801 -366.956032) (xy 27.490681 -367.011208) (xy 27.474613 -367.064615) (xy 27.450941 -367.115112)
			(xy 27.420168 -367.161625) (xy 27.382951 -367.203162) (xy 27.340083 -367.238837) (xy 27.292477 -367.267891)
			(xy 27.241148 -367.289703) (xy 27.187191 -367.303809) (xy 27.131754 -367.309909) (xy 27.07602 -367.307872)
			(xy 27.021177 -367.297742) (xy 26.968393 -367.279735) (xy 26.918793 -367.254234) (xy 26.873435 -367.221783)
			(xy 26.833286 -367.183074) (xy 26.7992 -367.138931) (xy 26.771904 -367.090296) (xy 26.751981 -367.038205)
			(xy 26.739855 -366.983768) (xy 26.735784 -366.928146) (xy 24.94921 -366.928146) (xy 24.938588 -366.944201)
			(xy 24.901371 -366.985738) (xy 24.858503 -367.021413) (xy 24.810897 -367.050467) (xy 24.759568 -367.072279)
			(xy 24.705611 -367.086385) (xy 24.650174 -367.092485) (xy 24.59444 -367.090448) (xy 24.539597 -367.080318)
			(xy 24.486813 -367.062311) (xy 24.437213 -367.03681) (xy 24.391855 -367.004359) (xy 24.351706 -366.96565)
			(xy 24.31762 -366.921507) (xy 24.290324 -366.872872) (xy 24.270401 -366.820781) (xy 24.258275 -366.766344)
			(xy 24.254204 -366.710722) (xy 21.593048 -366.710722) (xy 21.593048 -367.771426) (xy 24.374092 -367.771426)
			(xy 24.378163 -367.715804) (xy 24.390289 -367.661367) (xy 24.410212 -367.609276) (xy 24.437508 -367.560641)
			(xy 24.471594 -367.516498) (xy 24.511743 -367.477789) (xy 24.557101 -367.445338) (xy 24.606701 -367.419837)
			(xy 24.659485 -367.40183) (xy 24.714328 -367.3917) (xy 24.770062 -367.389663) (xy 24.825499 -367.395763)
			(xy 24.879456 -367.409869) (xy 24.930785 -367.431681) (xy 24.978391 -367.460735) (xy 25.021259 -367.49641)
			(xy 25.058476 -367.537947) (xy 25.089249 -367.58446) (xy 25.112921 -367.634957) (xy 25.128989 -367.688364)
			(xy 25.137109 -367.74354) (xy 25.137618 -367.771426) (xy 25.137109 -367.799312) (xy 25.128989 -367.854488)
			(xy 25.112921 -367.907895) (xy 25.089249 -367.958392) (xy 25.058476 -368.004905) (xy 25.021259 -368.046442)
			(xy 24.978391 -368.082117) (xy 24.930785 -368.111171) (xy 24.879456 -368.132983) (xy 24.825499 -368.147089)
			(xy 24.770062 -368.153189) (xy 24.714328 -368.151152) (xy 24.659485 -368.141022) (xy 24.606701 -368.123015)
			(xy 24.557101 -368.097514) (xy 24.511743 -368.065063) (xy 24.471594 -368.026354) (xy 24.437508 -367.982211)
			(xy 24.410212 -367.933576) (xy 24.390289 -367.881485) (xy 24.378163 -367.827048) (xy 24.374092 -367.771426)
			(xy 21.593048 -367.771426) (xy 21.593048 -368.393488) (xy 29.519874 -368.393488) (xy 29.519874 -368.306588)
			(xy 29.527892 -368.220059) (xy 29.54386 -368.134639) (xy 29.567641 -368.051057) (xy 29.599033 -367.970025)
			(xy 29.637767 -367.892236) (xy 29.683514 -367.818352) (xy 29.735883 -367.749005) (xy 29.794427 -367.684785)
			(xy 29.858647 -367.626241) (xy 29.927994 -367.573872) (xy 30.001878 -367.528125) (xy 30.079667 -367.489391)
			(xy 30.160699 -367.457999) (xy 30.244281 -367.434218) (xy 30.329701 -367.41825) (xy 30.41623 -367.410232)
			(xy 30.50313 -367.410232) (xy 30.589659 -367.41825) (xy 30.675079 -367.434218) (xy 30.758661 -367.457999)
			(xy 30.839693 -367.489391) (xy 30.917482 -367.528125) (xy 30.991366 -367.573872) (xy 31.060713 -367.626241)
			(xy 31.124933 -367.684785) (xy 31.183477 -367.749005) (xy 31.235846 -367.818352) (xy 31.281593 -367.892236)
			(xy 31.320327 -367.970025) (xy 31.351719 -368.051057) (xy 31.3755 -368.134639) (xy 31.391468 -368.220059)
			(xy 31.399486 -368.306588) (xy 31.399988 -368.350038) (xy 31.399486 -368.393488) (xy 34.599874 -368.393488)
			(xy 34.599874 -368.306588) (xy 34.607892 -368.220059) (xy 34.62386 -368.134639) (xy 34.647641 -368.051057)
			(xy 34.679033 -367.970025) (xy 34.717767 -367.892236) (xy 34.763514 -367.818352) (xy 34.815883 -367.749005)
			(xy 34.874427 -367.684785) (xy 34.938647 -367.626241) (xy 35.007994 -367.573872) (xy 35.081878 -367.528125)
			(xy 35.159667 -367.489391) (xy 35.240699 -367.457999) (xy 35.324281 -367.434218) (xy 35.409701 -367.41825)
			(xy 35.49623 -367.410232) (xy 35.58313 -367.410232) (xy 35.669659 -367.41825) (xy 35.755079 -367.434218)
			(xy 35.838661 -367.457999) (xy 35.919693 -367.489391) (xy 35.997482 -367.528125) (xy 36.071366 -367.573872)
			(xy 36.140713 -367.626241) (xy 36.204933 -367.684785) (xy 36.263477 -367.749005) (xy 36.315846 -367.818352)
			(xy 36.361593 -367.892236) (xy 36.400327 -367.970025) (xy 36.431719 -368.051057) (xy 36.4555 -368.134639)
			(xy 36.471468 -368.220059) (xy 36.479486 -368.306588) (xy 36.479988 -368.350038) (xy 36.479486 -368.393488)
			(xy 36.471468 -368.480017) (xy 36.4555 -368.565437) (xy 36.451166 -368.58067) (xy 40.05275 -368.58067)
			(xy 40.056821 -368.525048) (xy 40.068947 -368.470611) (xy 40.08887 -368.41852) (xy 40.116166 -368.369885)
			(xy 40.150252 -368.325742) (xy 40.190401 -368.287033) (xy 40.235759 -368.254582) (xy 40.285359 -368.229081)
			(xy 40.338143 -368.211074) (xy 40.392986 -368.200944) (xy 40.44872 -368.198907) (xy 40.504157 -368.205007)
			(xy 40.558114 -368.219113) (xy 40.609443 -368.240925) (xy 40.657049 -368.269979) (xy 40.699917 -368.305654)
			(xy 40.737134 -368.347191) (xy 40.767907 -368.393704) (xy 40.791579 -368.444201) (xy 40.807647 -368.497608)
			(xy 40.815767 -368.552784) (xy 40.816276 -368.58067) (xy 40.815767 -368.608556) (xy 40.807647 -368.663732)
			(xy 40.791579 -368.717139) (xy 40.767907 -368.767636) (xy 40.737134 -368.814149) (xy 40.699917 -368.855686)
			(xy 40.657049 -368.891361) (xy 40.609443 -368.920415) (xy 40.558114 -368.942227) (xy 40.504157 -368.956333)
			(xy 40.44872 -368.962433) (xy 40.392986 -368.960396) (xy 40.338143 -368.950266) (xy 40.285359 -368.932259)
			(xy 40.235759 -368.906758) (xy 40.190401 -368.874307) (xy 40.150252 -368.835598) (xy 40.116166 -368.791455)
			(xy 40.08887 -368.74282) (xy 40.068947 -368.690729) (xy 40.056821 -368.636292) (xy 40.05275 -368.58067)
			(xy 36.451166 -368.58067) (xy 36.431719 -368.649019) (xy 36.400327 -368.730051) (xy 36.361593 -368.80784)
			(xy 36.315846 -368.881724) (xy 36.263477 -368.951071) (xy 36.204933 -369.015291) (xy 36.140713 -369.073835)
			(xy 36.071366 -369.126204) (xy 35.997482 -369.171951) (xy 35.919693 -369.210685) (xy 35.838661 -369.242077)
			(xy 35.755079 -369.265858) (xy 35.669659 -369.281826) (xy 35.58313 -369.289844) (xy 35.49623 -369.289844)
			(xy 35.409701 -369.281826) (xy 35.324281 -369.265858) (xy 35.240699 -369.242077) (xy 35.159667 -369.210685)
			(xy 35.081878 -369.171951) (xy 35.007994 -369.126204) (xy 34.938647 -369.073835) (xy 34.874427 -369.015291)
			(xy 34.815883 -368.951071) (xy 34.763514 -368.881724) (xy 34.717767 -368.80784) (xy 34.679033 -368.730051)
			(xy 34.647641 -368.649019) (xy 34.62386 -368.565437) (xy 34.607892 -368.480017) (xy 34.599874 -368.393488)
			(xy 31.399486 -368.393488) (xy 31.391468 -368.480017) (xy 31.3755 -368.565437) (xy 31.351719 -368.649019)
			(xy 31.320327 -368.730051) (xy 31.281593 -368.80784) (xy 31.235846 -368.881724) (xy 31.183477 -368.951071)
			(xy 31.124933 -369.015291) (xy 31.060713 -369.073835) (xy 30.991366 -369.126204) (xy 30.917482 -369.171951)
			(xy 30.839693 -369.210685) (xy 30.758661 -369.242077) (xy 30.675079 -369.265858) (xy 30.589659 -369.281826)
			(xy 30.50313 -369.289844) (xy 30.41623 -369.289844) (xy 30.329701 -369.281826) (xy 30.244281 -369.265858)
			(xy 30.160699 -369.242077) (xy 30.079667 -369.210685) (xy 30.001878 -369.171951) (xy 29.927994 -369.126204)
			(xy 29.858647 -369.073835) (xy 29.794427 -369.015291) (xy 29.735883 -368.951071) (xy 29.683514 -368.881724)
			(xy 29.637767 -368.80784) (xy 29.599033 -368.730051) (xy 29.567641 -368.649019) (xy 29.54386 -368.565437)
			(xy 29.527892 -368.480017) (xy 29.519874 -368.393488) (xy 21.593048 -368.393488) (xy 21.593048 -369.143534)
			(xy 23.807926 -369.143534) (xy 23.811997 -369.087912) (xy 23.824123 -369.033475) (xy 23.844046 -368.981384)
			(xy 23.871342 -368.932749) (xy 23.905428 -368.888606) (xy 23.945577 -368.849897) (xy 23.990935 -368.817446)
			(xy 24.040535 -368.791945) (xy 24.093319 -368.773938) (xy 24.148162 -368.763808) (xy 24.203896 -368.761771)
			(xy 24.259333 -368.767871) (xy 24.31329 -368.781977) (xy 24.364619 -368.803789) (xy 24.412225 -368.832843)
			(xy 24.455093 -368.868518) (xy 24.49231 -368.910055) (xy 24.523083 -368.956568) (xy 24.530952 -368.973354)
			(xy 26.797506 -368.973354) (xy 26.801577 -368.917732) (xy 26.813703 -368.863295) (xy 26.833626 -368.811204)
			(xy 26.860922 -368.762569) (xy 26.895008 -368.718426) (xy 26.935157 -368.679717) (xy 26.980515 -368.647266)
			(xy 27.030115 -368.621765) (xy 27.082899 -368.603758) (xy 27.137742 -368.593628) (xy 27.193476 -368.591591)
			(xy 27.248913 -368.597691) (xy 27.30287 -368.611797) (xy 27.354199 -368.633609) (xy 27.401805 -368.662663)
			(xy 27.444673 -368.698338) (xy 27.48189 -368.739875) (xy 27.512663 -368.786388) (xy 27.536335 -368.836885)
			(xy 27.552403 -368.890292) (xy 27.560523 -368.945468) (xy 27.561032 -368.973354) (xy 27.560523 -369.00124)
			(xy 27.552403 -369.056416) (xy 27.536335 -369.109823) (xy 27.512663 -369.16032) (xy 27.48189 -369.206833)
			(xy 27.444673 -369.24837) (xy 27.401805 -369.284045) (xy 27.354199 -369.313099) (xy 27.30287 -369.334911)
			(xy 27.248913 -369.349017) (xy 27.193476 -369.355117) (xy 27.137742 -369.35308) (xy 27.082899 -369.34295)
			(xy 27.030115 -369.324943) (xy 26.980515 -369.299442) (xy 26.935157 -369.266991) (xy 26.895008 -369.228282)
			(xy 26.860922 -369.184139) (xy 26.833626 -369.135504) (xy 26.813703 -369.083413) (xy 26.801577 -369.028976)
			(xy 26.797506 -368.973354) (xy 24.530952 -368.973354) (xy 24.546755 -369.007065) (xy 24.562823 -369.060472)
			(xy 24.570943 -369.115648) (xy 24.571452 -369.143534) (xy 24.570943 -369.17142) (xy 24.562823 -369.226596)
			(xy 24.546755 -369.280003) (xy 24.523083 -369.3305) (xy 24.49231 -369.377013) (xy 24.455093 -369.41855)
			(xy 24.412225 -369.454225) (xy 24.364619 -369.483279) (xy 24.31329 -369.505091) (xy 24.259333 -369.519197)
			(xy 24.203896 -369.525297) (xy 24.148162 -369.52326) (xy 24.093319 -369.51313) (xy 24.040535 -369.495123)
			(xy 23.990935 -369.469622) (xy 23.945577 -369.437171) (xy 23.905428 -369.398462) (xy 23.871342 -369.354319)
			(xy 23.844046 -369.305684) (xy 23.824123 -369.253593) (xy 23.811997 -369.199156) (xy 23.807926 -369.143534)
			(xy 21.593048 -369.143534) (xy 21.593048 -370.933488) (xy 29.519874 -370.933488) (xy 29.519874 -370.846588)
			(xy 29.527892 -370.760059) (xy 29.54386 -370.674639) (xy 29.567641 -370.591057) (xy 29.599033 -370.510025)
			(xy 29.637767 -370.432236) (xy 29.683514 -370.358352) (xy 29.735883 -370.289005) (xy 29.794427 -370.224785)
			(xy 29.858647 -370.166241) (xy 29.927994 -370.113872) (xy 30.001878 -370.068125) (xy 30.079667 -370.029391)
			(xy 30.160699 -369.997999) (xy 30.244281 -369.974218) (xy 30.329701 -369.95825) (xy 30.41623 -369.950232)
			(xy 30.50313 -369.950232) (xy 30.589659 -369.95825) (xy 30.675079 -369.974218) (xy 30.758661 -369.997999)
			(xy 30.839693 -370.029391) (xy 30.917482 -370.068125) (xy 30.991366 -370.113872) (xy 31.060713 -370.166241)
			(xy 31.124933 -370.224785) (xy 31.183477 -370.289005) (xy 31.235846 -370.358352) (xy 31.281593 -370.432236)
			(xy 31.320327 -370.510025) (xy 31.351719 -370.591057) (xy 31.3755 -370.674639) (xy 31.391468 -370.760059)
			(xy 31.399486 -370.846588) (xy 31.399988 -370.890038) (xy 31.399486 -370.933488) (xy 34.599874 -370.933488)
			(xy 34.599874 -370.846588) (xy 34.607892 -370.760059) (xy 34.62386 -370.674639) (xy 34.647641 -370.591057)
			(xy 34.679033 -370.510025) (xy 34.717767 -370.432236) (xy 34.763514 -370.358352) (xy 34.815883 -370.289005)
			(xy 34.874427 -370.224785) (xy 34.938647 -370.166241) (xy 35.007994 -370.113872) (xy 35.081878 -370.068125)
			(xy 35.159667 -370.029391) (xy 35.240699 -369.997999) (xy 35.324281 -369.974218) (xy 35.409701 -369.95825)
			(xy 35.49623 -369.950232) (xy 35.58313 -369.950232) (xy 35.669659 -369.95825) (xy 35.755079 -369.974218)
			(xy 35.838661 -369.997999) (xy 35.919693 -370.029391) (xy 35.997482 -370.068125) (xy 36.04789 -370.099336)
			(xy 41.045128 -370.099336) (xy 41.049199 -370.043714) (xy 41.061325 -369.989277) (xy 41.081248 -369.937186)
			(xy 41.108544 -369.888551) (xy 41.14263 -369.844408) (xy 41.182779 -369.805699) (xy 41.228137 -369.773248)
			(xy 41.277737 -369.747747) (xy 41.330521 -369.72974) (xy 41.385364 -369.71961) (xy 41.441098 -369.717573)
			(xy 41.496535 -369.723673) (xy 41.550492 -369.737779) (xy 41.601821 -369.759591) (xy 41.649427 -369.788645)
			(xy 41.692295 -369.82432) (xy 41.729512 -369.865857) (xy 41.760285 -369.91237) (xy 41.783957 -369.962867)
			(xy 41.800025 -370.016274) (xy 41.808145 -370.07145) (xy 41.808654 -370.099336) (xy 41.808145 -370.127222)
			(xy 41.800025 -370.182398) (xy 41.783957 -370.235805) (xy 41.760285 -370.286302) (xy 41.729512 -370.332815)
			(xy 41.692295 -370.374352) (xy 41.649427 -370.410027) (xy 41.601821 -370.439081) (xy 41.550492 -370.460893)
			(xy 41.496535 -370.474999) (xy 41.441098 -370.481099) (xy 41.385364 -370.479062) (xy 41.330521 -370.468932)
			(xy 41.277737 -370.450925) (xy 41.228137 -370.425424) (xy 41.182779 -370.392973) (xy 41.14263 -370.354264)
			(xy 41.108544 -370.310121) (xy 41.081248 -370.261486) (xy 41.061325 -370.209395) (xy 41.049199 -370.154958)
			(xy 41.045128 -370.099336) (xy 36.04789 -370.099336) (xy 36.071366 -370.113872) (xy 36.140713 -370.166241)
			(xy 36.204933 -370.224785) (xy 36.263477 -370.289005) (xy 36.315846 -370.358352) (xy 36.361593 -370.432236)
			(xy 36.400327 -370.510025) (xy 36.431719 -370.591057) (xy 36.4555 -370.674639) (xy 36.471468 -370.760059)
			(xy 36.479486 -370.846588) (xy 36.479988 -370.890038) (xy 36.479486 -370.933488) (xy 36.471468 -371.020017)
			(xy 36.4555 -371.105437) (xy 36.431719 -371.189019) (xy 36.400327 -371.270051) (xy 36.361593 -371.34784)
			(xy 36.315846 -371.421724) (xy 36.263477 -371.491071) (xy 36.243163 -371.513354) (xy 40.899078 -371.513354)
			(xy 40.903149 -371.457732) (xy 40.915275 -371.403295) (xy 40.935198 -371.351204) (xy 40.962494 -371.302569)
			(xy 40.99658 -371.258426) (xy 41.036729 -371.219717) (xy 41.082087 -371.187266) (xy 41.131687 -371.161765)
			(xy 41.184471 -371.143758) (xy 41.239314 -371.133628) (xy 41.295048 -371.131591) (xy 41.350485 -371.137691)
			(xy 41.404442 -371.151797) (xy 41.455771 -371.173609) (xy 41.503377 -371.202663) (xy 41.546245 -371.238338)
			(xy 41.583462 -371.279875) (xy 41.614235 -371.326388) (xy 41.637907 -371.376885) (xy 41.653975 -371.430292)
			(xy 41.662095 -371.485468) (xy 41.662604 -371.513354) (xy 41.662095 -371.54124) (xy 41.653975 -371.596416)
			(xy 41.637907 -371.649823) (xy 41.614235 -371.70032) (xy 41.583462 -371.746833) (xy 41.546245 -371.78837)
			(xy 41.503377 -371.824045) (xy 41.455771 -371.853099) (xy 41.404442 -371.874911) (xy 41.350485 -371.889017)
			(xy 41.295048 -371.895117) (xy 41.239314 -371.89308) (xy 41.184471 -371.88295) (xy 41.131687 -371.864943)
			(xy 41.082087 -371.839442) (xy 41.036729 -371.806991) (xy 40.99658 -371.768282) (xy 40.962494 -371.724139)
			(xy 40.935198 -371.675504) (xy 40.915275 -371.623413) (xy 40.903149 -371.568976) (xy 40.899078 -371.513354)
			(xy 36.243163 -371.513354) (xy 36.204933 -371.555291) (xy 36.140713 -371.613835) (xy 36.071366 -371.666204)
			(xy 35.997482 -371.711951) (xy 35.919693 -371.750685) (xy 35.838661 -371.782077) (xy 35.755079 -371.805858)
			(xy 35.669659 -371.821826) (xy 35.58313 -371.829844) (xy 35.49623 -371.829844) (xy 35.409701 -371.821826)
			(xy 35.324281 -371.805858) (xy 35.240699 -371.782077) (xy 35.159667 -371.750685) (xy 35.081878 -371.711951)
			(xy 35.007994 -371.666204) (xy 34.938647 -371.613835) (xy 34.874427 -371.555291) (xy 34.815883 -371.491071)
			(xy 34.763514 -371.421724) (xy 34.717767 -371.34784) (xy 34.679033 -371.270051) (xy 34.647641 -371.189019)
			(xy 34.62386 -371.105437) (xy 34.607892 -371.020017) (xy 34.599874 -370.933488) (xy 31.399486 -370.933488)
			(xy 31.391468 -371.020017) (xy 31.3755 -371.105437) (xy 31.351719 -371.189019) (xy 31.320327 -371.270051)
			(xy 31.281593 -371.34784) (xy 31.235846 -371.421724) (xy 31.183477 -371.491071) (xy 31.124933 -371.555291)
			(xy 31.060713 -371.613835) (xy 30.991366 -371.666204) (xy 30.917482 -371.711951) (xy 30.839693 -371.750685)
			(xy 30.758661 -371.782077) (xy 30.675079 -371.805858) (xy 30.589659 -371.821826) (xy 30.50313 -371.829844)
			(xy 30.41623 -371.829844) (xy 30.329701 -371.821826) (xy 30.244281 -371.805858) (xy 30.160699 -371.782077)
			(xy 30.079667 -371.750685) (xy 30.001878 -371.711951) (xy 29.927994 -371.666204) (xy 29.858647 -371.613835)
			(xy 29.794427 -371.555291) (xy 29.735883 -371.491071) (xy 29.683514 -371.421724) (xy 29.637767 -371.34784)
			(xy 29.599033 -371.270051) (xy 29.567641 -371.189019) (xy 29.54386 -371.105437) (xy 29.527892 -371.020017)
			(xy 29.519874 -370.933488) (xy 21.593048 -370.933488) (xy 21.593048 -371.345968) (xy 21.947886 -371.700806)
			(xy 27.195778 -371.700806) (xy 27.199849 -371.645184) (xy 27.211975 -371.590747) (xy 27.231898 -371.538656)
			(xy 27.259194 -371.490021) (xy 27.29328 -371.445878) (xy 27.333429 -371.407169) (xy 27.378787 -371.374718)
			(xy 27.428387 -371.349217) (xy 27.481171 -371.33121) (xy 27.536014 -371.32108) (xy 27.591748 -371.319043)
			(xy 27.647185 -371.325143) (xy 27.701142 -371.339249) (xy 27.752471 -371.361061) (xy 27.800077 -371.390115)
			(xy 27.842945 -371.42579) (xy 27.880162 -371.467327) (xy 27.910935 -371.51384) (xy 27.934607 -371.564337)
			(xy 27.950675 -371.617744) (xy 27.958795 -371.67292) (xy 27.959304 -371.700806) (xy 27.958795 -371.728692)
			(xy 27.950675 -371.783868) (xy 27.934607 -371.837275) (xy 27.910935 -371.887772) (xy 27.880162 -371.934285)
			(xy 27.842945 -371.975822) (xy 27.800077 -372.011497) (xy 27.752471 -372.040551) (xy 27.701142 -372.062363)
			(xy 27.647185 -372.076469) (xy 27.591748 -372.082569) (xy 27.536014 -372.080532) (xy 27.481171 -372.070402)
			(xy 27.428387 -372.052395) (xy 27.378787 -372.026894) (xy 27.333429 -371.994443) (xy 27.29328 -371.955734)
			(xy 27.259194 -371.911591) (xy 27.231898 -371.862956) (xy 27.211975 -371.810865) (xy 27.199849 -371.756428)
			(xy 27.195778 -371.700806) (xy 21.947886 -371.700806) (xy 23.720568 -373.473488) (xy 29.519874 -373.473488)
			(xy 29.519874 -373.386588) (xy 29.527892 -373.300059) (xy 29.54386 -373.214639) (xy 29.567641 -373.131057)
			(xy 29.599033 -373.050025) (xy 29.637767 -372.972236) (xy 29.683514 -372.898352) (xy 29.735883 -372.829005)
			(xy 29.794427 -372.764785) (xy 29.858647 -372.706241) (xy 29.927994 -372.653872) (xy 30.001878 -372.608125)
			(xy 30.079667 -372.569391) (xy 30.160699 -372.537999) (xy 30.244281 -372.514218) (xy 30.329701 -372.49825)
			(xy 30.41623 -372.490232) (xy 30.50313 -372.490232) (xy 30.589659 -372.49825) (xy 30.675079 -372.514218)
			(xy 30.758661 -372.537999) (xy 30.839693 -372.569391) (xy 30.917482 -372.608125) (xy 30.991366 -372.653872)
			(xy 31.060713 -372.706241) (xy 31.124933 -372.764785) (xy 31.183477 -372.829005) (xy 31.235846 -372.898352)
			(xy 31.281593 -372.972236) (xy 31.320327 -373.050025) (xy 31.351719 -373.131057) (xy 31.3755 -373.214639)
			(xy 31.391468 -373.300059) (xy 31.399486 -373.386588) (xy 31.399988 -373.430038) (xy 31.399486 -373.473488)
			(xy 34.599874 -373.473488) (xy 34.599874 -373.386588) (xy 34.607892 -373.300059) (xy 34.62386 -373.214639)
			(xy 34.647641 -373.131057) (xy 34.679033 -373.050025) (xy 34.717767 -372.972236) (xy 34.763514 -372.898352)
			(xy 34.815883 -372.829005) (xy 34.874427 -372.764785) (xy 34.938647 -372.706241) (xy 35.007994 -372.653872)
			(xy 35.081878 -372.608125) (xy 35.159667 -372.569391) (xy 35.240699 -372.537999) (xy 35.324281 -372.514218)
			(xy 35.409701 -372.49825) (xy 35.49623 -372.490232) (xy 35.58313 -372.490232) (xy 35.669659 -372.49825)
			(xy 35.755079 -372.514218) (xy 35.838661 -372.537999) (xy 35.919693 -372.569391) (xy 35.997482 -372.608125)
			(xy 36.071366 -372.653872) (xy 36.140713 -372.706241) (xy 36.204933 -372.764785) (xy 36.263477 -372.829005)
			(xy 36.315846 -372.898352) (xy 36.361593 -372.972236) (xy 36.400327 -373.050025) (xy 36.431719 -373.131057)
			(xy 36.4555 -373.214639) (xy 36.471468 -373.300059) (xy 36.479486 -373.386588) (xy 36.479988 -373.430038)
			(xy 36.479486 -373.473488) (xy 36.471468 -373.560017) (xy 36.4555 -373.645437) (xy 36.431719 -373.729019)
			(xy 36.431138 -373.73052) (xy 40.82745 -373.73052) (xy 40.831521 -373.674898) (xy 40.843647 -373.620461)
			(xy 40.86357 -373.56837) (xy 40.890866 -373.519735) (xy 40.924952 -373.475592) (xy 40.965101 -373.436883)
			(xy 41.010459 -373.404432) (xy 41.060059 -373.378931) (xy 41.112843 -373.360924) (xy 41.167686 -373.350794)
			(xy 41.22342 -373.348757) (xy 41.278857 -373.354857) (xy 41.332814 -373.368963) (xy 41.384143 -373.390775)
			(xy 41.431749 -373.419829) (xy 41.474617 -373.455504) (xy 41.511834 -373.497041) (xy 41.542607 -373.543554)
			(xy 41.566279 -373.594051) (xy 41.582347 -373.647458) (xy 41.590467 -373.702634) (xy 41.590976 -373.73052)
			(xy 41.590467 -373.758406) (xy 41.582347 -373.813582) (xy 41.566279 -373.866989) (xy 41.542607 -373.917486)
			(xy 41.511834 -373.963999) (xy 41.474617 -374.005536) (xy 41.431749 -374.041211) (xy 41.384143 -374.070265)
			(xy 41.332814 -374.092077) (xy 41.278857 -374.106183) (xy 41.22342 -374.112283) (xy 41.167686 -374.110246)
			(xy 41.112843 -374.100116) (xy 41.060059 -374.082109) (xy 41.010459 -374.056608) (xy 40.965101 -374.024157)
			(xy 40.924952 -373.985448) (xy 40.890866 -373.941305) (xy 40.86357 -373.89267) (xy 40.843647 -373.840579)
			(xy 40.831521 -373.786142) (xy 40.82745 -373.73052) (xy 36.431138 -373.73052) (xy 36.400327 -373.810051)
			(xy 36.361593 -373.88784) (xy 36.315846 -373.961724) (xy 36.263477 -374.031071) (xy 36.204933 -374.095291)
			(xy 36.140713 -374.153835) (xy 36.071366 -374.206204) (xy 35.997482 -374.251951) (xy 35.919693 -374.290685)
			(xy 35.838661 -374.322077) (xy 35.755079 -374.345858) (xy 35.669659 -374.361826) (xy 35.58313 -374.369844)
			(xy 35.49623 -374.369844) (xy 35.409701 -374.361826) (xy 35.324281 -374.345858) (xy 35.240699 -374.322077)
			(xy 35.159667 -374.290685) (xy 35.081878 -374.251951) (xy 35.007994 -374.206204) (xy 34.938647 -374.153835)
			(xy 34.874427 -374.095291) (xy 34.815883 -374.031071) (xy 34.763514 -373.961724) (xy 34.717767 -373.88784)
			(xy 34.679033 -373.810051) (xy 34.647641 -373.729019) (xy 34.62386 -373.645437) (xy 34.607892 -373.560017)
			(xy 34.599874 -373.473488) (xy 31.399486 -373.473488) (xy 31.391468 -373.560017) (xy 31.3755 -373.645437)
			(xy 31.351719 -373.729019) (xy 31.320327 -373.810051) (xy 31.281593 -373.88784) (xy 31.235846 -373.961724)
			(xy 31.183477 -374.031071) (xy 31.124933 -374.095291) (xy 31.060713 -374.153835) (xy 30.991366 -374.206204)
			(xy 30.917482 -374.251951) (xy 30.839693 -374.290685) (xy 30.758661 -374.322077) (xy 30.675079 -374.345858)
			(xy 30.589659 -374.361826) (xy 30.50313 -374.369844) (xy 30.41623 -374.369844) (xy 30.329701 -374.361826)
			(xy 30.244281 -374.345858) (xy 30.160699 -374.322077) (xy 30.079667 -374.290685) (xy 30.001878 -374.251951)
			(xy 29.927994 -374.206204) (xy 29.858647 -374.153835) (xy 29.794427 -374.095291) (xy 29.735883 -374.031071)
			(xy 29.683514 -373.961724) (xy 29.637767 -373.88784) (xy 29.599033 -373.810051) (xy 29.567641 -373.729019)
			(xy 29.54386 -373.645437) (xy 29.527892 -373.560017) (xy 29.519874 -373.473488) (xy 23.720568 -373.473488)
			(xy 24.362156 -374.115076) (xy 26.403552 -374.115076) (xy 26.407623 -374.059454) (xy 26.419749 -374.005017)
			(xy 26.439672 -373.952926) (xy 26.466968 -373.904291) (xy 26.501054 -373.860148) (xy 26.541203 -373.821439)
			(xy 26.586561 -373.788988) (xy 26.636161 -373.763487) (xy 26.688945 -373.74548) (xy 26.743788 -373.73535)
			(xy 26.799522 -373.733313) (xy 26.854959 -373.739413) (xy 26.908916 -373.753519) (xy 26.960245 -373.775331)
			(xy 27.007851 -373.804385) (xy 27.050719 -373.84006) (xy 27.087936 -373.881597) (xy 27.118709 -373.92811)
			(xy 27.142381 -373.978607) (xy 27.158449 -374.032014) (xy 27.166569 -374.08719) (xy 27.167078 -374.115076)
			(xy 27.166569 -374.142962) (xy 27.158449 -374.198138) (xy 27.142381 -374.251545) (xy 27.118709 -374.302042)
			(xy 27.087936 -374.348555) (xy 27.050719 -374.390092) (xy 27.007851 -374.425767) (xy 26.960245 -374.454821)
			(xy 26.908916 -374.476633) (xy 26.904823 -374.477703) (xy 47.298092 -374.477703) (xy 47.298092 -374.396593)
			(xy 47.306042 -374.315874) (xy 47.321865 -374.236323) (xy 47.34541 -374.158707) (xy 47.376449 -374.083771)
			(xy 47.414684 -374.012239) (xy 47.459746 -373.944799) (xy 47.511201 -373.8821) (xy 47.568554 -373.824747)
			(xy 47.631253 -373.773292) (xy 47.698693 -373.72823) (xy 47.770225 -373.689995) (xy 47.845161 -373.658956)
			(xy 47.922777 -373.635411) (xy 48.002328 -373.619588) (xy 48.083047 -373.611638) (xy 48.164157 -373.611638)
			(xy 48.244876 -373.619588) (xy 48.324427 -373.635411) (xy 48.402043 -373.658956) (xy 48.476979 -373.689995)
			(xy 48.548511 -373.72823) (xy 48.615951 -373.773292) (xy 48.67865 -373.824747) (xy 48.736003 -373.8821)
			(xy 48.787458 -373.944799) (xy 48.83252 -374.012239) (xy 48.870755 -374.083771) (xy 48.901794 -374.158707)
			(xy 48.925339 -374.236323) (xy 48.941162 -374.315874) (xy 48.949112 -374.396593) (xy 48.94961 -374.437148)
			(xy 48.949112 -374.477703) (xy 50.798212 -374.477703) (xy 50.798212 -374.396593) (xy 50.806162 -374.315874)
			(xy 50.821985 -374.236323) (xy 50.84553 -374.158707) (xy 50.876569 -374.083771) (xy 50.914804 -374.012239)
			(xy 50.959866 -373.944799) (xy 51.011321 -373.8821) (xy 51.068674 -373.824747) (xy 51.131373 -373.773292)
			(xy 51.198813 -373.72823) (xy 51.270345 -373.689995) (xy 51.345281 -373.658956) (xy 51.422897 -373.635411)
			(xy 51.502448 -373.619588) (xy 51.583167 -373.611638) (xy 51.664277 -373.611638) (xy 51.744996 -373.619588)
			(xy 51.824547 -373.635411) (xy 51.902163 -373.658956) (xy 51.977099 -373.689995) (xy 52.048631 -373.72823)
			(xy 52.116071 -373.773292) (xy 52.17877 -373.824747) (xy 52.236123 -373.8821) (xy 52.287578 -373.944799)
			(xy 52.33264 -374.012239) (xy 52.370875 -374.083771) (xy 52.401914 -374.158707) (xy 52.425459 -374.236323)
			(xy 52.441282 -374.315874) (xy 52.449232 -374.396593) (xy 52.44973 -374.437148) (xy 52.449232 -374.477703)
			(xy 52.441282 -374.558422) (xy 52.425459 -374.637973) (xy 52.401914 -374.715589) (xy 52.370875 -374.790525)
			(xy 52.33264 -374.862057) (xy 52.287578 -374.929497) (xy 52.236123 -374.992196) (xy 52.17877 -375.049549)
			(xy 52.116071 -375.101004) (xy 52.048631 -375.146066) (xy 51.977099 -375.184301) (xy 51.902163 -375.21534)
			(xy 51.824547 -375.238885) (xy 51.744996 -375.254708) (xy 51.664277 -375.262658) (xy 51.583167 -375.262658)
			(xy 51.502448 -375.254708) (xy 51.422897 -375.238885) (xy 51.345281 -375.21534) (xy 51.270345 -375.184301)
			(xy 51.198813 -375.146066) (xy 51.131373 -375.101004) (xy 51.068674 -375.049549) (xy 51.011321 -374.992196)
			(xy 50.959866 -374.929497) (xy 50.914804 -374.862057) (xy 50.876569 -374.790525) (xy 50.84553 -374.715589)
			(xy 50.821985 -374.637973) (xy 50.806162 -374.558422) (xy 50.798212 -374.477703) (xy 48.949112 -374.477703)
			(xy 48.941162 -374.558422) (xy 48.925339 -374.637973) (xy 48.901794 -374.715589) (xy 48.870755 -374.790525)
			(xy 48.83252 -374.862057) (xy 48.787458 -374.929497) (xy 48.736003 -374.992196) (xy 48.67865 -375.049549)
			(xy 48.615951 -375.101004) (xy 48.548511 -375.146066) (xy 48.476979 -375.184301) (xy 48.402043 -375.21534)
			(xy 48.324427 -375.238885) (xy 48.244876 -375.254708) (xy 48.164157 -375.262658) (xy 48.083047 -375.262658)
			(xy 48.002328 -375.254708) (xy 47.922777 -375.238885) (xy 47.845161 -375.21534) (xy 47.770225 -375.184301)
			(xy 47.698693 -375.146066) (xy 47.631253 -375.101004) (xy 47.568554 -375.049549) (xy 47.511201 -374.992196)
			(xy 47.459746 -374.929497) (xy 47.414684 -374.862057) (xy 47.376449 -374.790525) (xy 47.34541 -374.715589)
			(xy 47.321865 -374.637973) (xy 47.306042 -374.558422) (xy 47.298092 -374.477703) (xy 26.904823 -374.477703)
			(xy 26.854959 -374.490739) (xy 26.799522 -374.496839) (xy 26.743788 -374.494802) (xy 26.688945 -374.484672)
			(xy 26.636161 -374.466665) (xy 26.586561 -374.441164) (xy 26.541203 -374.408713) (xy 26.501054 -374.370004)
			(xy 26.466968 -374.325861) (xy 26.439672 -374.277226) (xy 26.419749 -374.225135) (xy 26.407623 -374.170698)
			(xy 26.403552 -374.115076) (xy 24.362156 -374.115076) (xy 26.260568 -376.013488) (xy 29.519874 -376.013488)
			(xy 29.519874 -375.926588) (xy 29.527892 -375.840059) (xy 29.54386 -375.754639) (xy 29.567641 -375.671057)
			(xy 29.599033 -375.590025) (xy 29.637767 -375.512236) (xy 29.683514 -375.438352) (xy 29.735883 -375.369005)
			(xy 29.794427 -375.304785) (xy 29.858647 -375.246241) (xy 29.927994 -375.193872) (xy 30.001878 -375.148125)
			(xy 30.079667 -375.109391) (xy 30.160699 -375.077999) (xy 30.244281 -375.054218) (xy 30.329701 -375.03825)
			(xy 30.41623 -375.030232) (xy 30.50313 -375.030232) (xy 30.589659 -375.03825) (xy 30.675079 -375.054218)
			(xy 30.758661 -375.077999) (xy 30.839693 -375.109391) (xy 30.917482 -375.148125) (xy 30.991366 -375.193872)
			(xy 31.060713 -375.246241) (xy 31.124933 -375.304785) (xy 31.183477 -375.369005) (xy 31.235846 -375.438352)
			(xy 31.281593 -375.512236) (xy 31.320327 -375.590025) (xy 31.351719 -375.671057) (xy 31.3755 -375.754639)
			(xy 31.391468 -375.840059) (xy 31.399486 -375.926588) (xy 31.399988 -375.970038) (xy 31.399486 -376.013488)
			(xy 34.599874 -376.013488) (xy 34.599874 -375.926588) (xy 34.607892 -375.840059) (xy 34.62386 -375.754639)
			(xy 34.647641 -375.671057) (xy 34.679033 -375.590025) (xy 34.717767 -375.512236) (xy 34.763514 -375.438352)
			(xy 34.815883 -375.369005) (xy 34.874427 -375.304785) (xy 34.938647 -375.246241) (xy 35.007994 -375.193872)
			(xy 35.081878 -375.148125) (xy 35.159667 -375.109391) (xy 35.240699 -375.077999) (xy 35.324281 -375.054218)
			(xy 35.409701 -375.03825) (xy 35.49623 -375.030232) (xy 35.58313 -375.030232) (xy 35.669659 -375.03825)
			(xy 35.755079 -375.054218) (xy 35.838661 -375.077999) (xy 35.919693 -375.109391) (xy 35.997482 -375.148125)
			(xy 36.064299 -375.189496) (xy 40.058846 -375.189496) (xy 40.062917 -375.133874) (xy 40.075043 -375.079437)
			(xy 40.094966 -375.027346) (xy 40.122262 -374.978711) (xy 40.156348 -374.934568) (xy 40.196497 -374.895859)
			(xy 40.241855 -374.863408) (xy 40.291455 -374.837907) (xy 40.344239 -374.8199) (xy 40.399082 -374.80977)
			(xy 40.454816 -374.807733) (xy 40.510253 -374.813833) (xy 40.56421 -374.827939) (xy 40.615539 -374.849751)
			(xy 40.663145 -374.878805) (xy 40.706013 -374.91448) (xy 40.74323 -374.956017) (xy 40.774003 -375.00253)
			(xy 40.797675 -375.053027) (xy 40.813743 -375.106434) (xy 40.821863 -375.16161) (xy 40.822372 -375.189496)
			(xy 40.821863 -375.217382) (xy 40.813743 -375.272558) (xy 40.797675 -375.325965) (xy 40.774003 -375.376462)
			(xy 40.74323 -375.422975) (xy 40.706013 -375.464512) (xy 40.663145 -375.500187) (xy 40.615539 -375.529241)
			(xy 40.56421 -375.551053) (xy 40.510253 -375.565159) (xy 40.454816 -375.571259) (xy 40.399082 -375.569222)
			(xy 40.344239 -375.559092) (xy 40.291455 -375.541085) (xy 40.241855 -375.515584) (xy 40.196497 -375.483133)
			(xy 40.156348 -375.444424) (xy 40.122262 -375.400281) (xy 40.094966 -375.351646) (xy 40.075043 -375.299555)
			(xy 40.062917 -375.245118) (xy 40.058846 -375.189496) (xy 36.064299 -375.189496) (xy 36.071366 -375.193872)
			(xy 36.140713 -375.246241) (xy 36.204933 -375.304785) (xy 36.263477 -375.369005) (xy 36.315846 -375.438352)
			(xy 36.361593 -375.512236) (xy 36.400327 -375.590025) (xy 36.431719 -375.671057) (xy 36.4555 -375.754639)
			(xy 36.459585 -375.77649) (xy 69.600316 -375.77649) (xy 69.604387 -375.720868) (xy 69.616513 -375.666431)
			(xy 69.636436 -375.61434) (xy 69.663732 -375.565705) (xy 69.697818 -375.521562) (xy 69.737967 -375.482853)
			(xy 69.783325 -375.450402) (xy 69.832925 -375.424901) (xy 69.885709 -375.406894) (xy 69.940552 -375.396764)
			(xy 69.996286 -375.394727) (xy 70.051723 -375.400827) (xy 70.10568 -375.414933) (xy 70.157009 -375.436745)
			(xy 70.204615 -375.465799) (xy 70.247483 -375.501474) (xy 70.2847 -375.543011) (xy 70.315473 -375.589524)
			(xy 70.339145 -375.640021) (xy 70.355213 -375.693428) (xy 70.363333 -375.748604) (xy 70.363842 -375.77649)
			(xy 70.735442 -375.77649) (xy 70.739513 -375.720868) (xy 70.751639 -375.666431) (xy 70.771562 -375.61434)
			(xy 70.798858 -375.565705) (xy 70.832944 -375.521562) (xy 70.873093 -375.482853) (xy 70.918451 -375.450402)
			(xy 70.968051 -375.424901) (xy 71.020835 -375.406894) (xy 71.075678 -375.396764) (xy 71.131412 -375.394727)
			(xy 71.186849 -375.400827) (xy 71.240806 -375.414933) (xy 71.292135 -375.436745) (xy 71.339741 -375.465799)
			(xy 71.382609 -375.501474) (xy 71.419826 -375.543011) (xy 71.450599 -375.589524) (xy 71.474271 -375.640021)
			(xy 71.490339 -375.693428) (xy 71.498459 -375.748604) (xy 71.498968 -375.77649) (xy 71.498459 -375.804376)
			(xy 71.490339 -375.859552) (xy 71.474271 -375.912959) (xy 71.450599 -375.963456) (xy 71.419826 -376.009969)
			(xy 71.382609 -376.051506) (xy 71.339741 -376.087181) (xy 71.292135 -376.116235) (xy 71.240806 -376.138047)
			(xy 71.186849 -376.152153) (xy 71.131412 -376.158253) (xy 71.075678 -376.156216) (xy 71.020835 -376.146086)
			(xy 70.968051 -376.128079) (xy 70.918451 -376.102578) (xy 70.873093 -376.070127) (xy 70.832944 -376.031418)
			(xy 70.798858 -375.987275) (xy 70.771562 -375.93864) (xy 70.751639 -375.886549) (xy 70.739513 -375.832112)
			(xy 70.735442 -375.77649) (xy 70.363842 -375.77649) (xy 70.363333 -375.804376) (xy 70.355213 -375.859552)
			(xy 70.339145 -375.912959) (xy 70.315473 -375.963456) (xy 70.2847 -376.009969) (xy 70.247483 -376.051506)
			(xy 70.204615 -376.087181) (xy 70.157009 -376.116235) (xy 70.10568 -376.138047) (xy 70.051723 -376.152153)
			(xy 69.996286 -376.158253) (xy 69.940552 -376.156216) (xy 69.885709 -376.146086) (xy 69.832925 -376.128079)
			(xy 69.783325 -376.102578) (xy 69.737967 -376.070127) (xy 69.697818 -376.031418) (xy 69.663732 -375.987275)
			(xy 69.636436 -375.93864) (xy 69.616513 -375.886549) (xy 69.604387 -375.832112) (xy 69.600316 -375.77649)
			(xy 36.459585 -375.77649) (xy 36.471468 -375.840059) (xy 36.479486 -375.926588) (xy 36.479988 -375.970038)
			(xy 36.479486 -376.013488) (xy 36.471468 -376.100017) (xy 36.4555 -376.185437) (xy 36.431719 -376.269019)
			(xy 36.400327 -376.350051) (xy 36.361593 -376.42784) (xy 36.315846 -376.501724) (xy 36.263477 -376.571071)
			(xy 36.204933 -376.635291) (xy 36.140713 -376.693835) (xy 36.071366 -376.746204) (xy 35.997482 -376.791951)
			(xy 35.99691 -376.792236) (xy 40.137586 -376.792236) (xy 40.141657 -376.736614) (xy 40.153783 -376.682177)
			(xy 40.173706 -376.630086) (xy 40.201002 -376.581451) (xy 40.235088 -376.537308) (xy 40.275237 -376.498599)
			(xy 40.320595 -376.466148) (xy 40.370195 -376.440647) (xy 40.422979 -376.42264) (xy 40.477822 -376.41251)
			(xy 40.533556 -376.410473) (xy 40.588993 -376.416573) (xy 40.64295 -376.430679) (xy 40.694279 -376.452491)
			(xy 40.741885 -376.481545) (xy 40.784753 -376.51722) (xy 40.82197 -376.558757) (xy 40.852743 -376.60527)
			(xy 40.860136 -376.62104) (xy 68.257418 -376.62104) (xy 68.261489 -376.565418) (xy 68.273615 -376.510981)
			(xy 68.293538 -376.45889) (xy 68.320834 -376.410255) (xy 68.35492 -376.366112) (xy 68.395069 -376.327403)
			(xy 68.440427 -376.294952) (xy 68.490027 -376.269451) (xy 68.542811 -376.251444) (xy 68.597654 -376.241314)
			(xy 68.653388 -376.239277) (xy 68.708825 -376.245377) (xy 68.762782 -376.259483) (xy 68.814111 -376.281295)
			(xy 68.861717 -376.310349) (xy 68.904585 -376.346024) (xy 68.941802 -376.387561) (xy 68.972575 -376.434074)
			(xy 68.996247 -376.484571) (xy 69.012315 -376.537978) (xy 69.020435 -376.593154) (xy 69.020944 -376.62104)
			(xy 69.020435 -376.648926) (xy 69.012315 -376.704102) (xy 68.996247 -376.757509) (xy 68.972575 -376.808006)
			(xy 68.941802 -376.854519) (xy 68.904585 -376.896056) (xy 68.861717 -376.931731) (xy 68.814111 -376.960785)
			(xy 68.762782 -376.982597) (xy 68.708825 -376.996703) (xy 68.653388 -377.002803) (xy 68.597654 -377.000766)
			(xy 68.542811 -376.990636) (xy 68.490027 -376.972629) (xy 68.440427 -376.947128) (xy 68.395069 -376.914677)
			(xy 68.35492 -376.875968) (xy 68.320834 -376.831825) (xy 68.293538 -376.78319) (xy 68.273615 -376.731099)
			(xy 68.261489 -376.676662) (xy 68.257418 -376.62104) (xy 40.860136 -376.62104) (xy 40.876415 -376.655767)
			(xy 40.892483 -376.709174) (xy 40.900603 -376.76435) (xy 40.901112 -376.792236) (xy 40.900603 -376.820122)
			(xy 40.892483 -376.875298) (xy 40.876415 -376.928705) (xy 40.852743 -376.979202) (xy 40.82197 -377.025715)
			(xy 40.784753 -377.067252) (xy 40.741885 -377.102927) (xy 40.694279 -377.131981) (xy 40.64295 -377.153793)
			(xy 40.588993 -377.167899) (xy 40.533556 -377.173999) (xy 40.477822 -377.171962) (xy 40.422979 -377.161832)
			(xy 40.370195 -377.143825) (xy 40.320595 -377.118324) (xy 40.275237 -377.085873) (xy 40.235088 -377.047164)
			(xy 40.201002 -377.003021) (xy 40.173706 -376.954386) (xy 40.153783 -376.902295) (xy 40.141657 -376.847858)
			(xy 40.137586 -376.792236) (xy 35.99691 -376.792236) (xy 35.919693 -376.830685) (xy 35.838661 -376.862077)
			(xy 35.755079 -376.885858) (xy 35.669659 -376.901826) (xy 35.58313 -376.909844) (xy 35.49623 -376.909844)
			(xy 35.409701 -376.901826) (xy 35.324281 -376.885858) (xy 35.240699 -376.862077) (xy 35.159667 -376.830685)
			(xy 35.081878 -376.791951) (xy 35.007994 -376.746204) (xy 34.938647 -376.693835) (xy 34.874427 -376.635291)
			(xy 34.815883 -376.571071) (xy 34.763514 -376.501724) (xy 34.717767 -376.42784) (xy 34.679033 -376.350051)
			(xy 34.647641 -376.269019) (xy 34.62386 -376.185437) (xy 34.607892 -376.100017) (xy 34.599874 -376.013488)
			(xy 31.399486 -376.013488) (xy 31.391468 -376.100017) (xy 31.3755 -376.185437) (xy 31.351719 -376.269019)
			(xy 31.320327 -376.350051) (xy 31.281593 -376.42784) (xy 31.235846 -376.501724) (xy 31.183477 -376.571071)
			(xy 31.124933 -376.635291) (xy 31.060713 -376.693835) (xy 30.991366 -376.746204) (xy 30.917482 -376.791951)
			(xy 30.839693 -376.830685) (xy 30.758661 -376.862077) (xy 30.675079 -376.885858) (xy 30.589659 -376.901826)
			(xy 30.50313 -376.909844) (xy 30.41623 -376.909844) (xy 30.329701 -376.901826) (xy 30.244281 -376.885858)
			(xy 30.160699 -376.862077) (xy 30.079667 -376.830685) (xy 30.001878 -376.791951) (xy 29.927994 -376.746204)
			(xy 29.858647 -376.693835) (xy 29.794427 -376.635291) (xy 29.735883 -376.571071) (xy 29.683514 -376.501724)
			(xy 29.637767 -376.42784) (xy 29.599033 -376.350051) (xy 29.567641 -376.269019) (xy 29.54386 -376.185437)
			(xy 29.527892 -376.100017) (xy 29.519874 -376.013488) (xy 26.260568 -376.013488) (xy 28.270708 -378.023628)
			(xy 28.287158 -378.039361) (xy 28.324559 -378.065297) (xy 28.365979 -378.084162) (xy 28.410095 -378.095352)
			(xy 28.455499 -378.098511) (xy 28.50074 -378.093537) (xy 28.544373 -378.080589) (xy 28.585005 -378.060081)
			(xy 28.603448 -378.046742) (xy 28.625542 -378.030619) (xy 28.673429 -378.00419) (xy 28.724599 -377.98487)
			(xy 28.778003 -377.973057) (xy 28.832548 -377.968991) (xy 28.887114 -377.972756) (xy 28.940582 -377.984275)
			(xy 28.991858 -378.003312) (xy 29.03989 -378.029477) (xy 29.083692 -378.062233) (xy 29.122368 -378.100909)
			(xy 29.155123 -378.144711) (xy 29.181288 -378.192743) (xy 29.200325 -378.244019) (xy 29.211844 -378.297488)
			(xy 29.215609 -378.352053) (xy 29.211543 -378.406598) (xy 29.199729 -378.460002) (xy 29.18041 -378.511172)
			(xy 29.157056 -378.553488) (xy 29.519874 -378.553488) (xy 29.519874 -378.466588) (xy 29.527892 -378.380059)
			(xy 29.54386 -378.294639) (xy 29.567641 -378.211057) (xy 29.599033 -378.130025) (xy 29.637767 -378.052236)
			(xy 29.683514 -377.978352) (xy 29.735883 -377.909005) (xy 29.794427 -377.844785) (xy 29.858647 -377.786241)
			(xy 29.927994 -377.733872) (xy 30.001878 -377.688125) (xy 30.079667 -377.649391) (xy 30.160699 -377.617999)
			(xy 30.244281 -377.594218) (xy 30.329701 -377.57825) (xy 30.41623 -377.570232) (xy 30.50313 -377.570232)
			(xy 30.589659 -377.57825) (xy 30.675079 -377.594218) (xy 30.758661 -377.617999) (xy 30.839693 -377.649391)
			(xy 30.917482 -377.688125) (xy 30.991366 -377.733872) (xy 31.060713 -377.786241) (xy 31.124933 -377.844785)
			(xy 31.183477 -377.909005) (xy 31.235846 -377.978352) (xy 31.281593 -378.052236) (xy 31.320327 -378.130025)
			(xy 31.351719 -378.211057) (xy 31.3755 -378.294639) (xy 31.391468 -378.380059) (xy 31.399486 -378.466588)
			(xy 31.399988 -378.510038) (xy 31.399486 -378.553488) (xy 34.599874 -378.553488) (xy 34.599874 -378.466588)
			(xy 34.607892 -378.380059) (xy 34.62386 -378.294639) (xy 34.647641 -378.211057) (xy 34.679033 -378.130025)
			(xy 34.717767 -378.052236) (xy 34.763514 -377.978352) (xy 34.815883 -377.909005) (xy 34.874427 -377.844785)
			(xy 34.938647 -377.786241) (xy 35.007994 -377.733872) (xy 35.081878 -377.688125) (xy 35.159667 -377.649391)
			(xy 35.240699 -377.617999) (xy 35.324281 -377.594218) (xy 35.409701 -377.57825) (xy 35.49623 -377.570232)
			(xy 35.58313 -377.570232) (xy 35.669659 -377.57825) (xy 35.755079 -377.594218) (xy 35.838661 -377.617999)
			(xy 35.919693 -377.649391) (xy 35.997482 -377.688125) (xy 36.071366 -377.733872) (xy 36.140713 -377.786241)
			(xy 36.204933 -377.844785) (xy 36.263477 -377.909005) (xy 36.315846 -377.978352) (xy 36.361593 -378.052236)
			(xy 36.400327 -378.130025) (xy 36.431719 -378.211057) (xy 36.4555 -378.294639) (xy 36.471468 -378.380059)
			(xy 36.479486 -378.466588) (xy 36.479988 -378.510038) (xy 36.479486 -378.553488) (xy 36.471468 -378.640017)
			(xy 36.4555 -378.725437) (xy 36.431719 -378.809019) (xy 36.400327 -378.890051) (xy 36.361593 -378.96784)
			(xy 36.315846 -379.041724) (xy 36.263477 -379.111071) (xy 36.204933 -379.175291) (xy 36.140713 -379.233835)
			(xy 36.071366 -379.286204) (xy 35.997482 -379.331951) (xy 35.919693 -379.370685) (xy 35.838661 -379.402077)
			(xy 35.755079 -379.425858) (xy 35.669659 -379.441826) (xy 35.58313 -379.449844) (xy 35.49623 -379.449844)
			(xy 35.409701 -379.441826) (xy 35.324281 -379.425858) (xy 35.240699 -379.402077) (xy 35.159667 -379.370685)
			(xy 35.081878 -379.331951) (xy 35.007994 -379.286204) (xy 34.938647 -379.233835) (xy 34.874427 -379.175291)
			(xy 34.815883 -379.111071) (xy 34.763514 -379.041724) (xy 34.717767 -378.96784) (xy 34.679033 -378.890051)
			(xy 34.647641 -378.809019) (xy 34.62386 -378.725437) (xy 34.607892 -378.640017) (xy 34.599874 -378.553488)
			(xy 31.399486 -378.553488) (xy 31.391468 -378.640017) (xy 31.3755 -378.725437) (xy 31.351719 -378.809019)
			(xy 31.320327 -378.890051) (xy 31.281593 -378.96784) (xy 31.235846 -379.041724) (xy 31.183477 -379.111071)
			(xy 31.124933 -379.175291) (xy 31.060713 -379.233835) (xy 30.991366 -379.286204) (xy 30.917482 -379.331951)
			(xy 30.839693 -379.370685) (xy 30.758661 -379.402077) (xy 30.675079 -379.425858) (xy 30.589659 -379.441826)
			(xy 30.50313 -379.449844) (xy 30.41623 -379.449844) (xy 30.329701 -379.441826) (xy 30.244281 -379.425858)
			(xy 30.160699 -379.402077) (xy 30.079667 -379.370685) (xy 30.001878 -379.331951) (xy 29.927994 -379.286204)
			(xy 29.858647 -379.233835) (xy 29.794427 -379.175291) (xy 29.735883 -379.111071) (xy 29.683514 -379.041724)
			(xy 29.637767 -378.96784) (xy 29.599033 -378.890051) (xy 29.567641 -378.809019) (xy 29.54386 -378.725437)
			(xy 29.527892 -378.640017) (xy 29.519874 -378.553488) (xy 29.157056 -378.553488) (xy 29.153981 -378.559059)
			(xy 29.137864 -378.581158) (xy 29.124541 -378.59962) (xy 29.103995 -378.640243) (xy 29.091018 -378.683877)
			(xy 29.086024 -378.729125) (xy 29.089173 -378.774539) (xy 29.100365 -378.818665) (xy 29.119242 -378.86009)
			(xy 29.145198 -378.897488) (xy 29.160978 -378.913898) (xy 29.203142 -378.956062) (xy 29.254196 -379.00737)
			(xy 29.254196 -381.093488) (xy 29.519874 -381.093488) (xy 29.519874 -381.006588) (xy 29.527892 -380.920059)
			(xy 29.54386 -380.834639) (xy 29.567641 -380.751057) (xy 29.599033 -380.670025) (xy 29.637767 -380.592236)
			(xy 29.683514 -380.518352) (xy 29.735883 -380.449005) (xy 29.794427 -380.384785) (xy 29.858647 -380.326241)
			(xy 29.927994 -380.273872) (xy 30.001878 -380.228125) (xy 30.079667 -380.189391) (xy 30.160699 -380.157999)
			(xy 30.244281 -380.134218) (xy 30.329701 -380.11825) (xy 30.41623 -380.110232) (xy 30.50313 -380.110232)
			(xy 30.589659 -380.11825) (xy 30.675079 -380.134218) (xy 30.758661 -380.157999) (xy 30.839693 -380.189391)
			(xy 30.917482 -380.228125) (xy 30.991366 -380.273872) (xy 31.060713 -380.326241) (xy 31.124933 -380.384785)
			(xy 31.183477 -380.449005) (xy 31.235846 -380.518352) (xy 31.281593 -380.592236) (xy 31.320327 -380.670025)
			(xy 31.351719 -380.751057) (xy 31.3755 -380.834639) (xy 31.391468 -380.920059) (xy 31.399486 -381.006588)
			(xy 31.399988 -381.050038) (xy 31.399486 -381.093488) (xy 34.599874 -381.093488) (xy 34.599874 -381.006588)
			(xy 34.607892 -380.920059) (xy 34.62386 -380.834639) (xy 34.647641 -380.751057) (xy 34.679033 -380.670025)
			(xy 34.717767 -380.592236) (xy 34.763514 -380.518352) (xy 34.815883 -380.449005) (xy 34.874427 -380.384785)
			(xy 34.938647 -380.326241) (xy 35.007994 -380.273872) (xy 35.081878 -380.228125) (xy 35.159667 -380.189391)
			(xy 35.240699 -380.157999) (xy 35.324281 -380.134218) (xy 35.409701 -380.11825) (xy 35.49623 -380.110232)
			(xy 35.58313 -380.110232) (xy 35.669659 -380.11825) (xy 35.755079 -380.134218) (xy 35.838661 -380.157999)
			(xy 35.919693 -380.189391) (xy 35.997482 -380.228125) (xy 36.071366 -380.273872) (xy 36.140713 -380.326241)
			(xy 36.204933 -380.384785) (xy 36.263477 -380.449005) (xy 36.315846 -380.518352) (xy 36.361593 -380.592236)
			(xy 36.400327 -380.670025) (xy 36.431719 -380.751057) (xy 36.446236 -380.80208) (xy 38.761819 -380.80208)
			(xy 38.765709 -380.747731) (xy 38.777295 -380.694489) (xy 38.79634 -380.643437) (xy 38.822456 -380.595616)
			(xy 38.855113 -380.551999) (xy 38.893645 -380.513473) (xy 38.937268 -380.480823) (xy 38.985093 -380.454714)
			(xy 39.036147 -380.435678) (xy 39.089391 -380.424101) (xy 39.14374 -380.420219) (xy 39.198089 -380.424112)
			(xy 39.251331 -380.4357) (xy 39.302381 -380.454748) (xy 39.350201 -380.480867) (xy 39.372286 -380.496826)
			(xy 39.391298 -380.510422) (xy 39.433181 -380.531154) (xy 39.478149 -380.54388) (xy 39.524686 -380.54817)
			(xy 39.571223 -380.54388) (xy 39.616191 -380.531154) (xy 39.658074 -380.510422) (xy 39.677086 -380.496826)
			(xy 39.699143 -380.480819) (xy 39.746971 -380.454692) (xy 39.798031 -380.435637) (xy 39.851283 -380.424044)
			(xy 39.905644 -380.420148) (xy 39.960005 -380.424028) (xy 40.01326 -380.435606) (xy 40.064326 -380.454645)
			(xy 40.112162 -380.480758) (xy 40.155795 -380.513414) (xy 40.194336 -380.551947) (xy 40.227 -380.595573)
			(xy 40.253123 -380.643404) (xy 40.272173 -380.694466) (xy 40.283761 -380.747719) (xy 40.287652 -380.80208)
			(xy 40.648512 -380.80208) (xy 40.652402 -380.747729) (xy 40.663988 -380.694485) (xy 40.683034 -380.643433)
			(xy 40.709152 -380.59561) (xy 40.74181 -380.551992) (xy 40.780343 -380.513465) (xy 40.823967 -380.480815)
			(xy 40.871794 -380.454706) (xy 40.92285 -380.435669) (xy 40.976096 -380.424093) (xy 41.030447 -380.420212)
			(xy 41.084798 -380.424106) (xy 41.13804 -380.435696) (xy 41.189092 -380.454745) (xy 41.236912 -380.480866)
			(xy 41.258998 -380.496826) (xy 41.27801 -380.510422) (xy 41.319893 -380.531154) (xy 41.364861 -380.54388)
			(xy 41.411398 -380.54817) (xy 41.457935 -380.54388) (xy 41.502903 -380.531154) (xy 41.544786 -380.510422)
			(xy 41.563798 -380.496826) (xy 41.585854 -380.48082) (xy 41.633682 -380.454695) (xy 41.684741 -380.435642)
			(xy 41.737992 -380.42405) (xy 41.79235 -380.420155) (xy 41.84671 -380.424036) (xy 41.899964 -380.435614)
			(xy 41.951028 -380.454653) (xy 41.998862 -380.480766) (xy 42.042493 -380.513421) (xy 42.081033 -380.551954)
			(xy 42.113696 -380.595579) (xy 42.139818 -380.643409) (xy 42.158866 -380.694469) (xy 42.170454 -380.747721)
			(xy 42.174345 -380.80208) (xy 42.17046 -380.856439) (xy 42.158878 -380.909692) (xy 42.139835 -380.960754)
			(xy 42.113718 -381.008587) (xy 42.081059 -381.052215) (xy 42.042524 -381.090752) (xy 41.998897 -381.123412)
			(xy 41.951065 -381.14953) (xy 41.900003 -381.168574) (xy 41.84675 -381.180158) (xy 41.792391 -381.184045)
			(xy 41.738032 -381.180156) (xy 41.68478 -381.16857) (xy 41.633719 -381.149522) (xy 41.585889 -381.123402)
			(xy 41.563798 -381.107442) (xy 41.544786 -381.093846) (xy 41.502903 -381.073114) (xy 41.457935 -381.060388)
			(xy 41.411398 -381.056098) (xy 41.364861 -381.060388) (xy 41.319893 -381.073114) (xy 41.27801 -381.093846)
			(xy 41.258998 -381.107442) (xy 41.236878 -381.123356) (xy 41.189055 -381.149472) (xy 41.138001 -381.168516)
			(xy 41.084757 -381.1801) (xy 41.030407 -381.183988) (xy 40.976056 -381.180102) (xy 40.922811 -381.168519)
			(xy 40.871757 -381.149477) (xy 40.823933 -381.123363) (xy 40.780312 -381.090708) (xy 40.741783 -381.052177)
			(xy 40.70913 -381.008555) (xy 40.683017 -380.96073) (xy 40.663977 -380.909675) (xy 40.652396 -380.856431)
			(xy 40.648512 -380.80208) (xy 40.287652 -380.80208) (xy 40.283767 -380.85644) (xy 40.272184 -380.909695)
			(xy 40.25314 -380.960759) (xy 40.227023 -381.008593) (xy 40.194363 -381.052222) (xy 40.155826 -381.09076)
			(xy 40.112197 -381.12342) (xy 40.064363 -381.149538) (xy 40.0133 -381.168583) (xy 39.960045 -381.180166)
			(xy 39.905684 -381.184052) (xy 39.851324 -381.180162) (xy 39.79807 -381.168574) (xy 39.747008 -381.149525)
			(xy 39.699177 -381.123403) (xy 39.677086 -381.107442) (xy 39.658074 -381.093846) (xy 39.616191 -381.073114)
			(xy 39.571223 -381.060388) (xy 39.524686 -381.056098) (xy 39.478149 -381.060388) (xy 39.433181 -381.073114)
			(xy 39.391298 -381.093846) (xy 39.372286 -381.107442) (xy 39.350166 -381.123355) (xy 39.302344 -381.149469)
			(xy 39.251291 -381.168511) (xy 39.198049 -381.180094) (xy 39.1437 -381.183981) (xy 39.089351 -381.180094)
			(xy 39.036108 -381.168511) (xy 38.985056 -381.149469) (xy 38.937233 -381.123355) (xy 38.893614 -381.0907)
			(xy 38.855086 -381.05217) (xy 38.822434 -381.008549) (xy 38.796323 -380.960725) (xy 38.777283 -380.909672)
			(xy 38.765703 -380.856429) (xy 38.761819 -380.80208) (xy 36.446236 -380.80208) (xy 36.4555 -380.834639)
			(xy 36.471468 -380.920059) (xy 36.479486 -381.006588) (xy 36.479988 -381.050038) (xy 36.479486 -381.093488)
			(xy 36.471468 -381.180017) (xy 36.4555 -381.265437) (xy 36.431719 -381.349019) (xy 36.400327 -381.430051)
			(xy 36.361593 -381.50784) (xy 36.315846 -381.581724) (xy 36.263477 -381.651071) (xy 36.204933 -381.715291)
			(xy 36.140713 -381.773835) (xy 36.071366 -381.826204) (xy 35.997482 -381.871951) (xy 35.919693 -381.910685)
			(xy 35.838661 -381.942077) (xy 35.755079 -381.965858) (xy 35.669659 -381.981826) (xy 35.58313 -381.989844)
			(xy 35.49623 -381.989844) (xy 35.409701 -381.981826) (xy 35.324281 -381.965858) (xy 35.240699 -381.942077)
			(xy 35.159667 -381.910685) (xy 35.081878 -381.871951) (xy 35.007994 -381.826204) (xy 34.938647 -381.773835)
			(xy 34.874427 -381.715291) (xy 34.815883 -381.651071) (xy 34.763514 -381.581724) (xy 34.717767 -381.50784)
			(xy 34.679033 -381.430051) (xy 34.647641 -381.349019) (xy 34.62386 -381.265437) (xy 34.607892 -381.180017)
			(xy 34.599874 -381.093488) (xy 31.399486 -381.093488) (xy 31.391468 -381.180017) (xy 31.3755 -381.265437)
			(xy 31.351719 -381.349019) (xy 31.320327 -381.430051) (xy 31.281593 -381.50784) (xy 31.235846 -381.581724)
			(xy 31.183477 -381.651071) (xy 31.124933 -381.715291) (xy 31.060713 -381.773835) (xy 30.991366 -381.826204)
			(xy 30.917482 -381.871951) (xy 30.839693 -381.910685) (xy 30.758661 -381.942077) (xy 30.675079 -381.965858)
			(xy 30.589659 -381.981826) (xy 30.50313 -381.989844) (xy 30.41623 -381.989844) (xy 30.329701 -381.981826)
			(xy 30.244281 -381.965858) (xy 30.160699 -381.942077) (xy 30.079667 -381.910685) (xy 30.001878 -381.871951)
			(xy 29.927994 -381.826204) (xy 29.858647 -381.773835) (xy 29.794427 -381.715291) (xy 29.735883 -381.651071)
			(xy 29.683514 -381.581724) (xy 29.637767 -381.50784) (xy 29.599033 -381.430051) (xy 29.567641 -381.349019)
			(xy 29.54386 -381.265437) (xy 29.527892 -381.180017) (xy 29.519874 -381.093488) (xy 29.254196 -381.093488)
			(xy 29.254196 -382.635824) (xy 38.76176 -382.635824) (xy 38.765644 -382.581466) (xy 38.777225 -382.528215)
			(xy 38.796267 -382.477153) (xy 38.822382 -382.429322) (xy 38.855039 -382.385694) (xy 38.893573 -382.347157)
			(xy 38.937198 -382.314498) (xy 38.985028 -382.288379) (xy 39.036088 -382.269333) (xy 39.089339 -382.257748)
			(xy 39.143696 -382.25386) (xy 39.198054 -382.257747) (xy 39.251305 -382.269331) (xy 39.302365 -382.288376)
			(xy 39.350195 -382.314493) (xy 39.372286 -382.330452) (xy 39.391298 -382.344048) (xy 39.433181 -382.36478)
			(xy 39.478149 -382.377506) (xy 39.524686 -382.381796) (xy 39.571223 -382.377506) (xy 39.616191 -382.36478)
			(xy 39.658074 -382.344048) (xy 39.677086 -382.330452) (xy 39.699212 -382.314545) (xy 39.747036 -382.288427)
			(xy 39.798091 -382.269382) (xy 39.851336 -382.257796) (xy 39.905688 -382.253907) (xy 39.96004 -382.257793)
			(xy 40.013286 -382.269375) (xy 40.064342 -382.288417) (xy 40.112168 -382.314532) (xy 40.15579 -382.347187)
			(xy 40.19432 -382.385719) (xy 40.226975 -382.429342) (xy 40.253088 -382.477169) (xy 40.272128 -382.528225)
			(xy 40.283709 -382.581471) (xy 40.287593 -382.635824) (xy 40.648453 -382.635824) (xy 40.652337 -382.581465)
			(xy 40.663919 -382.528211) (xy 40.682962 -382.477149) (xy 40.709078 -382.429316) (xy 40.741736 -382.385687)
			(xy 40.780271 -382.34715) (xy 40.823898 -382.314489) (xy 40.871729 -382.28837) (xy 40.922791 -382.269325)
			(xy 40.976044 -382.25774) (xy 41.030403 -382.253853) (xy 41.084762 -382.257741) (xy 41.138014 -382.269326)
			(xy 41.189076 -382.288373) (xy 41.236907 -382.314492) (xy 41.258998 -382.330452) (xy 41.27801 -382.344048)
			(xy 41.319893 -382.36478) (xy 41.364861 -382.377506) (xy 41.411398 -382.381796) (xy 41.457935 -382.377506)
			(xy 41.502903 -382.36478) (xy 41.544786 -382.344048) (xy 41.563798 -382.330452) (xy 41.585924 -382.314546)
			(xy 41.633747 -382.28843) (xy 41.6848 -382.269386) (xy 41.738044 -382.257802) (xy 41.792395 -382.253914)
			(xy 41.846746 -382.257801) (xy 41.89999 -382.269383) (xy 41.951044 -382.288426) (xy 41.998868 -382.31454)
			(xy 42.042488 -382.347195) (xy 42.081017 -382.385726) (xy 42.11367 -382.429348) (xy 42.139782 -382.477174)
			(xy 42.158822 -382.528228) (xy 42.170402 -382.581473) (xy 42.174286 -382.635824) (xy 42.889427 -382.635824)
			(xy 42.893313 -382.581459) (xy 42.904896 -382.5282) (xy 42.923941 -382.477132) (xy 42.950061 -382.429295)
			(xy 42.982724 -382.385662) (xy 43.021264 -382.347122) (xy 43.064897 -382.31446) (xy 43.112735 -382.28834)
			(xy 43.163803 -382.269295) (xy 43.217062 -382.257712) (xy 43.271427 -382.253827) (xy 43.325791 -382.25772)
			(xy 43.379049 -382.26931) (xy 43.430114 -382.288362) (xy 43.477948 -382.314489) (xy 43.50004 -382.330452)
			(xy 43.519052 -382.344048) (xy 43.560935 -382.36478) (xy 43.605903 -382.377506) (xy 43.65244 -382.381796)
			(xy 43.698977 -382.377506) (xy 43.743945 -382.36478) (xy 43.785828 -382.344048) (xy 43.80484 -382.330452)
			(xy 43.826965 -382.314549) (xy 43.874785 -382.28844) (xy 43.925834 -382.269403) (xy 43.979074 -382.257824)
			(xy 44.033419 -382.253939) (xy 44.087763 -382.257829) (xy 44.141001 -382.269413) (xy 44.192049 -382.288456)
			(xy 44.239867 -382.31457) (xy 44.283481 -382.347223) (xy 44.322005 -382.385751) (xy 44.354653 -382.429369)
			(xy 44.380762 -382.47719) (xy 44.399799 -382.52824) (xy 44.411377 -382.581479) (xy 44.415261 -382.635824)
			(xy 44.793437 -382.635824) (xy 44.797322 -382.581461) (xy 44.808905 -382.528204) (xy 44.827949 -382.477138)
			(xy 44.854068 -382.429303) (xy 44.886728 -382.385671) (xy 44.925267 -382.347133) (xy 44.968897 -382.314471)
			(xy 45.016733 -382.288352) (xy 45.067798 -382.269306) (xy 45.121055 -382.257723) (xy 45.175418 -382.253837)
			(xy 45.22978 -382.257728) (xy 45.283036 -382.269316) (xy 45.3341 -382.288366) (xy 45.381932 -382.31449)
			(xy 45.404024 -382.330452) (xy 45.423036 -382.344048) (xy 45.464919 -382.36478) (xy 45.509887 -382.377506)
			(xy 45.556424 -382.381796) (xy 45.602961 -382.377506) (xy 45.647929 -382.36478) (xy 45.689812 -382.344048)
			(xy 45.708824 -382.330452) (xy 45.730949 -382.314548) (xy 45.778771 -382.288436) (xy 45.829821 -382.269396)
			(xy 45.883062 -382.257816) (xy 45.93741 -382.25393) (xy 45.991757 -382.257818) (xy 46.044997 -382.269402)
			(xy 46.096047 -382.288444) (xy 46.143867 -382.314558) (xy 46.187484 -382.347212) (xy 46.22601 -382.385741)
			(xy 46.25866 -382.429361) (xy 46.28477 -382.477184) (xy 46.303808 -382.528235) (xy 46.315386 -382.581477)
			(xy 46.31927 -382.635824) (xy 46.31538 -382.690171) (xy 46.303794 -382.743411) (xy 46.28475 -382.79446)
			(xy 46.258634 -382.842279) (xy 46.225978 -382.885895) (xy 46.187448 -382.924419) (xy 46.143827 -382.957068)
			(xy 46.096003 -382.983176) (xy 46.044951 -383.002212) (xy 45.991709 -383.013789) (xy 45.937362 -383.01767)
			(xy 45.883015 -383.013778) (xy 45.829775 -383.00219) (xy 45.778727 -382.983144) (xy 45.730909 -382.957026)
			(xy 45.708824 -382.941068) (xy 45.689812 -382.927472) (xy 45.647929 -382.90674) (xy 45.602961 -382.894014)
			(xy 45.556424 -382.889724) (xy 45.509887 -382.894014) (xy 45.464919 -382.90674) (xy 45.423036 -382.927472)
			(xy 45.404024 -382.941068) (xy 45.381973 -382.957084) (xy 45.334143 -382.983214) (xy 45.283082 -383.00227)
			(xy 45.229828 -383.013865) (xy 45.175466 -383.017763) (xy 45.121102 -383.013884) (xy 45.067844 -383.002307)
			(xy 45.016776 -382.983268) (xy 44.968938 -382.957155) (xy 44.925303 -382.924499) (xy 44.88676 -382.885965)
			(xy 44.854094 -382.842338) (xy 44.827969 -382.794505) (xy 44.808918 -382.743442) (xy 44.797329 -382.690187)
			(xy 44.793437 -382.635824) (xy 44.415261 -382.635824) (xy 44.41137 -382.690169) (xy 44.399785 -382.743406)
			(xy 44.380742 -382.794454) (xy 44.354628 -382.842271) (xy 44.321974 -382.885885) (xy 44.283445 -382.924409)
			(xy 44.239826 -382.957056) (xy 44.192005 -382.983164) (xy 44.140955 -383.0022) (xy 44.087716 -383.013778)
			(xy 44.033371 -383.017661) (xy 43.979026 -383.01377) (xy 43.925788 -383.002184) (xy 43.874741 -382.98314)
			(xy 43.826924 -382.957025) (xy 43.80484 -382.941068) (xy 43.785828 -382.927472) (xy 43.743945 -382.90674)
			(xy 43.698977 -382.894014) (xy 43.65244 -382.889724) (xy 43.605903 -382.894014) (xy 43.560935 -382.90674)
			(xy 43.519052 -382.927472) (xy 43.50004 -382.941068) (xy 43.477988 -382.957085) (xy 43.430158 -382.983218)
			(xy 43.379095 -383.002276) (xy 43.325839 -383.013873) (xy 43.271475 -383.017773) (xy 43.217109 -383.013895)
			(xy 43.163849 -383.002318) (xy 43.112778 -382.98328) (xy 43.064937 -382.957166) (xy 43.0213 -382.924509)
			(xy 42.982755 -382.885974) (xy 42.950087 -382.842346) (xy 42.923961 -382.794512) (xy 42.904909 -382.743446)
			(xy 42.893319 -382.690189) (xy 42.889427 -382.635824) (xy 42.174286 -382.635824) (xy 42.170395 -382.690174)
			(xy 42.158808 -382.743418) (xy 42.139762 -382.79447) (xy 42.113644 -382.842292) (xy 42.080986 -382.88591)
			(xy 42.042452 -382.924436) (xy 41.998827 -382.957086) (xy 41.951 -382.983194) (xy 41.899944 -383.00223)
			(xy 41.846698 -383.013806) (xy 41.792347 -383.017686) (xy 41.737997 -383.013791) (xy 41.684754 -383.0022)
			(xy 41.633703 -382.98315) (xy 41.585883 -382.957028) (xy 41.563798 -382.941068) (xy 41.544786 -382.927472)
			(xy 41.502903 -382.90674) (xy 41.457935 -382.894014) (xy 41.411398 -382.889724) (xy 41.364861 -382.894014)
			(xy 41.319893 -382.90674) (xy 41.27801 -382.927472) (xy 41.258998 -382.941068) (xy 41.236947 -382.957082)
			(xy 41.18912 -382.983207) (xy 41.138061 -383.00226) (xy 41.08481 -383.013852) (xy 41.030451 -383.017747)
			(xy 40.976091 -383.013867) (xy 40.922837 -383.002289) (xy 40.871773 -382.98325) (xy 40.823938 -382.957137)
			(xy 40.780307 -382.924482) (xy 40.741767 -382.88595) (xy 40.709104 -382.842325) (xy 40.682981 -382.794495)
			(xy 40.663932 -382.743435) (xy 40.652344 -382.690183) (xy 40.648453 -382.635824) (xy 40.287593 -382.635824)
			(xy 40.283702 -382.690176) (xy 40.272115 -382.743421) (xy 40.253068 -382.794475) (xy 40.226949 -382.842298)
			(xy 40.194289 -382.885917) (xy 40.155754 -382.924444) (xy 40.112127 -382.957094) (xy 40.064298 -382.983203)
			(xy 40.01324 -383.002239) (xy 39.959993 -383.013814) (xy 39.90564 -383.017693) (xy 39.851288 -383.013797)
			(xy 39.798044 -383.002205) (xy 39.746992 -382.983153) (xy 39.699172 -382.957029) (xy 39.677086 -382.941068)
			(xy 39.658074 -382.927472) (xy 39.616191 -382.90674) (xy 39.571223 -382.894014) (xy 39.524686 -382.889724)
			(xy 39.478149 -382.894014) (xy 39.433181 -382.90674) (xy 39.391298 -382.927472) (xy 39.372286 -382.941068)
			(xy 39.350236 -382.957081) (xy 39.302409 -382.983204) (xy 39.251351 -383.002255) (xy 39.198101 -383.013846)
			(xy 39.143744 -383.01774) (xy 39.089386 -383.013859) (xy 39.036134 -383.00228) (xy 38.985071 -382.983241)
			(xy 38.937239 -382.957128) (xy 38.893609 -382.924474) (xy 38.855071 -382.885943) (xy 38.822408 -382.842319)
			(xy 38.796287 -382.79449) (xy 38.777239 -382.743432) (xy 38.765651 -382.690181) (xy 38.76176 -382.635824)
			(xy 29.254196 -382.635824) (xy 29.254196 -383.633488) (xy 29.519874 -383.633488) (xy 29.519874 -383.546588)
			(xy 29.527892 -383.460059) (xy 29.54386 -383.374639) (xy 29.567641 -383.291057) (xy 29.599033 -383.210025)
			(xy 29.637767 -383.132236) (xy 29.683514 -383.058352) (xy 29.735883 -382.989005) (xy 29.794427 -382.924785)
			(xy 29.858647 -382.866241) (xy 29.927994 -382.813872) (xy 30.001878 -382.768125) (xy 30.079667 -382.729391)
			(xy 30.160699 -382.697999) (xy 30.244281 -382.674218) (xy 30.329701 -382.65825) (xy 30.41623 -382.650232)
			(xy 30.50313 -382.650232) (xy 30.589659 -382.65825) (xy 30.675079 -382.674218) (xy 30.758661 -382.697999)
			(xy 30.839693 -382.729391) (xy 30.917482 -382.768125) (xy 30.991366 -382.813872) (xy 31.060713 -382.866241)
			(xy 31.124933 -382.924785) (xy 31.183477 -382.989005) (xy 31.235846 -383.058352) (xy 31.281593 -383.132236)
			(xy 31.320327 -383.210025) (xy 31.351719 -383.291057) (xy 31.3755 -383.374639) (xy 31.391468 -383.460059)
			(xy 31.399486 -383.546588) (xy 31.399988 -383.590038) (xy 31.399486 -383.633488) (xy 34.599874 -383.633488)
			(xy 34.599874 -383.546588) (xy 34.607892 -383.460059) (xy 34.62386 -383.374639) (xy 34.647641 -383.291057)
			(xy 34.679033 -383.210025) (xy 34.717767 -383.132236) (xy 34.763514 -383.058352) (xy 34.815883 -382.989005)
			(xy 34.874427 -382.924785) (xy 34.938647 -382.866241) (xy 35.007994 -382.813872) (xy 35.081878 -382.768125)
			(xy 35.159667 -382.729391) (xy 35.240699 -382.697999) (xy 35.324281 -382.674218) (xy 35.409701 -382.65825)
			(xy 35.49623 -382.650232) (xy 35.58313 -382.650232) (xy 35.669659 -382.65825) (xy 35.755079 -382.674218)
			(xy 35.838661 -382.697999) (xy 35.919693 -382.729391) (xy 35.997482 -382.768125) (xy 36.071366 -382.813872)
			(xy 36.140713 -382.866241) (xy 36.204933 -382.924785) (xy 36.263477 -382.989005) (xy 36.315846 -383.058352)
			(xy 36.361593 -383.132236) (xy 36.400327 -383.210025) (xy 36.431719 -383.291057) (xy 36.4555 -383.374639)
			(xy 36.471468 -383.460059) (xy 36.479486 -383.546588) (xy 36.479988 -383.590038) (xy 36.479486 -383.633488)
			(xy 36.471468 -383.720017) (xy 36.4555 -383.805437) (xy 36.431719 -383.889019) (xy 36.400327 -383.970051)
			(xy 36.361593 -384.04784) (xy 36.315846 -384.121724) (xy 36.263477 -384.191071) (xy 36.204933 -384.255291)
			(xy 36.140713 -384.313835) (xy 36.071366 -384.366204) (xy 35.997482 -384.411951) (xy 35.919693 -384.450685)
			(xy 35.838661 -384.482077) (xy 35.755079 -384.505858) (xy 35.669659 -384.521826) (xy 35.58313 -384.529844)
			(xy 35.49623 -384.529844) (xy 35.409701 -384.521826) (xy 35.324281 -384.505858) (xy 35.240699 -384.482077)
			(xy 35.159667 -384.450685) (xy 35.081878 -384.411951) (xy 35.007994 -384.366204) (xy 34.938647 -384.313835)
			(xy 34.874427 -384.255291) (xy 34.815883 -384.191071) (xy 34.763514 -384.121724) (xy 34.717767 -384.04784)
			(xy 34.679033 -383.970051) (xy 34.647641 -383.889019) (xy 34.62386 -383.805437) (xy 34.607892 -383.720017)
			(xy 34.599874 -383.633488) (xy 31.399486 -383.633488) (xy 31.391468 -383.720017) (xy 31.3755 -383.805437)
			(xy 31.351719 -383.889019) (xy 31.320327 -383.970051) (xy 31.281593 -384.04784) (xy 31.235846 -384.121724)
			(xy 31.183477 -384.191071) (xy 31.124933 -384.255291) (xy 31.060713 -384.313835) (xy 30.991366 -384.366204)
			(xy 30.917482 -384.411951) (xy 30.839693 -384.450685) (xy 30.758661 -384.482077) (xy 30.675079 -384.505858)
			(xy 30.589659 -384.521826) (xy 30.50313 -384.529844) (xy 30.41623 -384.529844) (xy 30.329701 -384.521826)
			(xy 30.244281 -384.505858) (xy 30.160699 -384.482077) (xy 30.079667 -384.450685) (xy 30.001878 -384.411951)
			(xy 29.927994 -384.366204) (xy 29.858647 -384.313835) (xy 29.794427 -384.255291) (xy 29.735883 -384.191071)
			(xy 29.683514 -384.121724) (xy 29.637767 -384.04784) (xy 29.599033 -383.970051) (xy 29.567641 -383.889019)
			(xy 29.54386 -383.805437) (xy 29.527892 -383.720017) (xy 29.519874 -383.633488) (xy 29.254196 -383.633488)
			(xy 29.254196 -384.536702) (xy 38.761789 -384.536702) (xy 38.765676 -384.482349) (xy 38.777259 -384.429102)
			(xy 38.796303 -384.378046) (xy 38.822418 -384.330219) (xy 38.855075 -384.286596) (xy 38.893608 -384.248065)
			(xy 38.937232 -384.21541) (xy 38.985059 -384.189296) (xy 39.036117 -384.170255) (xy 39.089364 -384.158674)
			(xy 39.143718 -384.154789) (xy 39.198071 -384.158679) (xy 39.251317 -384.170265) (xy 39.302373 -384.189311)
			(xy 39.350198 -384.215429) (xy 39.372286 -384.231388) (xy 39.391298 -384.244984) (xy 39.433181 -384.265716)
			(xy 39.478149 -384.278442) (xy 39.524686 -384.282732) (xy 39.571223 -384.278442) (xy 39.616191 -384.265716)
			(xy 39.658074 -384.244984) (xy 39.677086 -384.231388) (xy 39.699178 -384.215432) (xy 39.747004 -384.18931)
			(xy 39.798062 -384.17026) (xy 39.85131 -384.158671) (xy 39.905666 -384.154778) (xy 39.960023 -384.158661)
			(xy 40.013274 -384.170241) (xy 40.064334 -384.189282) (xy 40.112165 -384.215396) (xy 40.155793 -384.248052)
			(xy 40.194328 -384.286584) (xy 40.226987 -384.330209) (xy 40.253105 -384.378037) (xy 40.27215 -384.429096)
			(xy 40.283734 -384.482346) (xy 40.287622 -384.536702) (xy 40.648481 -384.536702) (xy 40.652369 -384.482347)
			(xy 40.663953 -384.429099) (xy 40.682997 -384.378041) (xy 40.709114 -384.330213) (xy 40.741772 -384.286589)
			(xy 40.780306 -384.248057) (xy 40.823932 -384.215402) (xy 40.871761 -384.189288) (xy 40.92282 -384.170246)
			(xy 40.976069 -384.158666) (xy 41.030425 -384.154781) (xy 41.084779 -384.158673) (xy 41.138027 -384.17026)
			(xy 41.189084 -384.189308) (xy 41.23691 -384.215428) (xy 41.258998 -384.231388) (xy 41.27801 -384.244984)
			(xy 41.319893 -384.265716) (xy 41.364861 -384.278442) (xy 41.411398 -384.282732) (xy 41.457935 -384.278442)
			(xy 41.502903 -384.265716) (xy 41.544786 -384.244984) (xy 41.563798 -384.231388) (xy 41.58589 -384.215433)
			(xy 41.633715 -384.189313) (xy 41.684771 -384.170265) (xy 41.738019 -384.158677) (xy 41.792373 -384.154785)
			(xy 41.846728 -384.158669) (xy 41.899977 -384.17025) (xy 41.951036 -384.189291) (xy 41.998865 -384.215404)
			(xy 42.042491 -384.248059) (xy 42.081025 -384.286591) (xy 42.113682 -384.330215) (xy 42.139799 -384.378042)
			(xy 42.158843 -384.429099) (xy 42.170427 -384.482348) (xy 42.174315 -384.536702) (xy 42.889456 -384.536702)
			(xy 42.893344 -384.482342) (xy 42.90493 -384.429087) (xy 42.923977 -384.378024) (xy 42.950097 -384.330192)
			(xy 42.98276 -384.286564) (xy 43.021299 -384.24803) (xy 43.064931 -384.215372) (xy 43.112766 -384.189257)
			(xy 43.163832 -384.170217) (xy 43.217087 -384.158638) (xy 43.271448 -384.154756) (xy 43.325809 -384.158651)
			(xy 43.379061 -384.170244) (xy 43.430122 -384.189298) (xy 43.477951 -384.215425) (xy 43.50004 -384.231388)
			(xy 43.519052 -384.244984) (xy 43.560935 -384.265716) (xy 43.605903 -384.278442) (xy 43.65244 -384.282732)
			(xy 43.698977 -384.278442) (xy 43.743945 -384.265716) (xy 43.785828 -384.244984) (xy 43.80484 -384.231388)
			(xy 43.826931 -384.215437) (xy 43.874753 -384.189323) (xy 43.925806 -384.170281) (xy 43.979048 -384.158698)
			(xy 44.033397 -384.154811) (xy 44.087746 -384.158697) (xy 44.140989 -384.170279) (xy 44.192041 -384.189321)
			(xy 44.239864 -384.215434) (xy 44.283484 -384.248087) (xy 44.322013 -384.286616) (xy 44.354666 -384.330235)
			(xy 44.380779 -384.378058) (xy 44.399821 -384.429111) (xy 44.411403 -384.482353) (xy 44.415289 -384.536702)
			(xy 44.793466 -384.536702) (xy 44.797354 -384.482344) (xy 44.808938 -384.429092) (xy 44.827984 -384.378031)
			(xy 44.854103 -384.3302) (xy 44.886764 -384.286574) (xy 44.925302 -384.24804) (xy 44.968931 -384.215384)
			(xy 45.016764 -384.189269) (xy 45.067827 -384.170228) (xy 45.12108 -384.158648) (xy 45.175439 -384.154766)
			(xy 45.229798 -384.15866) (xy 45.283048 -384.17025) (xy 45.334107 -384.189302) (xy 45.381935 -384.215426)
			(xy 45.404024 -384.231388) (xy 45.423036 -384.244984) (xy 45.464919 -384.265716) (xy 45.509887 -384.278442)
			(xy 45.556424 -384.282732) (xy 45.602961 -384.278442) (xy 45.647929 -384.265716) (xy 45.689812 -384.244984)
			(xy 45.708824 -384.231388) (xy 45.730915 -384.215435) (xy 45.778739 -384.189319) (xy 45.829793 -384.170275)
			(xy 45.883037 -384.15869) (xy 45.937388 -384.154801) (xy 45.991739 -384.158687) (xy 46.044984 -384.170268)
			(xy 46.096039 -384.189309) (xy 46.143864 -384.215423) (xy 46.187486 -384.248076) (xy 46.226017 -384.286606)
			(xy 46.258672 -384.330227) (xy 46.284787 -384.378052) (xy 46.303829 -384.429106) (xy 46.315412 -384.482351)
			(xy 46.318554 -384.526282) (xy 76.258418 -384.526282) (xy 76.262489 -384.47066) (xy 76.274615 -384.416223)
			(xy 76.294538 -384.364132) (xy 76.321834 -384.315497) (xy 76.35592 -384.271354) (xy 76.396069 -384.232645)
			(xy 76.441427 -384.200194) (xy 76.491027 -384.174693) (xy 76.543811 -384.156686) (xy 76.598654 -384.146556)
			(xy 76.654388 -384.144519) (xy 76.709825 -384.150619) (xy 76.763782 -384.164725) (xy 76.815111 -384.186537)
			(xy 76.862717 -384.215591) (xy 76.905585 -384.251266) (xy 76.942802 -384.292803) (xy 76.973575 -384.339316)
			(xy 76.997247 -384.389813) (xy 77.013315 -384.44322) (xy 77.021435 -384.498396) (xy 77.021944 -384.526282)
			(xy 79.347058 -384.526282) (xy 79.351129 -384.47066) (xy 79.363255 -384.416223) (xy 79.383178 -384.364132)
			(xy 79.410474 -384.315497) (xy 79.44456 -384.271354) (xy 79.484709 -384.232645) (xy 79.530067 -384.200194)
			(xy 79.579667 -384.174693) (xy 79.632451 -384.156686) (xy 79.687294 -384.146556) (xy 79.743028 -384.144519)
			(xy 79.798465 -384.150619) (xy 79.852422 -384.164725) (xy 79.903751 -384.186537) (xy 79.951357 -384.215591)
			(xy 79.994225 -384.251266) (xy 80.031442 -384.292803) (xy 80.062215 -384.339316) (xy 80.085887 -384.389813)
			(xy 80.101955 -384.44322) (xy 80.110075 -384.498396) (xy 80.110584 -384.526282) (xy 80.110075 -384.554168)
			(xy 80.101955 -384.609344) (xy 80.085887 -384.662751) (xy 80.062215 -384.713248) (xy 80.031442 -384.759761)
			(xy 79.994225 -384.801298) (xy 79.951357 -384.836973) (xy 79.903751 -384.866027) (xy 79.852422 -384.887839)
			(xy 79.798465 -384.901945) (xy 79.743028 -384.908045) (xy 79.687294 -384.906008) (xy 79.632451 -384.895878)
			(xy 79.579667 -384.877871) (xy 79.530067 -384.85237) (xy 79.484709 -384.819919) (xy 79.44456 -384.78121)
			(xy 79.410474 -384.737067) (xy 79.383178 -384.688432) (xy 79.363255 -384.636341) (xy 79.351129 -384.581904)
			(xy 79.347058 -384.526282) (xy 77.021944 -384.526282) (xy 77.021435 -384.554168) (xy 77.013315 -384.609344)
			(xy 76.997247 -384.662751) (xy 76.973575 -384.713248) (xy 76.942802 -384.759761) (xy 76.905585 -384.801298)
			(xy 76.862717 -384.836973) (xy 76.815111 -384.866027) (xy 76.763782 -384.887839) (xy 76.709825 -384.901945)
			(xy 76.654388 -384.908045) (xy 76.598654 -384.906008) (xy 76.543811 -384.895878) (xy 76.491027 -384.877871)
			(xy 76.441427 -384.85237) (xy 76.396069 -384.819919) (xy 76.35592 -384.78121) (xy 76.321834 -384.737067)
			(xy 76.294538 -384.688432) (xy 76.274615 -384.636341) (xy 76.262489 -384.581904) (xy 76.258418 -384.526282)
			(xy 46.318554 -384.526282) (xy 46.319299 -384.536702) (xy 46.315411 -384.591054) (xy 46.303828 -384.644298)
			(xy 46.284785 -384.695352) (xy 46.25867 -384.743177) (xy 46.226014 -384.786797) (xy 46.187483 -384.825327)
			(xy 46.14386 -384.85798) (xy 46.096035 -384.884093) (xy 46.04498 -384.903133) (xy 45.991735 -384.914714)
			(xy 45.937383 -384.918599) (xy 45.883032 -384.914709) (xy 45.829788 -384.903124) (xy 45.778735 -384.884079)
			(xy 45.730911 -384.857962) (xy 45.708824 -384.842004) (xy 45.689812 -384.828408) (xy 45.647929 -384.807676)
			(xy 45.602961 -384.79495) (xy 45.556424 -384.79066) (xy 45.509887 -384.79495) (xy 45.464919 -384.807676)
			(xy 45.423036 -384.828408) (xy 45.404024 -384.842004) (xy 45.381939 -384.857971) (xy 45.334112 -384.884096)
			(xy 45.283053 -384.903149) (xy 45.229802 -384.91474) (xy 45.175444 -384.918634) (xy 45.121085 -384.914752)
			(xy 45.067832 -384.903173) (xy 45.016769 -384.884133) (xy 44.968935 -384.858019) (xy 44.925305 -384.825363)
			(xy 44.886767 -384.78683) (xy 44.854106 -384.743204) (xy 44.827986 -384.695374) (xy 44.80894 -384.644313)
			(xy 44.797354 -384.591061) (xy 44.793466 -384.536702) (xy 44.415289 -384.536702) (xy 44.411402 -384.591051)
			(xy 44.399819 -384.644294) (xy 44.380777 -384.695346) (xy 44.354663 -384.743169) (xy 44.32201 -384.786788)
			(xy 44.28348 -384.825316) (xy 44.23986 -384.857969) (xy 44.192037 -384.884081) (xy 44.140984 -384.903122)
			(xy 44.087741 -384.914703) (xy 44.033392 -384.918589) (xy 43.979043 -384.914701) (xy 43.925801 -384.903118)
			(xy 43.874749 -384.884075) (xy 43.826927 -384.857961) (xy 43.80484 -384.842004) (xy 43.785828 -384.828408)
			(xy 43.743945 -384.807676) (xy 43.698977 -384.79495) (xy 43.65244 -384.79066) (xy 43.605903 -384.79495)
			(xy 43.560935 -384.807676) (xy 43.519052 -384.828408) (xy 43.50004 -384.842004) (xy 43.477955 -384.857973)
			(xy 43.430126 -384.8841) (xy 43.379066 -384.903155) (xy 43.325813 -384.914748) (xy 43.271453 -384.918644)
			(xy 43.217092 -384.914763) (xy 43.163836 -384.903185) (xy 43.112771 -384.884145) (xy 43.064935 -384.85803)
			(xy 43.021303 -384.825374) (xy 42.982763 -384.786839) (xy 42.9501 -384.743212) (xy 42.923979 -384.69538)
			(xy 42.904931 -384.644317) (xy 42.893345 -384.591063) (xy 42.889456 -384.536702) (xy 42.174315 -384.536702)
			(xy 42.170426 -384.591057) (xy 42.158842 -384.644305) (xy 42.139797 -384.695362) (xy 42.11368 -384.74319)
			(xy 42.081021 -384.786813) (xy 42.042487 -384.825344) (xy 41.998861 -384.857998) (xy 41.951032 -384.884111)
			(xy 41.899973 -384.903152) (xy 41.846723 -384.914731) (xy 41.792368 -384.918615) (xy 41.738014 -384.914722)
			(xy 41.684767 -384.903134) (xy 41.633711 -384.884085) (xy 41.585886 -384.857964) (xy 41.563798 -384.842004)
			(xy 41.544786 -384.828408) (xy 41.502903 -384.807676) (xy 41.457935 -384.79495) (xy 41.411398 -384.79066)
			(xy 41.364861 -384.79495) (xy 41.319893 -384.807676) (xy 41.27801 -384.828408) (xy 41.258998 -384.842004)
			(xy 41.236914 -384.857969) (xy 41.189088 -384.88409) (xy 41.138032 -384.903139) (xy 41.084784 -384.914727)
			(xy 41.030429 -384.918619) (xy 40.976074 -384.914735) (xy 40.922825 -384.903155) (xy 40.871765 -384.884114)
			(xy 40.823936 -384.858001) (xy 40.780309 -384.825346) (xy 40.741775 -384.786815) (xy 40.709116 -384.743191)
			(xy 40.682999 -384.695364) (xy 40.663954 -384.644306) (xy 40.65237 -384.591057) (xy 40.648481 -384.536702)
			(xy 40.287622 -384.536702) (xy 40.283733 -384.591059) (xy 40.272149 -384.644308) (xy 40.253103 -384.695367)
			(xy 40.226985 -384.743196) (xy 40.194325 -384.78682) (xy 40.155789 -384.825352) (xy 40.112161 -384.858007)
			(xy 40.06433 -384.88412) (xy 40.013269 -384.90316) (xy 39.960018 -384.914739) (xy 39.905662 -384.918622)
			(xy 39.851306 -384.914728) (xy 39.798057 -384.903139) (xy 39.747 -384.884088) (xy 39.699174 -384.857965)
			(xy 39.677086 -384.842004) (xy 39.658074 -384.828408) (xy 39.616191 -384.807676) (xy 39.571223 -384.79495)
			(xy 39.524686 -384.79066) (xy 39.478149 -384.79495) (xy 39.433181 -384.807676) (xy 39.391298 -384.828408)
			(xy 39.372286 -384.842004) (xy 39.350202 -384.857968) (xy 39.302377 -384.884087) (xy 39.251322 -384.903134)
			(xy 39.198076 -384.914721) (xy 39.143722 -384.918611) (xy 39.089369 -384.914727) (xy 39.036121 -384.903147)
			(xy 38.985064 -384.884106) (xy 38.937236 -384.857992) (xy 38.893611 -384.825338) (xy 38.855078 -384.786807)
			(xy 38.822421 -384.743185) (xy 38.796305 -384.695359) (xy 38.77726 -384.644303) (xy 38.765677 -384.591056)
			(xy 38.761789 -384.536702) (xy 29.254196 -384.536702) (xy 29.254196 -386.173488) (xy 29.519874 -386.173488)
			(xy 29.519874 -386.086588) (xy 29.527892 -386.000059) (xy 29.54386 -385.914639) (xy 29.567641 -385.831057)
			(xy 29.599033 -385.750025) (xy 29.637767 -385.672236) (xy 29.683514 -385.598352) (xy 29.735883 -385.529005)
			(xy 29.794427 -385.464785) (xy 29.858647 -385.406241) (xy 29.927994 -385.353872) (xy 30.001878 -385.308125)
			(xy 30.079667 -385.269391) (xy 30.160699 -385.237999) (xy 30.244281 -385.214218) (xy 30.329701 -385.19825)
			(xy 30.41623 -385.190232) (xy 30.50313 -385.190232) (xy 30.589659 -385.19825) (xy 30.675079 -385.214218)
			(xy 30.758661 -385.237999) (xy 30.839693 -385.269391) (xy 30.917482 -385.308125) (xy 30.991366 -385.353872)
			(xy 31.060713 -385.406241) (xy 31.124933 -385.464785) (xy 31.183477 -385.529005) (xy 31.235846 -385.598352)
			(xy 31.281593 -385.672236) (xy 31.320327 -385.750025) (xy 31.351719 -385.831057) (xy 31.3755 -385.914639)
			(xy 31.391468 -386.000059) (xy 31.399486 -386.086588) (xy 31.399988 -386.130038) (xy 31.399486 -386.173488)
			(xy 34.599874 -386.173488) (xy 34.599874 -386.086588) (xy 34.607892 -386.000059) (xy 34.62386 -385.914639)
			(xy 34.647641 -385.831057) (xy 34.679033 -385.750025) (xy 34.717767 -385.672236) (xy 34.763514 -385.598352)
			(xy 34.815883 -385.529005) (xy 34.874427 -385.464785) (xy 34.938647 -385.406241) (xy 35.007994 -385.353872)
			(xy 35.081878 -385.308125) (xy 35.159667 -385.269391) (xy 35.240699 -385.237999) (xy 35.324281 -385.214218)
			(xy 35.409701 -385.19825) (xy 35.49623 -385.190232) (xy 35.58313 -385.190232) (xy 35.669659 -385.19825)
			(xy 35.755079 -385.214218) (xy 35.838661 -385.237999) (xy 35.919693 -385.269391) (xy 35.997482 -385.308125)
			(xy 36.071366 -385.353872) (xy 36.140713 -385.406241) (xy 36.204933 -385.464785) (xy 36.263477 -385.529005)
			(xy 36.315846 -385.598352) (xy 36.361593 -385.672236) (xy 36.400327 -385.750025) (xy 36.431719 -385.831057)
			(xy 36.4555 -385.914639) (xy 36.471468 -386.000059) (xy 36.479486 -386.086588) (xy 36.479988 -386.130038)
			(xy 36.479486 -386.173488) (xy 36.475937 -386.211784) (xy 38.761813 -386.211784) (xy 38.765702 -386.157435)
			(xy 38.777287 -386.104191) (xy 38.796332 -386.053139) (xy 38.822448 -386.005317) (xy 38.855105 -385.961698)
			(xy 38.893637 -385.923171) (xy 38.93726 -385.890521) (xy 38.985086 -385.864411) (xy 39.036141 -385.845373)
			(xy 39.089385 -385.833795) (xy 39.143736 -385.829913) (xy 39.198085 -385.833805) (xy 39.251328 -385.845393)
			(xy 39.302379 -385.86444) (xy 39.3502 -385.890559) (xy 39.372286 -385.906518) (xy 39.391298 -385.920114)
			(xy 39.433181 -385.940846) (xy 39.478149 -385.953572) (xy 39.524686 -385.957862) (xy 39.571223 -385.953572)
			(xy 39.616191 -385.940846) (xy 39.658074 -385.920114) (xy 39.677086 -385.906518) (xy 39.69915 -385.890522)
			(xy 39.746978 -385.864395) (xy 39.798038 -385.845342) (xy 39.851289 -385.83375) (xy 39.905648 -385.829854)
			(xy 39.960009 -385.833735) (xy 40.013263 -385.845313) (xy 40.064328 -385.864353) (xy 40.112163 -385.890466)
			(xy 40.155795 -385.923122) (xy 40.194334 -385.961655) (xy 40.226998 -386.00528) (xy 40.253119 -386.053111)
			(xy 40.272168 -386.104172) (xy 40.283755 -386.157425) (xy 40.287646 -386.211784) (xy 40.648505 -386.211784)
			(xy 40.652395 -386.157433) (xy 40.663981 -386.104188) (xy 40.683026 -386.053134) (xy 40.709144 -386.005311)
			(xy 40.741802 -385.961691) (xy 40.780335 -385.923164) (xy 40.82396 -385.890512) (xy 40.871787 -385.864402)
			(xy 40.922844 -385.845364) (xy 40.97609 -385.833787) (xy 41.030443 -385.829905) (xy 41.084794 -385.833799)
			(xy 41.138038 -385.845388) (xy 41.18909 -385.864437) (xy 41.236912 -385.890558) (xy 41.258998 -385.906518)
			(xy 41.27801 -385.920114) (xy 41.319893 -385.940846) (xy 41.364861 -385.953572) (xy 41.411398 -385.957862)
			(xy 41.457935 -385.953572) (xy 41.502903 -385.940846) (xy 41.544786 -385.920114) (xy 41.563798 -385.906518)
			(xy 41.585862 -385.890523) (xy 41.633689 -385.864398) (xy 41.684747 -385.845347) (xy 41.737998 -385.833756)
			(xy 41.792355 -385.829861) (xy 41.846714 -385.833743) (xy 41.899967 -385.845322) (xy 41.951029 -385.864361)
			(xy 41.998863 -385.890474) (xy 42.042493 -385.923129) (xy 42.081031 -385.961662) (xy 42.113693 -386.005286)
			(xy 42.139814 -386.053116) (xy 42.158861 -386.104175) (xy 42.170448 -386.157426) (xy 42.174339 -386.211784)
			(xy 42.88948 -386.211784) (xy 42.893371 -386.157427) (xy 42.904958 -386.104177) (xy 42.924006 -386.053118)
			(xy 42.950127 -386.00529) (xy 42.98279 -385.961667) (xy 43.021329 -385.923136) (xy 43.064959 -385.890483)
			(xy 43.112793 -385.864372) (xy 43.163856 -385.845335) (xy 43.217108 -385.833759) (xy 43.271466 -385.82988)
			(xy 43.325823 -385.833778) (xy 43.379072 -385.845372) (xy 43.430128 -385.864427) (xy 43.477953 -385.890555)
			(xy 43.50004 -385.906518) (xy 43.519052 -385.920114) (xy 43.560935 -385.940846) (xy 43.605903 -385.953572)
			(xy 43.65244 -385.957862) (xy 43.698977 -385.953572) (xy 43.743945 -385.940846) (xy 43.785828 -385.920114)
			(xy 43.80484 -385.906518) (xy 43.826903 -385.890526) (xy 43.874727 -385.864409) (xy 43.925782 -385.845363)
			(xy 43.979027 -385.833777) (xy 44.033379 -385.829887) (xy 44.087732 -385.833771) (xy 44.140978 -385.845351)
			(xy 44.192035 -385.864391) (xy 44.239862 -385.890504) (xy 44.283486 -385.923157) (xy 44.322019 -385.961686)
			(xy 44.354676 -386.005307) (xy 44.380794 -386.053132) (xy 44.399839 -386.104187) (xy 44.411424 -386.157432)
			(xy 44.415313 -386.211784) (xy 44.79349 -386.211784) (xy 44.79738 -386.157429) (xy 44.808966 -386.104181)
			(xy 44.828014 -386.053124) (xy 44.854133 -386.005298) (xy 44.886794 -385.961676) (xy 44.925331 -385.923146)
			(xy 44.968959 -385.890494) (xy 45.016791 -385.864383) (xy 45.067851 -385.845346) (xy 45.121101 -385.83377)
			(xy 45.175457 -385.82989) (xy 45.229812 -385.833786) (xy 45.283059 -385.845378) (xy 45.334114 -385.864431)
			(xy 45.381937 -385.890556) (xy 45.404024 -385.906518) (xy 45.423036 -385.920114) (xy 45.464919 -385.940846)
			(xy 45.509887 -385.953572) (xy 45.556424 -385.957862) (xy 45.602961 -385.953572) (xy 45.647929 -385.940846)
			(xy 45.689812 -385.920114) (xy 45.708824 -385.906518) (xy 45.730887 -385.890525) (xy 45.778713 -385.864405)
			(xy 45.829769 -385.845357) (xy 45.883016 -385.833769) (xy 45.93737 -385.829877) (xy 45.991725 -385.83376)
			(xy 46.044974 -385.84534) (xy 46.096033 -385.86438) (xy 46.143862 -385.890493) (xy 46.187489 -385.923147)
			(xy 46.226024 -385.961677) (xy 46.258683 -386.005299) (xy 46.284801 -386.053126) (xy 46.303847 -386.104182)
			(xy 46.315433 -386.15743) (xy 46.319323 -386.211784) (xy 46.315438 -386.266139) (xy 46.303856 -386.319388)
			(xy 46.284814 -386.370446) (xy 46.2587 -386.418274) (xy 46.226044 -386.461899) (xy 46.187512 -386.500433)
			(xy 46.143889 -386.533091) (xy 46.096061 -386.559207) (xy 46.045004 -386.578251) (xy 45.991756 -386.589835)
			(xy 45.937401 -386.593723) (xy 45.883047 -386.589836) (xy 45.829799 -386.578252) (xy 45.778741 -386.559208)
			(xy 45.730913 -386.533092) (xy 45.708824 -386.517134) (xy 45.689812 -386.503538) (xy 45.647929 -386.482806)
			(xy 45.602961 -386.47008) (xy 45.556424 -386.46579) (xy 45.509887 -386.47008) (xy 45.464919 -386.482806)
			(xy 45.423036 -386.503538) (xy 45.404024 -386.517134) (xy 45.381911 -386.533061) (xy 45.334085 -386.559182)
			(xy 45.283029 -386.578231) (xy 45.229781 -386.589819) (xy 45.175426 -386.59371) (xy 45.121071 -386.589826)
			(xy 45.067821 -386.578245) (xy 45.016762 -386.559204) (xy 44.968933 -386.533089) (xy 44.925307 -386.500433)
			(xy 44.886774 -386.4619) (xy 44.854117 -386.418276) (xy 44.828001 -386.370447) (xy 44.808958 -386.319389)
			(xy 44.797376 -386.26614) (xy 44.79349 -386.211784) (xy 44.415313 -386.211784) (xy 44.411428 -386.266137)
			(xy 44.399847 -386.319383) (xy 44.380806 -386.37044) (xy 44.354693 -386.418266) (xy 44.32204 -386.46189)
			(xy 44.28351 -386.500423) (xy 44.239888 -386.533079) (xy 44.192063 -386.559196) (xy 44.141008 -386.57824)
			(xy 44.087763 -386.589824) (xy 44.03341 -386.593713) (xy 43.979058 -386.589827) (xy 43.925812 -386.578246)
			(xy 43.874756 -386.559204) (xy 43.826929 -386.533091) (xy 43.80484 -386.517134) (xy 43.785828 -386.503538)
			(xy 43.743945 -386.482806) (xy 43.698977 -386.47008) (xy 43.65244 -386.46579) (xy 43.605903 -386.47008)
			(xy 43.560935 -386.482806) (xy 43.519052 -386.503538) (xy 43.50004 -386.517134) (xy 43.477927 -386.533062)
			(xy 43.4301 -386.559186) (xy 43.379042 -386.578237) (xy 43.325792 -386.589827) (xy 43.271435 -386.59372)
			(xy 43.217077 -386.589837) (xy 43.163826 -386.578257) (xy 43.112764 -386.559215) (xy 43.064933 -386.5331)
			(xy 43.021305 -386.500444) (xy 42.982769 -386.46191) (xy 42.95011 -386.418284) (xy 42.923993 -386.370454)
			(xy 42.904949 -386.319393) (xy 42.893366 -386.266142) (xy 42.88948 -386.211784) (xy 42.174339 -386.211784)
			(xy 42.170453 -386.266143) (xy 42.15887 -386.319395) (xy 42.139827 -386.370456) (xy 42.11371 -386.418287)
			(xy 42.081051 -386.461915) (xy 42.042516 -386.50045) (xy 41.998889 -386.533109) (xy 41.951058 -386.559226)
			(xy 41.899997 -386.57827) (xy 41.846745 -386.589853) (xy 41.792386 -386.593739) (xy 41.738028 -386.589849)
			(xy 41.684777 -386.578262) (xy 41.633717 -386.559215) (xy 41.585888 -386.533094) (xy 41.563798 -386.517134)
			(xy 41.544786 -386.503538) (xy 41.502903 -386.482806) (xy 41.457935 -386.47008) (xy 41.411398 -386.46579)
			(xy 41.364861 -386.47008) (xy 41.319893 -386.482806) (xy 41.27801 -386.503538) (xy 41.258998 -386.517134)
			(xy 41.236885 -386.533059) (xy 41.189062 -386.559176) (xy 41.138008 -386.578221) (xy 41.084763 -386.589805)
			(xy 41.030411 -386.593695) (xy 40.97606 -386.589809) (xy 40.922814 -386.578227) (xy 40.871759 -386.559185)
			(xy 40.823934 -386.533071) (xy 40.780312 -386.500416) (xy 40.741781 -386.461885) (xy 40.709127 -386.418263)
			(xy 40.683013 -386.370437) (xy 40.663972 -386.319382) (xy 40.652391 -386.266136) (xy 40.648505 -386.211784)
			(xy 40.287646 -386.211784) (xy 40.28376 -386.266144) (xy 40.272177 -386.319398) (xy 40.253132 -386.370461)
			(xy 40.227015 -386.418293) (xy 40.194355 -386.461922) (xy 40.155818 -386.500458) (xy 40.112189 -386.533117)
			(xy 40.064356 -386.559234) (xy 40.013293 -386.578278) (xy 39.96004 -386.589861) (xy 39.90568 -386.593746)
			(xy 39.85132 -386.589855) (xy 39.798068 -386.578267) (xy 39.747007 -386.559217) (xy 39.699176 -386.533095)
			(xy 39.677086 -386.517134) (xy 39.658074 -386.503538) (xy 39.616191 -386.482806) (xy 39.571223 -386.47008)
			(xy 39.524686 -386.46579) (xy 39.478149 -386.47008) (xy 39.433181 -386.482806) (xy 39.391298 -386.503538)
			(xy 39.372286 -386.517134) (xy 39.350174 -386.533058) (xy 39.302351 -386.559173) (xy 39.251298 -386.578216)
			(xy 39.198054 -386.589799) (xy 39.143704 -386.593687) (xy 39.089354 -386.589801) (xy 39.036111 -386.578218)
			(xy 38.985057 -386.559177) (xy 38.937234 -386.533063) (xy 38.893613 -386.500408) (xy 38.855085 -386.461878)
			(xy 38.822431 -386.418257) (xy 38.796319 -386.370433) (xy 38.777278 -386.319379) (xy 38.765698 -386.266135)
			(xy 38.761813 -386.211784) (xy 36.475937 -386.211784) (xy 36.471468 -386.260017) (xy 36.4555 -386.345437)
			(xy 36.431719 -386.429019) (xy 36.400327 -386.510051) (xy 36.361593 -386.58784) (xy 36.315846 -386.661724)
			(xy 36.263477 -386.731071) (xy 36.204933 -386.795291) (xy 36.140713 -386.853835) (xy 36.071366 -386.906204)
			(xy 35.997482 -386.951951) (xy 35.919693 -386.990685) (xy 35.838661 -387.022077) (xy 35.755079 -387.045858)
			(xy 35.669659 -387.061826) (xy 35.58313 -387.069844) (xy 35.49623 -387.069844) (xy 35.409701 -387.061826)
			(xy 35.324281 -387.045858) (xy 35.240699 -387.022077) (xy 35.159667 -386.990685) (xy 35.081878 -386.951951)
			(xy 35.007994 -386.906204) (xy 34.938647 -386.853835) (xy 34.874427 -386.795291) (xy 34.815883 -386.731071)
			(xy 34.763514 -386.661724) (xy 34.717767 -386.58784) (xy 34.679033 -386.510051) (xy 34.647641 -386.429019)
			(xy 34.62386 -386.345437) (xy 34.607892 -386.260017) (xy 34.599874 -386.173488) (xy 31.399486 -386.173488)
			(xy 31.391468 -386.260017) (xy 31.3755 -386.345437) (xy 31.351719 -386.429019) (xy 31.320327 -386.510051)
			(xy 31.281593 -386.58784) (xy 31.235846 -386.661724) (xy 31.183477 -386.731071) (xy 31.124933 -386.795291)
			(xy 31.060713 -386.853835) (xy 30.991366 -386.906204) (xy 30.917482 -386.951951) (xy 30.839693 -386.990685)
			(xy 30.758661 -387.022077) (xy 30.675079 -387.045858) (xy 30.589659 -387.061826) (xy 30.50313 -387.069844)
			(xy 30.41623 -387.069844) (xy 30.329701 -387.061826) (xy 30.244281 -387.045858) (xy 30.160699 -387.022077)
			(xy 30.079667 -386.990685) (xy 30.001878 -386.951951) (xy 29.927994 -386.906204) (xy 29.858647 -386.853835)
			(xy 29.794427 -386.795291) (xy 29.735883 -386.731071) (xy 29.683514 -386.661724) (xy 29.637767 -386.58784)
			(xy 29.599033 -386.510051) (xy 29.567641 -386.429019) (xy 29.54386 -386.345437) (xy 29.527892 -386.260017)
			(xy 29.519874 -386.173488) (xy 29.254196 -386.173488) (xy 29.254196 -387.197854) (xy 76.3938 -387.197854)
			(xy 76.397871 -387.142232) (xy 76.409997 -387.087795) (xy 76.42992 -387.035704) (xy 76.457216 -386.987069)
			(xy 76.491302 -386.942926) (xy 76.531451 -386.904217) (xy 76.576809 -386.871766) (xy 76.626409 -386.846265)
			(xy 76.679193 -386.828258) (xy 76.734036 -386.818128) (xy 76.78977 -386.816091) (xy 76.845207 -386.822191)
			(xy 76.899164 -386.836297) (xy 76.950493 -386.858109) (xy 76.998099 -386.887163) (xy 77.040967 -386.922838)
			(xy 77.078184 -386.964375) (xy 77.108957 -387.010888) (xy 77.132629 -387.061385) (xy 77.148697 -387.114792)
			(xy 77.156817 -387.169968) (xy 77.157326 -387.197854) (xy 77.156817 -387.22574) (xy 77.148697 -387.280916)
			(xy 77.132629 -387.334323) (xy 77.108957 -387.38482) (xy 77.078184 -387.431333) (xy 77.040967 -387.47287)
			(xy 76.998099 -387.508545) (xy 76.950493 -387.537599) (xy 76.899164 -387.559411) (xy 76.845207 -387.573517)
			(xy 76.78977 -387.579617) (xy 76.734036 -387.57758) (xy 76.679193 -387.56745) (xy 76.626409 -387.549443)
			(xy 76.576809 -387.523942) (xy 76.531451 -387.491491) (xy 76.491302 -387.452782) (xy 76.457216 -387.408639)
			(xy 76.42992 -387.360004) (xy 76.409997 -387.307913) (xy 76.397871 -387.253476) (xy 76.3938 -387.197854)
			(xy 29.254196 -387.197854) (xy 29.254196 -388.713488) (xy 29.519874 -388.713488) (xy 29.519874 -388.626588)
			(xy 29.527892 -388.540059) (xy 29.54386 -388.454639) (xy 29.567641 -388.371057) (xy 29.599033 -388.290025)
			(xy 29.637767 -388.212236) (xy 29.683514 -388.138352) (xy 29.735883 -388.069005) (xy 29.794427 -388.004785)
			(xy 29.858647 -387.946241) (xy 29.927994 -387.893872) (xy 30.001878 -387.848125) (xy 30.079667 -387.809391)
			(xy 30.160699 -387.777999) (xy 30.244281 -387.754218) (xy 30.329701 -387.73825) (xy 30.41623 -387.730232)
			(xy 30.50313 -387.730232) (xy 30.589659 -387.73825) (xy 30.675079 -387.754218) (xy 30.758661 -387.777999)
			(xy 30.839693 -387.809391) (xy 30.917482 -387.848125) (xy 30.991366 -387.893872) (xy 31.060713 -387.946241)
			(xy 31.124933 -388.004785) (xy 31.183477 -388.069005) (xy 31.235846 -388.138352) (xy 31.281593 -388.212236)
			(xy 31.320327 -388.290025) (xy 31.351719 -388.371057) (xy 31.3755 -388.454639) (xy 31.391468 -388.540059)
			(xy 31.399486 -388.626588) (xy 31.399988 -388.670038) (xy 31.399486 -388.713488) (xy 34.599874 -388.713488)
			(xy 34.599874 -388.626588) (xy 34.607892 -388.540059) (xy 34.62386 -388.454639) (xy 34.647641 -388.371057)
			(xy 34.679033 -388.290025) (xy 34.717767 -388.212236) (xy 34.763514 -388.138352) (xy 34.815883 -388.069005)
			(xy 34.874427 -388.004785) (xy 34.938647 -387.946241) (xy 35.007994 -387.893872) (xy 35.081878 -387.848125)
			(xy 35.159667 -387.809391) (xy 35.240699 -387.777999) (xy 35.324281 -387.754218) (xy 35.409701 -387.73825)
			(xy 35.49623 -387.730232) (xy 35.58313 -387.730232) (xy 35.669659 -387.73825) (xy 35.755079 -387.754218)
			(xy 35.838661 -387.777999) (xy 35.919693 -387.809391) (xy 35.997482 -387.848125) (xy 36.071366 -387.893872)
			(xy 36.140713 -387.946241) (xy 36.204933 -388.004785) (xy 36.263477 -388.069005) (xy 36.315846 -388.138352)
			(xy 36.361593 -388.212236) (xy 36.366953 -388.223001) (xy 38.718411 -388.223001) (xy 38.722298 -388.168653)
			(xy 38.73388 -388.11541) (xy 38.752921 -388.064358) (xy 38.779034 -388.016536) (xy 38.811687 -387.972916)
			(xy 38.850215 -387.934388) (xy 38.893834 -387.901735) (xy 38.941657 -387.875621) (xy 38.992709 -387.85658)
			(xy 39.045951 -387.844998) (xy 39.1003 -387.841111) (xy 39.154648 -387.844998) (xy 39.20789 -387.85658)
			(xy 39.258942 -387.875621) (xy 39.306765 -387.901734) (xy 39.328852 -387.91769) (xy 39.347864 -387.931286)
			(xy 39.389747 -387.952018) (xy 39.434715 -387.964744) (xy 39.481252 -387.969034) (xy 39.527789 -387.964744)
			(xy 39.572757 -387.952018) (xy 39.61464 -387.931286) (xy 39.633652 -387.91769) (xy 39.655743 -387.901729)
			(xy 39.703572 -387.875601) (xy 39.754632 -387.856546) (xy 39.807885 -387.844952) (xy 39.862246 -387.841056)
			(xy 39.916608 -387.844937) (xy 39.969864 -387.856515) (xy 40.02093 -387.875556) (xy 40.068766 -387.90167)
			(xy 40.112398 -387.934327) (xy 40.150938 -387.972862) (xy 40.183601 -388.01649) (xy 40.209722 -388.064322)
			(xy 40.22877 -388.115386) (xy 40.240356 -388.16864) (xy 40.244244 -388.223001) (xy 40.605103 -388.223001)
			(xy 40.608991 -388.168651) (xy 40.620573 -388.115407) (xy 40.639615 -388.064354) (xy 40.665729 -388.01653)
			(xy 40.698383 -387.972909) (xy 40.736913 -387.93438) (xy 40.780534 -387.901726) (xy 40.828358 -387.875613)
			(xy 40.879412 -387.856572) (xy 40.932656 -387.84499) (xy 40.987006 -387.841103) (xy 41.041357 -387.844992)
			(xy 41.0946 -387.856575) (xy 41.145653 -387.875618) (xy 41.193477 -387.901733) (xy 41.215564 -387.91769)
			(xy 41.234576 -387.931286) (xy 41.276459 -387.952018) (xy 41.321427 -387.964744) (xy 41.367964 -387.969034)
			(xy 41.414501 -387.964744) (xy 41.459469 -387.952018) (xy 41.501352 -387.931286) (xy 41.520364 -387.91769)
			(xy 41.542455 -387.90173) (xy 41.590283 -387.875604) (xy 41.641342 -387.85655) (xy 41.694594 -387.844958)
			(xy 41.748953 -387.841064) (xy 41.803313 -387.844945) (xy 41.856567 -387.856524) (xy 41.907631 -387.875564)
			(xy 41.955465 -387.901679) (xy 41.999096 -387.934335) (xy 42.037635 -387.972869) (xy 42.070297 -388.016496)
			(xy 42.096417 -388.064327) (xy 42.115463 -388.115389) (xy 42.127048 -388.168642) (xy 42.130936 -388.223001)
			(xy 42.846078 -388.223001) (xy 42.849966 -388.168645) (xy 42.86155 -388.115396) (xy 42.880595 -388.064337)
			(xy 42.906713 -388.016509) (xy 42.939371 -387.972885) (xy 42.977907 -387.934352) (xy 43.021533 -387.901697)
			(xy 43.069364 -387.875583) (xy 43.120424 -387.856542) (xy 43.173674 -387.844962) (xy 43.22803 -387.841078)
			(xy 43.282386 -387.84497) (xy 43.335634 -387.856559) (xy 43.386691 -387.875608) (xy 43.434518 -387.90173)
			(xy 43.456606 -387.91769) (xy 43.475618 -387.931286) (xy 43.517501 -387.952018) (xy 43.562469 -387.964744)
			(xy 43.609006 -387.969034) (xy 43.655543 -387.964744) (xy 43.700511 -387.952018) (xy 43.742394 -387.931286)
			(xy 43.761406 -387.91769) (xy 43.783496 -387.901733) (xy 43.831321 -387.875614) (xy 43.882376 -387.856567)
			(xy 43.935623 -387.84498) (xy 43.989977 -387.841089) (xy 44.044331 -387.844973) (xy 44.097579 -387.856553)
			(xy 44.148636 -387.875594) (xy 44.196465 -387.901708) (xy 44.240089 -387.934363) (xy 44.278623 -387.972894)
			(xy 44.31128 -388.016517) (xy 44.337396 -388.064343) (xy 44.35644 -388.1154) (xy 44.368024 -388.168647)
			(xy 44.371911 -388.223001) (xy 44.750088 -388.223001) (xy 44.753975 -388.168647) (xy 44.765559 -388.1154)
			(xy 44.784603 -388.064344) (xy 44.810719 -388.016517) (xy 44.843376 -387.972894) (xy 44.881909 -387.934363)
			(xy 44.925534 -387.901708) (xy 44.973362 -387.875594) (xy 45.024419 -387.856553) (xy 45.077667 -387.844972)
			(xy 45.132021 -387.841088) (xy 45.186375 -387.844978) (xy 45.239621 -387.856565) (xy 45.290677 -387.875612)
			(xy 45.338502 -387.901731) (xy 45.36059 -387.91769) (xy 45.379602 -387.931286) (xy 45.421485 -387.952018)
			(xy 45.466453 -387.964744) (xy 45.51299 -387.969034) (xy 45.559527 -387.964744) (xy 45.604495 -387.952018)
			(xy 45.646378 -387.931286) (xy 45.66539 -387.91769) (xy 45.68748 -387.901732) (xy 45.735306 -387.87561)
			(xy 45.786363 -387.85656) (xy 45.839612 -387.844972) (xy 45.893967 -387.841079) (xy 45.948324 -387.844962)
			(xy 46.001574 -387.856542) (xy 46.052634 -387.875583) (xy 46.100465 -387.901697) (xy 46.144092 -387.934352)
			(xy 46.182627 -387.972884) (xy 46.215286 -388.016509) (xy 46.241404 -388.064337) (xy 46.260449 -388.115396)
			(xy 46.272033 -388.168645) (xy 46.275921 -388.223001) (xy 46.272033 -388.277357) (xy 46.260448 -388.330607)
			(xy 46.241403 -388.381665) (xy 46.215285 -388.429493) (xy 46.182626 -388.473118) (xy 46.14409 -388.511649)
			(xy 46.100463 -388.544305) (xy 46.052632 -388.570418) (xy 46.001572 -388.589459) (xy 45.948321 -388.601038)
			(xy 45.893965 -388.604921) (xy 45.839609 -388.601028) (xy 45.786361 -388.589439) (xy 45.735304 -388.570389)
			(xy 45.687478 -388.544267) (xy 45.66539 -388.528306) (xy 45.646378 -388.51471) (xy 45.604495 -388.493978)
			(xy 45.559527 -388.481252) (xy 45.51299 -388.476962) (xy 45.466453 -388.481252) (xy 45.421485 -388.493978)
			(xy 45.379602 -388.51471) (xy 45.36059 -388.528306) (xy 45.338504 -388.544268) (xy 45.290679 -388.570387)
			(xy 45.239624 -388.589434) (xy 45.186377 -388.601021) (xy 45.132024 -388.604912) (xy 45.07767 -388.601028)
			(xy 45.024422 -388.589447) (xy 44.973364 -388.570407) (xy 44.925536 -388.544293) (xy 44.881911 -388.511639)
			(xy 44.843378 -388.473108) (xy 44.81072 -388.429485) (xy 44.784604 -388.381659) (xy 44.765559 -388.330602)
			(xy 44.753976 -388.277355) (xy 44.750088 -388.223001) (xy 44.371911 -388.223001) (xy 44.368024 -388.277355)
			(xy 44.35644 -388.330602) (xy 44.337395 -388.381659) (xy 44.311279 -388.429485) (xy 44.278621 -388.473108)
			(xy 44.240088 -388.511639) (xy 44.196463 -388.544293) (xy 44.148634 -388.570407) (xy 44.097576 -388.589447)
			(xy 44.044328 -388.601027) (xy 43.989974 -388.604911) (xy 43.935621 -388.60102) (xy 43.882374 -388.589433)
			(xy 43.831319 -388.570385) (xy 43.783494 -388.544265) (xy 43.761406 -388.528306) (xy 43.742394 -388.51471)
			(xy 43.700511 -388.493978) (xy 43.655543 -388.481252) (xy 43.609006 -388.476962) (xy 43.562469 -388.481252)
			(xy 43.517501 -388.493978) (xy 43.475618 -388.51471) (xy 43.456606 -388.528306) (xy 43.43452 -388.544269)
			(xy 43.386694 -388.570391) (xy 43.335637 -388.58944) (xy 43.282388 -388.601029) (xy 43.228033 -388.604922)
			(xy 43.173676 -388.601039) (xy 43.120426 -388.589459) (xy 43.069366 -388.570418) (xy 43.021535 -388.544304)
			(xy 42.977908 -388.511649) (xy 42.939373 -388.473117) (xy 42.906714 -388.429493) (xy 42.880596 -388.381665)
			(xy 42.861551 -388.330606) (xy 42.849966 -388.277357) (xy 42.846078 -388.223001) (xy 42.130936 -388.223001)
			(xy 42.127048 -388.277361) (xy 42.115463 -388.330614) (xy 42.096416 -388.381675) (xy 42.070295 -388.429506)
			(xy 42.037633 -388.473133) (xy 41.999094 -388.511666) (xy 41.955463 -388.544323) (xy 41.907629 -388.570437)
			(xy 41.856565 -388.589477) (xy 41.80331 -388.601055) (xy 41.74895 -388.604936) (xy 41.694591 -388.601041)
			(xy 41.64134 -388.589449) (xy 41.590281 -388.570396) (xy 41.542453 -388.544269) (xy 41.520364 -388.528306)
			(xy 41.501352 -388.51471) (xy 41.459469 -388.493978) (xy 41.414501 -388.481252) (xy 41.367964 -388.476962)
			(xy 41.321427 -388.481252) (xy 41.276459 -388.493978) (xy 41.234576 -388.51471) (xy 41.215564 -388.528306)
			(xy 41.193479 -388.544266) (xy 41.145655 -388.570381) (xy 41.094602 -388.589424) (xy 41.041359 -388.601008)
			(xy 40.987009 -388.604897) (xy 40.932658 -388.601011) (xy 40.879414 -388.589429) (xy 40.828361 -388.570388)
			(xy 40.780536 -388.544275) (xy 40.736915 -388.511622) (xy 40.698385 -388.473093) (xy 40.66573 -388.429472)
			(xy 40.639616 -388.381649) (xy 40.620574 -388.330595) (xy 40.608991 -388.277351) (xy 40.605103 -388.223001)
			(xy 40.244244 -388.223001) (xy 40.240355 -388.277362) (xy 40.228769 -388.330617) (xy 40.209721 -388.38168)
			(xy 40.1836 -388.429512) (xy 40.150937 -388.47314) (xy 40.112396 -388.511674) (xy 40.068764 -388.544331)
			(xy 40.020927 -388.570445) (xy 39.969861 -388.589485) (xy 39.916605 -388.601063) (xy 39.862243 -388.604944)
			(xy 39.807883 -388.601047) (xy 39.75463 -388.589454) (xy 39.70357 -388.570398) (xy 39.655741 -388.54427)
			(xy 39.633652 -388.528306) (xy 39.61464 -388.51471) (xy 39.572757 -388.493978) (xy 39.527789 -388.481252)
			(xy 39.481252 -388.476962) (xy 39.434715 -388.481252) (xy 39.389747 -388.493978) (xy 39.347864 -388.51471)
			(xy 39.328852 -388.528306) (xy 39.306767 -388.544265) (xy 39.258945 -388.570378) (xy 39.207893 -388.58942)
			(xy 39.154651 -388.601002) (xy 39.100302 -388.604889) (xy 39.045953 -388.601003) (xy 38.992711 -388.589421)
			(xy 38.941659 -388.570379) (xy 38.893836 -388.544267) (xy 38.850217 -388.511614) (xy 38.811688 -388.473086)
			(xy 38.779035 -388.429466) (xy 38.752922 -388.381644) (xy 38.73388 -388.330592) (xy 38.722298 -388.27735)
			(xy 38.718411 -388.223001) (xy 36.366953 -388.223001) (xy 36.400327 -388.290025) (xy 36.431719 -388.371057)
			(xy 36.4555 -388.454639) (xy 36.471468 -388.540059) (xy 36.479486 -388.626588) (xy 36.479988 -388.670038)
			(xy 36.479486 -388.713488) (xy 36.471468 -388.800017) (xy 36.4555 -388.885437) (xy 36.431719 -388.969019)
			(xy 36.400327 -389.050051) (xy 36.361593 -389.12784) (xy 36.315846 -389.201724) (xy 36.263477 -389.271071)
			(xy 36.204933 -389.335291) (xy 36.140713 -389.393835) (xy 36.071366 -389.446204) (xy 35.997482 -389.491951)
			(xy 35.919693 -389.530685) (xy 35.838661 -389.562077) (xy 35.755079 -389.585858) (xy 35.669659 -389.601826)
			(xy 35.58313 -389.609844) (xy 35.49623 -389.609844) (xy 35.409701 -389.601826) (xy 35.324281 -389.585858)
			(xy 35.240699 -389.562077) (xy 35.159667 -389.530685) (xy 35.081878 -389.491951) (xy 35.007994 -389.446204)
			(xy 34.938647 -389.393835) (xy 34.874427 -389.335291) (xy 34.815883 -389.271071) (xy 34.763514 -389.201724)
			(xy 34.717767 -389.12784) (xy 34.679033 -389.050051) (xy 34.647641 -388.969019) (xy 34.62386 -388.885437)
			(xy 34.607892 -388.800017) (xy 34.599874 -388.713488) (xy 31.399486 -388.713488) (xy 31.391468 -388.800017)
			(xy 31.3755 -388.885437) (xy 31.351719 -388.969019) (xy 31.320327 -389.050051) (xy 31.281593 -389.12784)
			(xy 31.235846 -389.201724) (xy 31.183477 -389.271071) (xy 31.124933 -389.335291) (xy 31.060713 -389.393835)
			(xy 30.991366 -389.446204) (xy 30.917482 -389.491951) (xy 30.839693 -389.530685) (xy 30.758661 -389.562077)
			(xy 30.675079 -389.585858) (xy 30.589659 -389.601826) (xy 30.50313 -389.609844) (xy 30.41623 -389.609844)
			(xy 30.329701 -389.601826) (xy 30.244281 -389.585858) (xy 30.160699 -389.562077) (xy 30.079667 -389.530685)
			(xy 30.001878 -389.491951) (xy 29.927994 -389.446204) (xy 29.858647 -389.393835) (xy 29.794427 -389.335291)
			(xy 29.735883 -389.271071) (xy 29.683514 -389.201724) (xy 29.637767 -389.12784) (xy 29.599033 -389.050051)
			(xy 29.567641 -388.969019) (xy 29.54386 -388.885437) (xy 29.527892 -388.800017) (xy 29.519874 -388.713488)
			(xy 29.254196 -388.713488) (xy 29.254196 -390.113488) (xy 38.718428 -390.113488) (xy 38.722317 -390.059142)
			(xy 38.7339 -390.005903) (xy 38.752942 -389.954854) (xy 38.779056 -389.907034) (xy 38.811709 -389.863418)
			(xy 38.850237 -389.824892) (xy 38.893855 -389.792242) (xy 38.941676 -389.766132) (xy 38.992726 -389.747093)
			(xy 39.045967 -389.735513) (xy 39.100313 -389.731628) (xy 39.154659 -389.735517) (xy 39.207898 -389.7471)
			(xy 39.258947 -389.766143) (xy 39.306766 -389.792256) (xy 39.328852 -389.808212) (xy 39.347864 -389.821808)
			(xy 39.389747 -389.84254) (xy 39.434715 -389.855266) (xy 39.481252 -389.859556) (xy 39.527789 -389.855266)
			(xy 39.572757 -389.84254) (xy 39.61464 -389.821808) (xy 39.633652 -389.808212) (xy 39.655723 -389.792221)
			(xy 39.703553 -389.76609) (xy 39.754615 -389.747033) (xy 39.80787 -389.735437) (xy 39.862233 -389.731539)
			(xy 39.916597 -389.735418) (xy 39.969856 -389.746995) (xy 40.020925 -389.766034) (xy 40.068764 -389.792148)
			(xy 40.1124 -389.824805) (xy 40.150943 -389.86334) (xy 40.183609 -389.906969) (xy 40.209733 -389.954803)
			(xy 40.228783 -390.005868) (xy 40.240371 -390.059124) (xy 40.244261 -390.113488) (xy 40.605121 -390.113488)
			(xy 40.60901 -390.05914) (xy 40.620594 -390.005899) (xy 40.639637 -389.954849) (xy 40.665751 -389.907028)
			(xy 40.698405 -389.863411) (xy 40.736935 -389.824885) (xy 40.780555 -389.792234) (xy 40.828378 -389.766123)
			(xy 40.87943 -389.747085) (xy 40.932672 -389.735505) (xy 40.98702 -389.731621) (xy 41.041367 -389.735511)
			(xy 41.094608 -389.747096) (xy 41.145658 -389.76614) (xy 41.193478 -389.792255) (xy 41.215564 -389.808212)
			(xy 41.234576 -389.821808) (xy 41.276459 -389.84254) (xy 41.321427 -389.855266) (xy 41.367964 -389.859556)
			(xy 41.414501 -389.855266) (xy 41.459469 -389.84254) (xy 41.501352 -389.821808) (xy 41.520364 -389.808212)
			(xy 41.542434 -389.792222) (xy 41.590263 -389.766093) (xy 41.641325 -389.747037) (xy 41.694578 -389.735443)
			(xy 41.748939 -389.731546) (xy 41.803302 -389.735426) (xy 41.856559 -389.747003) (xy 41.907626 -389.766043)
			(xy 41.955464 -389.792157) (xy 41.999098 -389.824813) (xy 42.037639 -389.863348) (xy 42.070304 -389.906975)
			(xy 42.096427 -389.954808) (xy 42.115476 -390.005871) (xy 42.127064 -390.059126) (xy 42.130954 -390.113488)
			(xy 42.846096 -390.113488) (xy 42.849985 -390.059135) (xy 42.861571 -390.005888) (xy 42.880616 -389.954833)
			(xy 42.906734 -389.907007) (xy 42.939393 -389.863386) (xy 42.977928 -389.824857) (xy 43.021554 -389.792205)
			(xy 43.069383 -389.766093) (xy 43.120441 -389.747055) (xy 43.17369 -389.735477) (xy 43.228043 -389.731596)
			(xy 43.282396 -389.73549) (xy 43.335642 -389.74708) (xy 43.386696 -389.766129) (xy 43.434519 -389.792252)
			(xy 43.456606 -389.808212) (xy 43.475618 -389.821808) (xy 43.517501 -389.84254) (xy 43.562469 -389.855266)
			(xy 43.609006 -389.859556) (xy 43.655543 -389.855266) (xy 43.700511 -389.84254) (xy 43.742394 -389.821808)
			(xy 43.761406 -389.808212) (xy 43.783475 -389.792226) (xy 43.831302 -389.766103) (xy 43.882359 -389.747053)
			(xy 43.935607 -389.735464) (xy 43.989963 -389.731571) (xy 44.04432 -389.735454) (xy 44.097571 -389.747033)
			(xy 44.148632 -389.766073) (xy 44.196463 -389.792186) (xy 44.240091 -389.824841) (xy 44.278627 -389.863372)
			(xy 44.311288 -389.906996) (xy 44.337407 -389.954824) (xy 44.356453 -390.005882) (xy 44.368039 -390.059132)
			(xy 44.371929 -390.113488) (xy 44.750105 -390.113488) (xy 44.753995 -390.059137) (xy 44.765579 -390.005892)
			(xy 44.784624 -389.954839) (xy 44.810741 -389.907015) (xy 44.843398 -389.863396) (xy 44.881931 -389.824868)
			(xy 44.925554 -389.792216) (xy 44.973381 -389.766105) (xy 45.024437 -389.747066) (xy 45.077683 -389.735488)
			(xy 45.132034 -389.731605) (xy 45.186385 -389.735498) (xy 45.239629 -389.747086) (xy 45.290682 -389.766133)
			(xy 45.338504 -389.792253) (xy 45.36059 -389.808212) (xy 45.379602 -389.821808) (xy 45.421485 -389.84254)
			(xy 45.466453 -389.855266) (xy 45.51299 -389.859556) (xy 45.559527 -389.855266) (xy 45.604495 -389.84254)
			(xy 45.646378 -389.821808) (xy 45.66539 -389.808212) (xy 45.68746 -389.792224) (xy 45.735287 -389.766099)
			(xy 45.786346 -389.747047) (xy 45.839596 -389.735456) (xy 45.893954 -389.731561) (xy 45.948313 -389.735443)
			(xy 46.001567 -389.747022) (xy 46.05263 -389.766061) (xy 46.100463 -389.792175) (xy 46.144094 -389.82483)
			(xy 46.182632 -389.863363) (xy 46.215294 -389.906988) (xy 46.241415 -389.954818) (xy 46.260462 -390.005878)
			(xy 46.272049 -390.05913) (xy 46.275939 -390.113488) (xy 46.272052 -390.167847) (xy 46.260469 -390.221099)
			(xy 46.241425 -390.27216) (xy 46.215307 -390.319992) (xy 46.182648 -390.363619) (xy 46.144112 -390.402154)
			(xy 46.100484 -390.434812) (xy 46.052652 -390.460929) (xy 46.00159 -390.479972) (xy 45.948337 -390.491554)
			(xy 45.893978 -390.495439) (xy 45.83962 -390.491547) (xy 45.786369 -390.479959) (xy 45.735309 -390.460911)
			(xy 45.68748 -390.434789) (xy 45.66539 -390.418828) (xy 45.646378 -390.405232) (xy 45.604495 -390.3845)
			(xy 45.559527 -390.371774) (xy 45.51299 -390.367484) (xy 45.466453 -390.371774) (xy 45.421485 -390.3845)
			(xy 45.379602 -390.405232) (xy 45.36059 -390.418828) (xy 45.338483 -390.43476) (xy 45.29066 -390.460877)
			(xy 45.239606 -390.479921) (xy 45.186362 -390.491506) (xy 45.13201 -390.495395) (xy 45.077659 -390.491509)
			(xy 45.024414 -390.479927) (xy 44.973359 -390.460885) (xy 44.925534 -390.434771) (xy 44.881912 -390.402117)
			(xy 44.843382 -390.363586) (xy 44.810728 -390.319965) (xy 44.784614 -390.272139) (xy 44.765573 -390.221085)
			(xy 44.753991 -390.167839) (xy 44.750105 -390.113488) (xy 44.371929 -390.113488) (xy 44.368043 -390.167844)
			(xy 44.35646 -390.221095) (xy 44.337417 -390.272154) (xy 44.311301 -390.319984) (xy 44.278643 -390.36361)
			(xy 44.240109 -390.402144) (xy 44.196483 -390.434801) (xy 44.148654 -390.460917) (xy 44.097594 -390.47996)
			(xy 44.044344 -390.491543) (xy 43.989987 -390.495429) (xy 43.935631 -390.491539) (xy 43.882382 -390.479953)
			(xy 43.831323 -390.460907) (xy 43.783495 -390.434787) (xy 43.761406 -390.418828) (xy 43.742394 -390.405232)
			(xy 43.700511 -390.3845) (xy 43.655543 -390.371774) (xy 43.609006 -390.367484) (xy 43.562469 -390.371774)
			(xy 43.517501 -390.3845) (xy 43.475618 -390.405232) (xy 43.456606 -390.418828) (xy 43.434499 -390.434761)
			(xy 43.386674 -390.460881) (xy 43.335619 -390.479927) (xy 43.282373 -390.491514) (xy 43.228019 -390.495404)
			(xy 43.173666 -390.491519) (xy 43.120418 -390.479938) (xy 43.069361 -390.460897) (xy 43.021534 -390.434783)
			(xy 42.97791 -390.402127) (xy 42.939378 -390.363596) (xy 42.906722 -390.319972) (xy 42.880606 -390.272146)
			(xy 42.861564 -390.221089) (xy 42.849982 -390.167842) (xy 42.846096 -390.113488) (xy 42.130954 -390.113488)
			(xy 42.127067 -390.16785) (xy 42.115483 -390.221106) (xy 42.096437 -390.272171) (xy 42.070317 -390.320005)
			(xy 42.037655 -390.363634) (xy 41.999116 -390.402171) (xy 41.955484 -390.43483) (xy 41.907648 -390.460947)
			(xy 41.856582 -390.47999) (xy 41.803326 -390.491571) (xy 41.748963 -390.495454) (xy 41.694602 -390.491561)
			(xy 41.641348 -390.47997) (xy 41.590285 -390.460917) (xy 41.542454 -390.434791) (xy 41.520364 -390.418828)
			(xy 41.501352 -390.405232) (xy 41.459469 -390.3845) (xy 41.414501 -390.371774) (xy 41.367964 -390.367484)
			(xy 41.321427 -390.371774) (xy 41.276459 -390.3845) (xy 41.234576 -390.405232) (xy 41.215564 -390.418828)
			(xy 41.193458 -390.434758) (xy 41.145636 -390.46087) (xy 41.094585 -390.479911) (xy 41.041343 -390.491492)
			(xy 40.986996 -390.495379) (xy 40.932648 -390.491491) (xy 40.879407 -390.479909) (xy 40.828356 -390.460867)
			(xy 40.780535 -390.434753) (xy 40.736917 -390.4021) (xy 40.69839 -390.363571) (xy 40.665738 -390.319952)
			(xy 40.639627 -390.272129) (xy 40.620587 -390.221078) (xy 40.609006 -390.167836) (xy 40.605121 -390.113488)
			(xy 40.244261 -390.113488) (xy 40.240374 -390.167852) (xy 40.22879 -390.221109) (xy 40.209743 -390.272175)
			(xy 40.183622 -390.320011) (xy 40.150958 -390.363641) (xy 40.112418 -390.402179) (xy 40.068784 -390.434839)
			(xy 40.020947 -390.460956) (xy 39.969879 -390.479999) (xy 39.916621 -390.491579) (xy 39.862257 -390.495461)
			(xy 39.807893 -390.491567) (xy 39.754638 -390.479974) (xy 39.703574 -390.46092) (xy 39.655743 -390.434792)
			(xy 39.633652 -390.418828) (xy 39.61464 -390.405232) (xy 39.572757 -390.3845) (xy 39.527789 -390.371774)
			(xy 39.481252 -390.367484) (xy 39.434715 -390.371774) (xy 39.389747 -390.3845) (xy 39.347864 -390.405232)
			(xy 39.328852 -390.418828) (xy 39.306746 -390.434757) (xy 39.258925 -390.460867) (xy 39.207875 -390.479906)
			(xy 39.154635 -390.491486) (xy 39.100289 -390.495372) (xy 39.045943 -390.491483) (xy 38.992703 -390.4799)
			(xy 38.941654 -390.460858) (xy 38.893835 -390.434745) (xy 38.850218 -390.402092) (xy 38.811693 -390.363564)
			(xy 38.779043 -390.319946) (xy 38.752932 -390.272125) (xy 38.733893 -390.221074) (xy 38.722313 -390.167834)
			(xy 38.718428 -390.113488) (xy 29.254196 -390.113488) (xy 29.254196 -391.253488) (xy 29.519874 -391.253488)
			(xy 29.519874 -391.166588) (xy 29.527892 -391.080059) (xy 29.54386 -390.994639) (xy 29.567641 -390.911057)
			(xy 29.599033 -390.830025) (xy 29.637767 -390.752236) (xy 29.683514 -390.678352) (xy 29.735883 -390.609005)
			(xy 29.794427 -390.544785) (xy 29.858647 -390.486241) (xy 29.927994 -390.433872) (xy 30.001878 -390.388125)
			(xy 30.079667 -390.349391) (xy 30.160699 -390.317999) (xy 30.244281 -390.294218) (xy 30.329701 -390.27825)
			(xy 30.41623 -390.270232) (xy 30.50313 -390.270232) (xy 30.589659 -390.27825) (xy 30.675079 -390.294218)
			(xy 30.758661 -390.317999) (xy 30.839693 -390.349391) (xy 30.917482 -390.388125) (xy 30.991366 -390.433872)
			(xy 31.060713 -390.486241) (xy 31.124933 -390.544785) (xy 31.183477 -390.609005) (xy 31.235846 -390.678352)
			(xy 31.281593 -390.752236) (xy 31.320327 -390.830025) (xy 31.351719 -390.911057) (xy 31.3755 -390.994639)
			(xy 31.391468 -391.080059) (xy 31.399486 -391.166588) (xy 31.399988 -391.210038) (xy 31.399486 -391.253488)
			(xy 34.599874 -391.253488) (xy 34.599874 -391.166588) (xy 34.607892 -391.080059) (xy 34.62386 -390.994639)
			(xy 34.647641 -390.911057) (xy 34.679033 -390.830025) (xy 34.717767 -390.752236) (xy 34.763514 -390.678352)
			(xy 34.815883 -390.609005) (xy 34.874427 -390.544785) (xy 34.938647 -390.486241) (xy 35.007994 -390.433872)
			(xy 35.081878 -390.388125) (xy 35.159667 -390.349391) (xy 35.240699 -390.317999) (xy 35.324281 -390.294218)
			(xy 35.409701 -390.27825) (xy 35.49623 -390.270232) (xy 35.58313 -390.270232) (xy 35.669659 -390.27825)
			(xy 35.755079 -390.294218) (xy 35.838661 -390.317999) (xy 35.919693 -390.349391) (xy 35.997482 -390.388125)
			(xy 36.071366 -390.433872) (xy 36.140713 -390.486241) (xy 36.204933 -390.544785) (xy 36.263477 -390.609005)
			(xy 36.315846 -390.678352) (xy 36.361593 -390.752236) (xy 36.400327 -390.830025) (xy 36.431719 -390.911057)
			(xy 36.4555 -390.994639) (xy 36.471468 -391.080059) (xy 36.479486 -391.166588) (xy 36.479988 -391.210038)
			(xy 36.479486 -391.253488) (xy 36.471468 -391.340017) (xy 36.4555 -391.425437) (xy 36.431719 -391.509019)
			(xy 36.400327 -391.590051) (xy 36.361593 -391.66784) (xy 36.315846 -391.741724) (xy 36.263477 -391.811071)
			(xy 36.204933 -391.875291) (xy 36.140713 -391.933835) (xy 36.071366 -391.986204) (xy 35.997482 -392.031951)
			(xy 35.919693 -392.070685) (xy 35.838661 -392.102077) (xy 35.755079 -392.125858) (xy 35.669659 -392.141826)
			(xy 35.58313 -392.149844) (xy 35.49623 -392.149844) (xy 35.409701 -392.141826) (xy 35.324281 -392.125858)
			(xy 35.240699 -392.102077) (xy 35.159667 -392.070685) (xy 35.081878 -392.031951) (xy 35.007994 -391.986204)
			(xy 34.938647 -391.933835) (xy 34.874427 -391.875291) (xy 34.815883 -391.811071) (xy 34.763514 -391.741724)
			(xy 34.717767 -391.66784) (xy 34.679033 -391.590051) (xy 34.647641 -391.509019) (xy 34.62386 -391.425437)
			(xy 34.607892 -391.340017) (xy 34.599874 -391.253488) (xy 31.399486 -391.253488) (xy 31.391468 -391.340017)
			(xy 31.3755 -391.425437) (xy 31.351719 -391.509019) (xy 31.320327 -391.590051) (xy 31.281593 -391.66784)
			(xy 31.235846 -391.741724) (xy 31.183477 -391.811071) (xy 31.124933 -391.875291) (xy 31.060713 -391.933835)
			(xy 30.991366 -391.986204) (xy 30.917482 -392.031951) (xy 30.839693 -392.070685) (xy 30.758661 -392.102077)
			(xy 30.675079 -392.125858) (xy 30.589659 -392.141826) (xy 30.50313 -392.149844) (xy 30.41623 -392.149844)
			(xy 30.329701 -392.141826) (xy 30.244281 -392.125858) (xy 30.160699 -392.102077) (xy 30.079667 -392.070685)
			(xy 30.001878 -392.031951) (xy 29.927994 -391.986204) (xy 29.858647 -391.933835) (xy 29.794427 -391.875291)
			(xy 29.735883 -391.811071) (xy 29.683514 -391.741724) (xy 29.637767 -391.66784) (xy 29.599033 -391.590051)
			(xy 29.567641 -391.509019) (xy 29.54386 -391.425437) (xy 29.527892 -391.340017) (xy 29.519874 -391.253488)
			(xy 29.254196 -391.253488) (xy 29.254196 -392.154722) (xy 38.718383 -392.154722) (xy 38.722268 -392.100369)
			(xy 38.733848 -392.047122) (xy 38.752888 -391.996066) (xy 38.779 -391.948238) (xy 38.811653 -391.904614)
			(xy 38.850182 -391.866081) (xy 38.893803 -391.833423) (xy 38.941627 -391.807305) (xy 38.992682 -391.78826)
			(xy 39.045927 -391.776674) (xy 39.100279 -391.772783) (xy 39.154632 -391.776668) (xy 39.207878 -391.788248)
			(xy 39.258935 -391.807288) (xy 39.306762 -391.8334) (xy 39.328852 -391.849356) (xy 39.347864 -391.862952)
			(xy 39.389747 -391.883684) (xy 39.434715 -391.89641) (xy 39.481252 -391.9007) (xy 39.527789 -391.89641)
			(xy 39.572757 -391.883684) (xy 39.61464 -391.862952) (xy 39.633652 -391.849356) (xy 39.655775 -391.833441)
			(xy 39.703602 -391.807317) (xy 39.75466 -391.788266) (xy 39.807909 -391.776676) (xy 39.862266 -391.772784)
			(xy 39.916624 -391.776667) (xy 39.969876 -391.788247) (xy 40.020937 -391.807289) (xy 40.068768 -391.833404)
			(xy 40.112396 -391.866061) (xy 40.150931 -391.904595) (xy 40.183589 -391.948222) (xy 40.209706 -391.996052)
			(xy 40.228749 -392.047113) (xy 40.240331 -392.100364) (xy 40.244216 -392.154722) (xy 40.605076 -392.154722)
			(xy 40.608961 -392.100367) (xy 40.620541 -392.047119) (xy 40.639582 -391.996061) (xy 40.665695 -391.948232)
			(xy 40.698349 -391.904607) (xy 40.73688 -391.866073) (xy 40.780502 -391.833414) (xy 40.828328 -391.807297)
			(xy 40.879385 -391.788251) (xy 40.932632 -391.776666) (xy 40.986986 -391.772776) (xy 41.04134 -391.776662)
			(xy 41.094588 -391.788243) (xy 41.145646 -391.807285) (xy 41.193474 -391.833399) (xy 41.215564 -391.849356)
			(xy 41.234576 -391.862952) (xy 41.276459 -391.883684) (xy 41.321427 -391.89641) (xy 41.367964 -391.9007)
			(xy 41.414501 -391.89641) (xy 41.459469 -391.883684) (xy 41.501352 -391.862952) (xy 41.520364 -391.849356)
			(xy 41.542487 -391.833442) (xy 41.590313 -391.80732) (xy 41.641369 -391.788271) (xy 41.694618 -391.776682)
			(xy 41.748973 -391.772791) (xy 41.803329 -391.776675) (xy 41.856579 -391.788256) (xy 41.907638 -391.807297)
			(xy 41.955468 -391.833412) (xy 41.999094 -391.866069) (xy 42.037627 -391.904602) (xy 42.070285 -391.948228)
			(xy 42.0964 -391.996057) (xy 42.115443 -392.047116) (xy 42.127024 -392.100366) (xy 42.130909 -392.154722)
			(xy 42.846051 -392.154722) (xy 42.849936 -392.100362) (xy 42.861518 -392.047108) (xy 42.880562 -391.996045)
			(xy 42.906679 -391.948211) (xy 42.939337 -391.904582) (xy 42.977873 -391.866045) (xy 43.021501 -391.833385)
			(xy 43.069334 -391.807266) (xy 43.120397 -391.788222) (xy 43.17365 -391.776638) (xy 43.22801 -391.772751)
			(xy 43.28237 -391.776641) (xy 43.335622 -391.788227) (xy 43.386684 -391.807275) (xy 43.434515 -391.833396)
			(xy 43.456606 -391.849356) (xy 43.475618 -391.862952) (xy 43.517501 -391.883684) (xy 43.562469 -391.89641)
			(xy 43.609006 -391.9007) (xy 43.655543 -391.89641) (xy 43.700511 -391.883684) (xy 43.742394 -391.862952)
			(xy 43.761406 -391.849356) (xy 43.783528 -391.833445) (xy 43.831351 -391.80733) (xy 43.882404 -391.788287)
			(xy 43.935647 -391.776704) (xy 43.989997 -391.772816) (xy 44.044347 -391.776703) (xy 44.097591 -391.788285)
			(xy 44.148644 -391.807328) (xy 44.196467 -391.833442) (xy 44.240087 -391.866097) (xy 44.278616 -391.904627)
			(xy 44.311268 -391.948249) (xy 44.33738 -391.996073) (xy 44.35642 -392.047127) (xy 44.368 -392.100371)
			(xy 44.371884 -392.154722) (xy 44.750061 -392.154722) (xy 44.753945 -392.100364) (xy 44.765527 -392.047112)
			(xy 44.784569 -391.996051) (xy 44.810685 -391.948219) (xy 44.843342 -391.904592) (xy 44.881876 -391.866056)
			(xy 44.925502 -391.833396) (xy 44.973332 -391.807278) (xy 45.024392 -391.788233) (xy 45.077643 -391.776648)
			(xy 45.132001 -391.772761) (xy 45.186358 -391.776649) (xy 45.239609 -391.788233) (xy 45.29067 -391.807279)
			(xy 45.338499 -391.833397) (xy 45.36059 -391.849356) (xy 45.379602 -391.862952) (xy 45.421485 -391.883684)
			(xy 45.466453 -391.89641) (xy 45.51299 -391.9007) (xy 45.559527 -391.89641) (xy 45.604495 -391.883684)
			(xy 45.646378 -391.862952) (xy 45.66539 -391.849356) (xy 45.687512 -391.833444) (xy 45.735336 -391.807326)
			(xy 45.786391 -391.788281) (xy 45.839636 -391.776696) (xy 45.893988 -391.772806) (xy 45.94834 -391.776692)
			(xy 46.001586 -391.788274) (xy 46.052642 -391.807316) (xy 46.100467 -391.833431) (xy 46.14409 -391.866086)
			(xy 46.18262 -391.904618) (xy 46.215274 -391.948241) (xy 46.230209 -391.975594) (xy 73.545698 -391.975594)
			(xy 73.549769 -391.919972) (xy 73.561895 -391.865535) (xy 73.581818 -391.813444) (xy 73.609114 -391.764809)
			(xy 73.6432 -391.720666) (xy 73.683349 -391.681957) (xy 73.728707 -391.649506) (xy 73.778307 -391.624005)
			(xy 73.831091 -391.605998) (xy 73.885934 -391.595868) (xy 73.941668 -391.593831) (xy 73.997105 -391.599931)
			(xy 74.051062 -391.614037) (xy 74.102391 -391.635849) (xy 74.149997 -391.664903) (xy 74.192865 -391.700578)
			(xy 74.230082 -391.742115) (xy 74.260855 -391.788628) (xy 74.284527 -391.839125) (xy 74.300595 -391.892532)
			(xy 74.308715 -391.947708) (xy 74.309224 -391.975594) (xy 74.719432 -391.975594) (xy 74.723503 -391.919972)
			(xy 74.735629 -391.865535) (xy 74.755552 -391.813444) (xy 74.782848 -391.764809) (xy 74.816934 -391.720666)
			(xy 74.857083 -391.681957) (xy 74.902441 -391.649506) (xy 74.952041 -391.624005) (xy 75.004825 -391.605998)
			(xy 75.059668 -391.595868) (xy 75.115402 -391.593831) (xy 75.170839 -391.599931) (xy 75.224796 -391.614037)
			(xy 75.276125 -391.635849) (xy 75.323731 -391.664903) (xy 75.366599 -391.700578) (xy 75.403816 -391.742115)
			(xy 75.434589 -391.788628) (xy 75.458261 -391.839125) (xy 75.474329 -391.892532) (xy 75.482449 -391.947708)
			(xy 75.482958 -391.975594) (xy 75.91755 -391.975594) (xy 75.921621 -391.919972) (xy 75.933747 -391.865535)
			(xy 75.95367 -391.813444) (xy 75.980966 -391.764809) (xy 76.015052 -391.720666) (xy 76.055201 -391.681957)
			(xy 76.100559 -391.649506) (xy 76.150159 -391.624005) (xy 76.202943 -391.605998) (xy 76.257786 -391.595868)
			(xy 76.31352 -391.593831) (xy 76.368957 -391.599931) (xy 76.422914 -391.614037) (xy 76.474243 -391.635849)
			(xy 76.521849 -391.664903) (xy 76.564717 -391.700578) (xy 76.601934 -391.742115) (xy 76.632707 -391.788628)
			(xy 76.656379 -391.839125) (xy 76.672447 -391.892532) (xy 76.680567 -391.947708) (xy 76.681076 -391.975594)
			(xy 77.054962 -391.975594) (xy 77.059033 -391.919972) (xy 77.071159 -391.865535) (xy 77.091082 -391.813444)
			(xy 77.118378 -391.764809) (xy 77.152464 -391.720666) (xy 77.192613 -391.681957) (xy 77.237971 -391.649506)
			(xy 77.287571 -391.624005) (xy 77.340355 -391.605998) (xy 77.395198 -391.595868) (xy 77.450932 -391.593831)
			(xy 77.506369 -391.599931) (xy 77.560326 -391.614037) (xy 77.611655 -391.635849) (xy 77.659261 -391.664903)
			(xy 77.702129 -391.700578) (xy 77.739346 -391.742115) (xy 77.770119 -391.788628) (xy 77.793791 -391.839125)
			(xy 77.809859 -391.892532) (xy 77.817979 -391.947708) (xy 77.818488 -391.975594) (xy 77.817979 -392.00348)
			(xy 77.809859 -392.058656) (xy 77.793791 -392.112063) (xy 77.770119 -392.16256) (xy 77.739346 -392.209073)
			(xy 77.702129 -392.25061) (xy 77.659261 -392.286285) (xy 77.611655 -392.315339) (xy 77.560326 -392.337151)
			(xy 77.506369 -392.351257) (xy 77.450932 -392.357357) (xy 77.395198 -392.35532) (xy 77.340355 -392.34519)
			(xy 77.287571 -392.327183) (xy 77.237971 -392.301682) (xy 77.192613 -392.269231) (xy 77.152464 -392.230522)
			(xy 77.118378 -392.186379) (xy 77.091082 -392.137744) (xy 77.071159 -392.085653) (xy 77.059033 -392.031216)
			(xy 77.054962 -391.975594) (xy 76.681076 -391.975594) (xy 76.680567 -392.00348) (xy 76.672447 -392.058656)
			(xy 76.656379 -392.112063) (xy 76.632707 -392.16256) (xy 76.601934 -392.209073) (xy 76.564717 -392.25061)
			(xy 76.521849 -392.286285) (xy 76.474243 -392.315339) (xy 76.422914 -392.337151) (xy 76.368957 -392.351257)
			(xy 76.31352 -392.357357) (xy 76.257786 -392.35532) (xy 76.202943 -392.34519) (xy 76.150159 -392.327183)
			(xy 76.100559 -392.301682) (xy 76.055201 -392.269231) (xy 76.015052 -392.230522) (xy 75.980966 -392.186379)
			(xy 75.95367 -392.137744) (xy 75.933747 -392.085653) (xy 75.921621 -392.031216) (xy 75.91755 -391.975594)
			(xy 75.482958 -391.975594) (xy 75.482449 -392.00348) (xy 75.474329 -392.058656) (xy 75.458261 -392.112063)
			(xy 75.434589 -392.16256) (xy 75.403816 -392.209073) (xy 75.366599 -392.25061) (xy 75.323731 -392.286285)
			(xy 75.276125 -392.315339) (xy 75.224796 -392.337151) (xy 75.170839 -392.351257) (xy 75.115402 -392.357357)
			(xy 75.059668 -392.35532) (xy 75.004825 -392.34519) (xy 74.952041 -392.327183) (xy 74.902441 -392.301682)
			(xy 74.857083 -392.269231) (xy 74.816934 -392.230522) (xy 74.782848 -392.186379) (xy 74.755552 -392.137744)
			(xy 74.735629 -392.085653) (xy 74.723503 -392.031216) (xy 74.719432 -391.975594) (xy 74.309224 -391.975594)
			(xy 74.308715 -392.00348) (xy 74.300595 -392.058656) (xy 74.284527 -392.112063) (xy 74.260855 -392.16256)
			(xy 74.230082 -392.209073) (xy 74.192865 -392.25061) (xy 74.149997 -392.286285) (xy 74.102391 -392.315339)
			(xy 74.051062 -392.337151) (xy 73.997105 -392.351257) (xy 73.941668 -392.357357) (xy 73.885934 -392.35532)
			(xy 73.831091 -392.34519) (xy 73.778307 -392.327183) (xy 73.728707 -392.301682) (xy 73.683349 -392.269231)
			(xy 73.6432 -392.230522) (xy 73.609114 -392.186379) (xy 73.581818 -392.137744) (xy 73.561895 -392.085653)
			(xy 73.549769 -392.031216) (xy 73.545698 -391.975594) (xy 46.230209 -391.975594) (xy 46.241388 -391.996067)
			(xy 46.260429 -392.047123) (xy 46.272009 -392.100369) (xy 46.275894 -392.154722) (xy 46.272003 -392.209074)
			(xy 46.260417 -392.262319) (xy 46.24137 -392.313372) (xy 46.215251 -392.361196) (xy 46.182592 -392.404815)
			(xy 46.144057 -392.443342) (xy 46.100431 -392.475993) (xy 46.052602 -392.502102) (xy 46.001545 -392.521138)
			(xy 45.948297 -392.532714) (xy 45.893945 -392.536594) (xy 45.839593 -392.532698) (xy 45.786349 -392.521107)
			(xy 45.735297 -392.502056) (xy 45.687476 -392.475933) (xy 45.66539 -392.459972) (xy 45.646378 -392.446376)
			(xy 45.604495 -392.425644) (xy 45.559527 -392.412918) (xy 45.51299 -392.408628) (xy 45.466453 -392.412918)
			(xy 45.421485 -392.425644) (xy 45.379602 -392.446376) (xy 45.36059 -392.459972) (xy 45.338536 -392.47598)
			(xy 45.290709 -392.502103) (xy 45.239651 -392.521155) (xy 45.186401 -392.532745) (xy 45.132044 -392.536639)
			(xy 45.077686 -392.532758) (xy 45.024434 -392.521179) (xy 44.973371 -392.50214) (xy 44.925538 -392.476027)
			(xy 44.881908 -392.443373) (xy 44.84337 -392.404841) (xy 44.810708 -392.361217) (xy 44.784587 -392.313389)
			(xy 44.765539 -392.262329) (xy 44.753952 -392.209079) (xy 44.750061 -392.154722) (xy 44.371884 -392.154722)
			(xy 44.367994 -392.209071) (xy 44.356408 -392.262314) (xy 44.337362 -392.313366) (xy 44.311245 -392.361188)
			(xy 44.278587 -392.404806) (xy 44.240054 -392.443332) (xy 44.196431 -392.475982) (xy 44.148604 -392.50209)
			(xy 44.097549 -392.521127) (xy 44.044304 -392.532703) (xy 43.989954 -392.536584) (xy 43.935604 -392.53269)
			(xy 43.882362 -392.521101) (xy 43.831311 -392.502052) (xy 43.783491 -392.475932) (xy 43.761406 -392.459972)
			(xy 43.742394 -392.446376) (xy 43.700511 -392.425644) (xy 43.655543 -392.412918) (xy 43.609006 -392.408628)
			(xy 43.562469 -392.412918) (xy 43.517501 -392.425644) (xy 43.475618 -392.446376) (xy 43.456606 -392.459972)
			(xy 43.434551 -392.475981) (xy 43.386723 -392.502107) (xy 43.335664 -392.521161) (xy 43.282412 -392.532753)
			(xy 43.228053 -392.536649) (xy 43.173693 -392.532768) (xy 43.120438 -392.521191) (xy 43.069373 -392.502151)
			(xy 43.021538 -392.476038) (xy 42.977906 -392.443383) (xy 42.939366 -392.40485) (xy 42.906702 -392.361225)
			(xy 42.88058 -392.313395) (xy 42.86153 -392.262334) (xy 42.849942 -392.209081) (xy 42.846051 -392.154722)
			(xy 42.130909 -392.154722) (xy 42.127018 -392.209077) (xy 42.115431 -392.262325) (xy 42.096382 -392.313383)
			(xy 42.070261 -392.361209) (xy 42.037599 -392.40483) (xy 41.999061 -392.443359) (xy 41.955432 -392.476011)
			(xy 41.907599 -392.502121) (xy 41.856537 -392.521157) (xy 41.803286 -392.532731) (xy 41.74893 -392.536609)
			(xy 41.694575 -392.532711) (xy 41.641328 -392.521117) (xy 41.590273 -392.502062) (xy 41.54245 -392.475935)
			(xy 41.520364 -392.459972) (xy 41.501352 -392.446376) (xy 41.459469 -392.425644) (xy 41.414501 -392.412918)
			(xy 41.367964 -392.408628) (xy 41.321427 -392.412918) (xy 41.276459 -392.425644) (xy 41.234576 -392.446376)
			(xy 41.215564 -392.459972) (xy 41.19351 -392.475977) (xy 41.145685 -392.502097) (xy 41.09463 -392.521145)
			(xy 41.041383 -392.532732) (xy 40.987029 -392.536624) (xy 40.932675 -392.53274) (xy 40.879426 -392.521161)
			(xy 40.828368 -392.502121) (xy 40.780539 -392.476009) (xy 40.736913 -392.443356) (xy 40.698378 -392.404826)
			(xy 40.665718 -392.361204) (xy 40.6396 -392.313378) (xy 40.620553 -392.262322) (xy 40.608967 -392.209075)
			(xy 40.605076 -392.154722) (xy 40.244216 -392.154722) (xy 40.240325 -392.209079) (xy 40.228737 -392.262329)
			(xy 40.209688 -392.313387) (xy 40.183566 -392.361215) (xy 40.150903 -392.404837) (xy 40.112363 -392.443367)
			(xy 40.068732 -392.476019) (xy 40.020898 -392.502129) (xy 39.969834 -392.521165) (xy 39.916581 -392.532739)
			(xy 39.862223 -392.536616) (xy 39.807866 -392.532717) (xy 39.754618 -392.521122) (xy 39.703562 -392.502065)
			(xy 39.655739 -392.475936) (xy 39.633652 -392.459972) (xy 39.61464 -392.446376) (xy 39.572757 -392.425644)
			(xy 39.527789 -392.412918) (xy 39.481252 -392.408628) (xy 39.434715 -392.412918) (xy 39.389747 -392.425644)
			(xy 39.347864 -392.446376) (xy 39.328852 -392.459972) (xy 39.306799 -392.475976) (xy 39.258974 -392.502094)
			(xy 39.20792 -392.52114) (xy 39.154675 -392.532726) (xy 39.100322 -392.536617) (xy 39.04597 -392.532732)
			(xy 38.992723 -392.521153) (xy 38.941666 -392.502113) (xy 38.893839 -392.476001) (xy 38.850214 -392.443348)
			(xy 38.811681 -392.404819) (xy 38.779023 -392.361198) (xy 38.752906 -392.313374) (xy 38.73386 -392.262319)
			(xy 38.722274 -392.209074) (xy 38.718383 -392.154722) (xy 29.254196 -392.154722) (xy 29.254196 -393.793488)
			(xy 29.519874 -393.793488) (xy 29.519874 -393.706588) (xy 29.527892 -393.620059) (xy 29.54386 -393.534639)
			(xy 29.567641 -393.451057) (xy 29.599033 -393.370025) (xy 29.637767 -393.292236) (xy 29.683514 -393.218352)
			(xy 29.735883 -393.149005) (xy 29.794427 -393.084785) (xy 29.858647 -393.026241) (xy 29.927994 -392.973872)
			(xy 30.001878 -392.928125) (xy 30.079667 -392.889391) (xy 30.160699 -392.857999) (xy 30.244281 -392.834218)
			(xy 30.329701 -392.81825) (xy 30.41623 -392.810232) (xy 30.50313 -392.810232) (xy 30.589659 -392.81825)
			(xy 30.675079 -392.834218) (xy 30.758661 -392.857999) (xy 30.839693 -392.889391) (xy 30.917482 -392.928125)
			(xy 30.991366 -392.973872) (xy 31.060713 -393.026241) (xy 31.124933 -393.084785) (xy 31.183477 -393.149005)
			(xy 31.235846 -393.218352) (xy 31.281593 -393.292236) (xy 31.320327 -393.370025) (xy 31.351719 -393.451057)
			(xy 31.3755 -393.534639) (xy 31.391468 -393.620059) (xy 31.399486 -393.706588) (xy 31.399988 -393.750038)
			(xy 31.399486 -393.793488) (xy 34.599874 -393.793488) (xy 34.599874 -393.706588) (xy 34.607892 -393.620059)
			(xy 34.62386 -393.534639) (xy 34.647641 -393.451057) (xy 34.679033 -393.370025) (xy 34.717767 -393.292236)
			(xy 34.763514 -393.218352) (xy 34.815883 -393.149005) (xy 34.874427 -393.084785) (xy 34.938647 -393.026241)
			(xy 35.007994 -392.973872) (xy 35.081878 -392.928125) (xy 35.159667 -392.889391) (xy 35.240699 -392.857999)
			(xy 35.324281 -392.834218) (xy 35.409701 -392.81825) (xy 35.49623 -392.810232) (xy 35.58313 -392.810232)
			(xy 35.669659 -392.81825) (xy 35.755079 -392.834218) (xy 35.838661 -392.857999) (xy 35.919693 -392.889391)
			(xy 35.997482 -392.928125) (xy 36.071366 -392.973872) (xy 36.140713 -393.026241) (xy 36.204933 -393.084785)
			(xy 36.263477 -393.149005) (xy 36.315846 -393.218352) (xy 36.361593 -393.292236) (xy 36.400327 -393.370025)
			(xy 36.431719 -393.451057) (xy 36.4555 -393.534639) (xy 36.471468 -393.620059) (xy 36.479486 -393.706588)
			(xy 36.479988 -393.750038) (xy 36.479486 -393.793488) (xy 36.471468 -393.880017) (xy 36.4555 -393.965437)
			(xy 36.431719 -394.049019) (xy 36.425719 -394.064506) (xy 38.718404 -394.064506) (xy 38.722291 -394.010156)
			(xy 38.733872 -393.956913) (xy 38.752913 -393.90586) (xy 38.779026 -393.858036) (xy 38.811679 -393.814416)
			(xy 38.850207 -393.775886) (xy 38.893827 -393.743232) (xy 38.94165 -393.717118) (xy 38.992702 -393.698075)
			(xy 39.045945 -393.686492) (xy 39.100295 -393.682604) (xy 39.154644 -393.686491) (xy 39.207888 -393.698072)
			(xy 39.258941 -393.717113) (xy 39.306764 -393.743226) (xy 39.328852 -393.759182) (xy 39.347864 -393.772778)
			(xy 39.389747 -393.79351) (xy 39.434715 -393.806236) (xy 39.481252 -393.810526) (xy 39.527789 -393.806236)
			(xy 39.572757 -393.79351) (xy 39.61464 -393.772778) (xy 39.633652 -393.759182) (xy 39.655751 -393.743231)
			(xy 39.703579 -393.717104) (xy 39.754639 -393.698051) (xy 39.807891 -393.686458) (xy 39.862251 -393.682563)
			(xy 39.916611 -393.686444) (xy 39.969866 -393.698023) (xy 40.020931 -393.717063) (xy 40.068766 -393.743178)
			(xy 40.112397 -393.775835) (xy 40.150936 -393.81437) (xy 40.183598 -393.857997) (xy 40.209719 -393.905829)
			(xy 40.228765 -393.956892) (xy 40.24035 -394.010146) (xy 40.244237 -394.064506) (xy 40.605097 -394.064506)
			(xy 40.608984 -394.010155) (xy 40.620565 -393.95691) (xy 40.639607 -393.905855) (xy 40.665721 -393.85803)
			(xy 40.698375 -393.814409) (xy 40.736905 -393.775878) (xy 40.780527 -393.743223) (xy 40.828351 -393.717109)
			(xy 40.879406 -393.698067) (xy 40.93265 -393.686484) (xy 40.987002 -393.682597) (xy 41.041353 -393.686485)
			(xy 41.094597 -393.698068) (xy 41.145652 -393.71711) (xy 41.193476 -393.743225) (xy 41.215564 -393.759182)
			(xy 41.234576 -393.772778) (xy 41.276459 -393.79351) (xy 41.321427 -393.806236) (xy 41.367964 -393.810526)
			(xy 41.414501 -393.806236) (xy 41.459469 -393.79351) (xy 41.501352 -393.772778) (xy 41.520364 -393.759182)
			(xy 41.542462 -393.743232) (xy 41.59029 -393.717107) (xy 41.641349 -393.698055) (xy 41.694599 -393.686464)
			(xy 41.748957 -393.68257) (xy 41.803317 -393.686452) (xy 41.85657 -393.698031) (xy 41.907633 -393.717072)
			(xy 41.955466 -393.743187) (xy 41.999096 -393.775843) (xy 42.037633 -393.814377) (xy 42.070294 -393.858003)
			(xy 42.096413 -393.905834) (xy 42.115458 -393.956895) (xy 42.127043 -394.010147) (xy 42.13093 -394.064506)
			(xy 42.846072 -394.064506) (xy 42.849959 -394.010149) (xy 42.861543 -393.956899) (xy 42.880587 -393.905839)
			(xy 42.906705 -393.858009) (xy 42.939363 -393.814384) (xy 42.977899 -393.775851) (xy 43.021526 -393.743194)
			(xy 43.069357 -393.717079) (xy 43.120417 -393.698037) (xy 43.173668 -393.686456) (xy 43.228025 -393.682572)
			(xy 43.282382 -393.686463) (xy 43.335631 -393.698051) (xy 43.38669 -393.7171) (xy 43.434517 -393.743222)
			(xy 43.456606 -393.759182) (xy 43.475618 -393.772778) (xy 43.517501 -393.79351) (xy 43.562469 -393.806236)
			(xy 43.609006 -393.810526) (xy 43.655543 -393.806236) (xy 43.700511 -393.79351) (xy 43.742394 -393.772778)
			(xy 43.761406 -393.759182) (xy 43.783503 -393.743236) (xy 43.831328 -393.717118) (xy 43.882383 -393.698071)
			(xy 43.935629 -393.686485) (xy 43.989981 -393.682595) (xy 44.044335 -393.68648) (xy 44.097581 -393.698061)
			(xy 44.148638 -393.717102) (xy 44.196465 -393.743216) (xy 44.240089 -393.775871) (xy 44.278621 -393.814402)
			(xy 44.311277 -393.858024) (xy 44.337393 -393.90585) (xy 44.356436 -393.956906) (xy 44.368018 -394.010153)
			(xy 44.371905 -394.064506) (xy 44.750081 -394.064506) (xy 44.753968 -394.010151) (xy 44.765551 -393.956903)
			(xy 44.784595 -393.905845) (xy 44.810711 -393.858017) (xy 44.843368 -393.814393) (xy 44.881901 -393.775861)
			(xy 44.925526 -393.743205) (xy 44.973355 -393.71709) (xy 45.024413 -393.698048) (xy 45.077662 -393.686467)
			(xy 45.132016 -393.682581) (xy 45.186371 -393.686471) (xy 45.239618 -393.698058) (xy 45.290675 -393.717104)
			(xy 45.338501 -393.743223) (xy 45.36059 -393.759182) (xy 45.379602 -393.772778) (xy 45.421485 -393.79351)
			(xy 45.466453 -393.806236) (xy 45.51299 -393.810526) (xy 45.559527 -393.806236) (xy 45.604495 -393.79351)
			(xy 45.646378 -393.772778) (xy 45.66539 -393.759182) (xy 45.687488 -393.743235) (xy 45.735313 -393.717114)
			(xy 45.78637 -393.698065) (xy 45.839617 -393.686477) (xy 45.893972 -393.682585) (xy 45.948328 -393.686469)
			(xy 46.001577 -393.69805) (xy 46.052636 -393.717091) (xy 46.100466 -393.743205) (xy 46.144091 -393.77586)
			(xy 46.182626 -393.814392) (xy 46.215284 -393.858016) (xy 46.2414 -393.905844) (xy 46.260444 -393.956902)
			(xy 46.272028 -394.010151) (xy 46.275915 -394.064506) (xy 46.272026 -394.118861) (xy 46.260441 -394.172109)
			(xy 46.241395 -394.223167) (xy 46.215277 -394.270994) (xy 46.182618 -394.314617) (xy 46.144082 -394.353148)
			(xy 46.100455 -394.385802) (xy 46.052625 -394.411914) (xy 46.001566 -394.430954) (xy 45.948316 -394.442532)
			(xy 45.89396 -394.446415) (xy 45.839606 -394.442521) (xy 45.786358 -394.430931) (xy 45.735302 -394.411881)
			(xy 45.687478 -394.385759) (xy 45.66539 -394.369798) (xy 45.646378 -394.356202) (xy 45.604495 -394.33547)
			(xy 45.559527 -394.322744) (xy 45.51299 -394.318454) (xy 45.466453 -394.322744) (xy 45.421485 -394.33547)
			(xy 45.379602 -394.356202) (xy 45.36059 -394.369798) (xy 45.338511 -394.385771) (xy 45.290686 -394.411891)
			(xy 45.23963 -394.430939) (xy 45.186383 -394.442527) (xy 45.132028 -394.446419) (xy 45.077673 -394.442535)
			(xy 45.024424 -394.430955) (xy 44.973366 -394.411915) (xy 44.925536 -394.385801) (xy 44.88191 -394.353147)
			(xy 44.843376 -394.314616) (xy 44.810717 -394.270993) (xy 44.7846 -394.223166) (xy 44.765555 -394.172109)
			(xy 44.75397 -394.118861) (xy 44.750081 -394.064506) (xy 44.371905 -394.064506) (xy 44.368017 -394.118859)
			(xy 44.356432 -394.172105) (xy 44.337388 -394.223161) (xy 44.311271 -394.270986) (xy 44.278613 -394.314608)
			(xy 44.24008 -394.353137) (xy 44.196455 -394.385791) (xy 44.148627 -394.411903) (xy 44.09757 -394.430942)
			(xy 44.044323 -394.442522) (xy 43.989969 -394.446405) (xy 43.935617 -394.442513) (xy 43.882371 -394.430925)
			(xy 43.831317 -394.411877) (xy 43.783493 -394.385757) (xy 43.761406 -394.369798) (xy 43.742394 -394.356202)
			(xy 43.700511 -394.33547) (xy 43.655543 -394.322744) (xy 43.609006 -394.318454) (xy 43.562469 -394.322744)
			(xy 43.517501 -394.33547) (xy 43.475618 -394.356202) (xy 43.456606 -394.369798) (xy 43.434527 -394.385772)
			(xy 43.386701 -394.411895) (xy 43.335643 -394.430945) (xy 43.282394 -394.442535) (xy 43.228037 -394.446428)
			(xy 43.17368 -394.442546) (xy 43.120429 -394.430966) (xy 43.069368 -394.411926) (xy 43.021536 -394.385812)
			(xy 42.977908 -394.353157) (xy 42.939371 -394.314625) (xy 42.906711 -394.271001) (xy 42.880592 -394.223172)
			(xy 42.861546 -394.172113) (xy 42.849961 -394.118863) (xy 42.846072 -394.064506) (xy 42.13093 -394.064506)
			(xy 42.127041 -394.118865) (xy 42.115455 -394.172116) (xy 42.096408 -394.223177) (xy 42.070287 -394.271007)
			(xy 42.037625 -394.314632) (xy 41.999086 -394.353165) (xy 41.955456 -394.38582) (xy 41.907622 -394.411933)
			(xy 41.856558 -394.430972) (xy 41.803305 -394.44255) (xy 41.748945 -394.44643) (xy 41.694587 -394.442534)
			(xy 41.641337 -394.430941) (xy 41.590279 -394.411888) (xy 41.542452 -394.385761) (xy 41.520364 -394.369798)
			(xy 41.501352 -394.356202) (xy 41.459469 -394.33547) (xy 41.414501 -394.322744) (xy 41.367964 -394.318454)
			(xy 41.321427 -394.322744) (xy 41.276459 -394.33547) (xy 41.234576 -394.356202) (xy 41.215564 -394.369798)
			(xy 41.193486 -394.385768) (xy 41.145662 -394.411885) (xy 41.094609 -394.430929) (xy 41.041365 -394.442514)
			(xy 40.987014 -394.446403) (xy 40.932662 -394.442518) (xy 40.879417 -394.430937) (xy 40.828362 -394.411896)
			(xy 40.780537 -394.385783) (xy 40.736914 -394.35313) (xy 40.698383 -394.3146) (xy 40.665728 -394.27098)
			(xy 40.639612 -394.223156) (xy 40.620569 -394.172102) (xy 40.608985 -394.118857) (xy 40.605097 -394.064506)
			(xy 40.244237 -394.064506) (xy 40.240348 -394.118866) (xy 40.228762 -394.17212) (xy 40.209714 -394.223182)
			(xy 40.183592 -394.271013) (xy 40.150929 -394.314639) (xy 40.112388 -394.353173) (xy 40.068756 -394.385828)
			(xy 40.02092 -394.411942) (xy 39.969855 -394.430981) (xy 39.9166 -394.442558) (xy 39.862239 -394.446437)
			(xy 39.807879 -394.44254) (xy 39.754627 -394.430946) (xy 39.703568 -394.411891) (xy 39.655741 -394.385762)
			(xy 39.633652 -394.369798) (xy 39.61464 -394.356202) (xy 39.572757 -394.33547) (xy 39.527789 -394.322744)
			(xy 39.481252 -394.318454) (xy 39.434715 -394.322744) (xy 39.389747 -394.33547) (xy 39.347864 -394.356202)
			(xy 39.328852 -394.369798) (xy 39.306774 -394.385767) (xy 39.258952 -394.411882) (xy 39.207899 -394.430924)
			(xy 39.154656 -394.442508) (xy 39.100307 -394.446396) (xy 39.045957 -394.44251) (xy 38.992714 -394.430928)
			(xy 38.941661 -394.411887) (xy 38.893837 -394.385775) (xy 38.850216 -394.353122) (xy 38.811687 -394.314593)
			(xy 38.779032 -394.270974) (xy 38.752918 -394.223151) (xy 38.733875 -394.172098) (xy 38.722292 -394.118855)
			(xy 38.718404 -394.064506) (xy 36.425719 -394.064506) (xy 36.400327 -394.130051) (xy 36.361593 -394.20784)
			(xy 36.315846 -394.281724) (xy 36.263477 -394.351071) (xy 36.204933 -394.415291) (xy 36.140713 -394.473835)
			(xy 36.071366 -394.526204) (xy 35.997482 -394.571951) (xy 35.919693 -394.610685) (xy 35.838661 -394.642077)
			(xy 35.755079 -394.665858) (xy 35.669659 -394.681826) (xy 35.58313 -394.689844) (xy 35.49623 -394.689844)
			(xy 35.409701 -394.681826) (xy 35.324281 -394.665858) (xy 35.240699 -394.642077) (xy 35.159667 -394.610685)
			(xy 35.081878 -394.571951) (xy 35.007994 -394.526204) (xy 34.938647 -394.473835) (xy 34.874427 -394.415291)
			(xy 34.815883 -394.351071) (xy 34.763514 -394.281724) (xy 34.717767 -394.20784) (xy 34.679033 -394.130051)
			(xy 34.647641 -394.049019) (xy 34.62386 -393.965437) (xy 34.607892 -393.880017) (xy 34.599874 -393.793488)
			(xy 31.399486 -393.793488) (xy 31.391468 -393.880017) (xy 31.3755 -393.965437) (xy 31.351719 -394.049019)
			(xy 31.320327 -394.130051) (xy 31.281593 -394.20784) (xy 31.235846 -394.281724) (xy 31.183477 -394.351071)
			(xy 31.124933 -394.415291) (xy 31.060713 -394.473835) (xy 30.991366 -394.526204) (xy 30.917482 -394.571951)
			(xy 30.839693 -394.610685) (xy 30.758661 -394.642077) (xy 30.675079 -394.665858) (xy 30.589659 -394.681826)
			(xy 30.50313 -394.689844) (xy 30.41623 -394.689844) (xy 30.329701 -394.681826) (xy 30.244281 -394.665858)
			(xy 30.160699 -394.642077) (xy 30.079667 -394.610685) (xy 30.001878 -394.571951) (xy 29.927994 -394.526204)
			(xy 29.858647 -394.473835) (xy 29.794427 -394.415291) (xy 29.735883 -394.351071) (xy 29.683514 -394.281724)
			(xy 29.637767 -394.20784) (xy 29.599033 -394.130051) (xy 29.567641 -394.049019) (xy 29.54386 -393.965437)
			(xy 29.527892 -393.880017) (xy 29.519874 -393.793488) (xy 29.254196 -393.793488) (xy 29.254196 -396.333488)
			(xy 29.519874 -396.333488) (xy 29.519874 -396.246588) (xy 29.527892 -396.160059) (xy 29.54386 -396.074639)
			(xy 29.567641 -395.991057) (xy 29.599033 -395.910025) (xy 29.637767 -395.832236) (xy 29.683514 -395.758352)
			(xy 29.735883 -395.689005) (xy 29.794427 -395.624785) (xy 29.858647 -395.566241) (xy 29.927994 -395.513872)
			(xy 30.001878 -395.468125) (xy 30.079667 -395.429391) (xy 30.160699 -395.397999) (xy 30.244281 -395.374218)
			(xy 30.329701 -395.35825) (xy 30.41623 -395.350232) (xy 30.50313 -395.350232) (xy 30.589659 -395.35825)
			(xy 30.675079 -395.374218) (xy 30.758661 -395.397999) (xy 30.839693 -395.429391) (xy 30.917482 -395.468125)
			(xy 30.991366 -395.513872) (xy 31.060713 -395.566241) (xy 31.124933 -395.624785) (xy 31.183477 -395.689005)
			(xy 31.235846 -395.758352) (xy 31.281593 -395.832236) (xy 31.320327 -395.910025) (xy 31.351719 -395.991057)
			(xy 31.3755 -396.074639) (xy 31.391468 -396.160059) (xy 31.399486 -396.246588) (xy 31.399988 -396.290038)
			(xy 31.399486 -396.333488) (xy 34.599874 -396.333488) (xy 34.599874 -396.246588) (xy 34.607892 -396.160059)
			(xy 34.62386 -396.074639) (xy 34.647641 -395.991057) (xy 34.679033 -395.910025) (xy 34.717767 -395.832236)
			(xy 34.763514 -395.758352) (xy 34.815883 -395.689005) (xy 34.874427 -395.624785) (xy 34.938647 -395.566241)
			(xy 35.007994 -395.513872) (xy 35.081878 -395.468125) (xy 35.159667 -395.429391) (xy 35.240699 -395.397999)
			(xy 35.324281 -395.374218) (xy 35.409701 -395.35825) (xy 35.49623 -395.350232) (xy 35.58313 -395.350232)
			(xy 35.669659 -395.35825) (xy 35.755079 -395.374218) (xy 35.838661 -395.397999) (xy 35.919693 -395.429391)
			(xy 35.997482 -395.468125) (xy 36.071366 -395.513872) (xy 36.140713 -395.566241) (xy 36.165583 -395.588913)
			(xy 47.708556 -395.588913) (xy 47.708556 -395.507803) (xy 47.716506 -395.427084) (xy 47.732329 -395.347533)
			(xy 47.755874 -395.269917) (xy 47.786913 -395.194981) (xy 47.825148 -395.123449) (xy 47.87021 -395.056009)
			(xy 47.921665 -394.99331) (xy 47.979018 -394.935957) (xy 48.041717 -394.884502) (xy 48.109157 -394.83944)
			(xy 48.180689 -394.801205) (xy 48.255625 -394.770166) (xy 48.333241 -394.746621) (xy 48.412792 -394.730798)
			(xy 48.493511 -394.722848) (xy 48.574621 -394.722848) (xy 48.65534 -394.730798) (xy 48.734891 -394.746621)
			(xy 48.812507 -394.770166) (xy 48.887443 -394.801205) (xy 48.958975 -394.83944) (xy 49.026415 -394.884502)
			(xy 49.089114 -394.935957) (xy 49.146467 -394.99331) (xy 49.197922 -395.056009) (xy 49.242984 -395.123449)
			(xy 49.281219 -395.194981) (xy 49.312258 -395.269917) (xy 49.335803 -395.347533) (xy 49.351626 -395.427084)
			(xy 49.359576 -395.507803) (xy 49.360074 -395.548358) (xy 49.359576 -395.588913) (xy 51.208676 -395.588913)
			(xy 51.208676 -395.507803) (xy 51.216626 -395.427084) (xy 51.232449 -395.347533) (xy 51.255994 -395.269917)
			(xy 51.287033 -395.194981) (xy 51.325268 -395.123449) (xy 51.37033 -395.056009) (xy 51.421785 -394.99331)
			(xy 51.479138 -394.935957) (xy 51.541837 -394.884502) (xy 51.609277 -394.83944) (xy 51.680809 -394.801205)
			(xy 51.755745 -394.770166) (xy 51.833361 -394.746621) (xy 51.912912 -394.730798) (xy 51.993631 -394.722848)
			(xy 52.074741 -394.722848) (xy 52.15546 -394.730798) (xy 52.235011 -394.746621) (xy 52.312627 -394.770166)
			(xy 52.387563 -394.801205) (xy 52.459095 -394.83944) (xy 52.526535 -394.884502) (xy 52.589234 -394.935957)
			(xy 52.646587 -394.99331) (xy 52.698042 -395.056009) (xy 52.743104 -395.123449) (xy 52.781339 -395.194981)
			(xy 52.812378 -395.269917) (xy 52.835923 -395.347533) (xy 52.851746 -395.427084) (xy 52.859696 -395.507803)
			(xy 52.860194 -395.548358) (xy 52.859696 -395.588913) (xy 52.851746 -395.669632) (xy 52.835923 -395.749183)
			(xy 52.812378 -395.826799) (xy 52.781339 -395.901735) (xy 52.743104 -395.973267) (xy 52.698042 -396.040707)
			(xy 52.646587 -396.103406) (xy 52.589234 -396.160759) (xy 52.526535 -396.212214) (xy 52.459095 -396.257276)
			(xy 52.387563 -396.295511) (xy 52.312627 -396.32655) (xy 52.235011 -396.350095) (xy 52.15546 -396.365918)
			(xy 52.074741 -396.373868) (xy 51.993631 -396.373868) (xy 51.912912 -396.365918) (xy 51.833361 -396.350095)
			(xy 51.755745 -396.32655) (xy 51.680809 -396.295511) (xy 51.609277 -396.257276) (xy 51.541837 -396.212214)
			(xy 51.479138 -396.160759) (xy 51.421785 -396.103406) (xy 51.37033 -396.040707) (xy 51.325268 -395.973267)
			(xy 51.287033 -395.901735) (xy 51.255994 -395.826799) (xy 51.232449 -395.749183) (xy 51.216626 -395.669632)
			(xy 51.208676 -395.588913) (xy 49.359576 -395.588913) (xy 49.351626 -395.669632) (xy 49.335803 -395.749183)
			(xy 49.312258 -395.826799) (xy 49.281219 -395.901735) (xy 49.242984 -395.973267) (xy 49.197922 -396.040707)
			(xy 49.146467 -396.103406) (xy 49.089114 -396.160759) (xy 49.026415 -396.212214) (xy 48.958975 -396.257276)
			(xy 48.887443 -396.295511) (xy 48.812507 -396.32655) (xy 48.734891 -396.350095) (xy 48.65534 -396.365918)
			(xy 48.574621 -396.373868) (xy 48.493511 -396.373868) (xy 48.412792 -396.365918) (xy 48.333241 -396.350095)
			(xy 48.255625 -396.32655) (xy 48.180689 -396.295511) (xy 48.109157 -396.257276) (xy 48.041717 -396.212214)
			(xy 47.979018 -396.160759) (xy 47.921665 -396.103406) (xy 47.87021 -396.040707) (xy 47.825148 -395.973267)
			(xy 47.786913 -395.901735) (xy 47.755874 -395.826799) (xy 47.732329 -395.749183) (xy 47.716506 -395.669632)
			(xy 47.708556 -395.588913) (xy 36.165583 -395.588913) (xy 36.204933 -395.624785) (xy 36.263477 -395.689005)
			(xy 36.315846 -395.758352) (xy 36.361593 -395.832236) (xy 36.400327 -395.910025) (xy 36.431719 -395.991057)
			(xy 36.4555 -396.074639) (xy 36.471468 -396.160059) (xy 36.479486 -396.246588) (xy 36.479988 -396.290038)
			(xy 36.479486 -396.333488) (xy 36.471468 -396.420017) (xy 36.4555 -396.505437) (xy 36.431719 -396.589019)
			(xy 36.400327 -396.670051) (xy 36.361593 -396.74784) (xy 36.315846 -396.821724) (xy 36.263477 -396.891071)
			(xy 36.204933 -396.955291) (xy 36.140713 -397.013835) (xy 36.071366 -397.066204) (xy 35.997482 -397.111951)
			(xy 35.919693 -397.150685) (xy 35.838661 -397.182077) (xy 35.755079 -397.205858) (xy 35.669659 -397.221826)
			(xy 35.58313 -397.229844) (xy 35.49623 -397.229844) (xy 35.409701 -397.221826) (xy 35.324281 -397.205858)
			(xy 35.240699 -397.182077) (xy 35.159667 -397.150685) (xy 35.081878 -397.111951) (xy 35.007994 -397.066204)
			(xy 34.938647 -397.013835) (xy 34.874427 -396.955291) (xy 34.815883 -396.891071) (xy 34.763514 -396.821724)
			(xy 34.717767 -396.74784) (xy 34.679033 -396.670051) (xy 34.647641 -396.589019) (xy 34.62386 -396.505437)
			(xy 34.607892 -396.420017) (xy 34.599874 -396.333488) (xy 31.399486 -396.333488) (xy 31.391468 -396.420017)
			(xy 31.3755 -396.505437) (xy 31.351719 -396.589019) (xy 31.320327 -396.670051) (xy 31.281593 -396.74784)
			(xy 31.235846 -396.821724) (xy 31.183477 -396.891071) (xy 31.124933 -396.955291) (xy 31.060713 -397.013835)
			(xy 30.991366 -397.066204) (xy 30.917482 -397.111951) (xy 30.839693 -397.150685) (xy 30.758661 -397.182077)
			(xy 30.675079 -397.205858) (xy 30.589659 -397.221826) (xy 30.50313 -397.229844) (xy 30.41623 -397.229844)
			(xy 30.329701 -397.221826) (xy 30.244281 -397.205858) (xy 30.160699 -397.182077) (xy 30.079667 -397.150685)
			(xy 30.001878 -397.111951) (xy 29.927994 -397.066204) (xy 29.858647 -397.013835) (xy 29.794427 -396.955291)
			(xy 29.735883 -396.891071) (xy 29.683514 -396.821724) (xy 29.637767 -396.74784) (xy 29.599033 -396.670051)
			(xy 29.567641 -396.589019) (xy 29.54386 -396.505437) (xy 29.527892 -396.420017) (xy 29.519874 -396.333488)
			(xy 29.254196 -396.333488) (xy 29.254196 -398.873488) (xy 29.519874 -398.873488) (xy 29.519874 -398.786588)
			(xy 29.527892 -398.700059) (xy 29.54386 -398.614639) (xy 29.567641 -398.531057) (xy 29.599033 -398.450025)
			(xy 29.637767 -398.372236) (xy 29.683514 -398.298352) (xy 29.735883 -398.229005) (xy 29.794427 -398.164785)
			(xy 29.858647 -398.106241) (xy 29.927994 -398.053872) (xy 30.001878 -398.008125) (xy 30.079667 -397.969391)
			(xy 30.160699 -397.937999) (xy 30.244281 -397.914218) (xy 30.329701 -397.89825) (xy 30.41623 -397.890232)
			(xy 30.50313 -397.890232) (xy 30.589659 -397.89825) (xy 30.675079 -397.914218) (xy 30.758661 -397.937999)
			(xy 30.839693 -397.969391) (xy 30.917482 -398.008125) (xy 30.991366 -398.053872) (xy 31.060713 -398.106241)
			(xy 31.124933 -398.164785) (xy 31.183477 -398.229005) (xy 31.235846 -398.298352) (xy 31.281593 -398.372236)
			(xy 31.320327 -398.450025) (xy 31.351719 -398.531057) (xy 31.3755 -398.614639) (xy 31.391468 -398.700059)
			(xy 31.399486 -398.786588) (xy 31.399988 -398.830038) (xy 31.399486 -398.873488) (xy 34.599874 -398.873488)
			(xy 34.599874 -398.786588) (xy 34.607892 -398.700059) (xy 34.62386 -398.614639) (xy 34.647641 -398.531057)
			(xy 34.679033 -398.450025) (xy 34.717767 -398.372236) (xy 34.763514 -398.298352) (xy 34.815883 -398.229005)
			(xy 34.874427 -398.164785) (xy 34.938647 -398.106241) (xy 35.007994 -398.053872) (xy 35.081878 -398.008125)
			(xy 35.159667 -397.969391) (xy 35.240699 -397.937999) (xy 35.324281 -397.914218) (xy 35.409701 -397.89825)
			(xy 35.49623 -397.890232) (xy 35.58313 -397.890232) (xy 35.669659 -397.89825) (xy 35.755079 -397.914218)
			(xy 35.838661 -397.937999) (xy 35.919693 -397.969391) (xy 35.997482 -398.008125) (xy 36.071366 -398.053872)
			(xy 36.140713 -398.106241) (xy 36.204933 -398.164785) (xy 36.263477 -398.229005) (xy 36.315846 -398.298352)
			(xy 36.361593 -398.372236) (xy 36.400327 -398.450025) (xy 36.431719 -398.531057) (xy 36.4555 -398.614639)
			(xy 36.471468 -398.700059) (xy 36.479486 -398.786588) (xy 36.479988 -398.830038) (xy 36.479486 -398.873488)
			(xy 36.471468 -398.960017) (xy 36.4555 -399.045437) (xy 36.431719 -399.129019) (xy 36.400327 -399.210051)
			(xy 36.361593 -399.28784) (xy 36.315846 -399.361724) (xy 36.263477 -399.431071) (xy 36.204933 -399.495291)
			(xy 36.140713 -399.553835) (xy 36.071366 -399.606204) (xy 35.997482 -399.651951) (xy 35.919693 -399.690685)
			(xy 35.838661 -399.722077) (xy 35.755079 -399.745858) (xy 35.669659 -399.761826) (xy 35.58313 -399.769844)
			(xy 35.49623 -399.769844) (xy 35.409701 -399.761826) (xy 35.324281 -399.745858) (xy 35.240699 -399.722077)
			(xy 35.159667 -399.690685) (xy 35.081878 -399.651951) (xy 35.007994 -399.606204) (xy 34.938647 -399.553835)
			(xy 34.874427 -399.495291) (xy 34.815883 -399.431071) (xy 34.763514 -399.361724) (xy 34.717767 -399.28784)
			(xy 34.679033 -399.210051) (xy 34.647641 -399.129019) (xy 34.62386 -399.045437) (xy 34.607892 -398.960017)
			(xy 34.599874 -398.873488) (xy 31.399486 -398.873488) (xy 31.391468 -398.960017) (xy 31.3755 -399.045437)
			(xy 31.351719 -399.129019) (xy 31.320327 -399.210051) (xy 31.281593 -399.28784) (xy 31.235846 -399.361724)
			(xy 31.183477 -399.431071) (xy 31.124933 -399.495291) (xy 31.060713 -399.553835) (xy 30.991366 -399.606204)
			(xy 30.917482 -399.651951) (xy 30.839693 -399.690685) (xy 30.758661 -399.722077) (xy 30.675079 -399.745858)
			(xy 30.589659 -399.761826) (xy 30.50313 -399.769844) (xy 30.41623 -399.769844) (xy 30.329701 -399.761826)
			(xy 30.244281 -399.745858) (xy 30.160699 -399.722077) (xy 30.079667 -399.690685) (xy 30.001878 -399.651951)
			(xy 29.927994 -399.606204) (xy 29.858647 -399.553835) (xy 29.794427 -399.495291) (xy 29.735883 -399.431071)
			(xy 29.683514 -399.361724) (xy 29.637767 -399.28784) (xy 29.599033 -399.210051) (xy 29.567641 -399.129019)
			(xy 29.54386 -399.045437) (xy 29.527892 -398.960017) (xy 29.519874 -398.873488) (xy 29.254196 -398.873488)
			(xy 29.254196 -401.413488) (xy 29.519874 -401.413488) (xy 29.519874 -401.326588) (xy 29.527892 -401.240059)
			(xy 29.54386 -401.154639) (xy 29.567641 -401.071057) (xy 29.599033 -400.990025) (xy 29.637767 -400.912236)
			(xy 29.683514 -400.838352) (xy 29.735883 -400.769005) (xy 29.794427 -400.704785) (xy 29.858647 -400.646241)
			(xy 29.927994 -400.593872) (xy 30.001878 -400.548125) (xy 30.079667 -400.509391) (xy 30.160699 -400.477999)
			(xy 30.244281 -400.454218) (xy 30.329701 -400.43825) (xy 30.41623 -400.430232) (xy 30.50313 -400.430232)
			(xy 30.589659 -400.43825) (xy 30.675079 -400.454218) (xy 30.758661 -400.477999) (xy 30.839693 -400.509391)
			(xy 30.917482 -400.548125) (xy 30.991366 -400.593872) (xy 31.060713 -400.646241) (xy 31.124933 -400.704785)
			(xy 31.183477 -400.769005) (xy 31.235846 -400.838352) (xy 31.281593 -400.912236) (xy 31.320327 -400.990025)
			(xy 31.351719 -401.071057) (xy 31.3755 -401.154639) (xy 31.391468 -401.240059) (xy 31.399486 -401.326588)
			(xy 31.399988 -401.370038) (xy 31.399486 -401.413488) (xy 34.599874 -401.413488) (xy 34.599874 -401.326588)
			(xy 34.607892 -401.240059) (xy 34.62386 -401.154639) (xy 34.647641 -401.071057) (xy 34.679033 -400.990025)
			(xy 34.717767 -400.912236) (xy 34.763514 -400.838352) (xy 34.815883 -400.769005) (xy 34.874427 -400.704785)
			(xy 34.938647 -400.646241) (xy 35.007994 -400.593872) (xy 35.081878 -400.548125) (xy 35.159667 -400.509391)
			(xy 35.240699 -400.477999) (xy 35.324281 -400.454218) (xy 35.409701 -400.43825) (xy 35.49623 -400.430232)
			(xy 35.58313 -400.430232) (xy 35.669659 -400.43825) (xy 35.755079 -400.454218) (xy 35.838661 -400.477999)
			(xy 35.919693 -400.509391) (xy 35.997482 -400.548125) (xy 36.071366 -400.593872) (xy 36.140713 -400.646241)
			(xy 36.204933 -400.704785) (xy 36.263477 -400.769005) (xy 36.315846 -400.838352) (xy 36.361593 -400.912236)
			(xy 36.400327 -400.990025) (xy 36.431719 -401.071057) (xy 36.4555 -401.154639) (xy 36.471468 -401.240059)
			(xy 36.479486 -401.326588) (xy 36.479988 -401.370038) (xy 36.479486 -401.413488) (xy 36.471468 -401.500017)
			(xy 36.4555 -401.585437) (xy 36.431719 -401.669019) (xy 36.400327 -401.750051) (xy 36.361593 -401.82784)
			(xy 36.315846 -401.901724) (xy 36.263477 -401.971071) (xy 36.204933 -402.035291) (xy 36.140713 -402.093835)
			(xy 36.071366 -402.146204) (xy 35.997482 -402.191951) (xy 35.919693 -402.230685) (xy 35.838661 -402.262077)
			(xy 35.755079 -402.285858) (xy 35.669659 -402.301826) (xy 35.58313 -402.309844) (xy 35.49623 -402.309844)
			(xy 35.409701 -402.301826) (xy 35.324281 -402.285858) (xy 35.240699 -402.262077) (xy 35.159667 -402.230685)
			(xy 35.081878 -402.191951) (xy 35.007994 -402.146204) (xy 34.938647 -402.093835) (xy 34.874427 -402.035291)
			(xy 34.815883 -401.971071) (xy 34.763514 -401.901724) (xy 34.717767 -401.82784) (xy 34.679033 -401.750051)
			(xy 34.647641 -401.669019) (xy 34.62386 -401.585437) (xy 34.607892 -401.500017) (xy 34.599874 -401.413488)
			(xy 31.399486 -401.413488) (xy 31.391468 -401.500017) (xy 31.3755 -401.585437) (xy 31.351719 -401.669019)
			(xy 31.320327 -401.750051) (xy 31.281593 -401.82784) (xy 31.235846 -401.901724) (xy 31.183477 -401.971071)
			(xy 31.124933 -402.035291) (xy 31.060713 -402.093835) (xy 30.991366 -402.146204) (xy 30.917482 -402.191951)
			(xy 30.839693 -402.230685) (xy 30.758661 -402.262077) (xy 30.675079 -402.285858) (xy 30.589659 -402.301826)
			(xy 30.50313 -402.309844) (xy 30.41623 -402.309844) (xy 30.329701 -402.301826) (xy 30.244281 -402.285858)
			(xy 30.160699 -402.262077) (xy 30.079667 -402.230685) (xy 30.001878 -402.191951) (xy 29.927994 -402.146204)
			(xy 29.858647 -402.093835) (xy 29.794427 -402.035291) (xy 29.735883 -401.971071) (xy 29.683514 -401.901724)
			(xy 29.637767 -401.82784) (xy 29.599033 -401.750051) (xy 29.567641 -401.669019) (xy 29.54386 -401.585437)
			(xy 29.527892 -401.500017) (xy 29.519874 -401.413488) (xy 29.254196 -401.413488) (xy 29.254196 -403.953488)
			(xy 29.519874 -403.953488) (xy 29.519874 -403.866588) (xy 29.527892 -403.780059) (xy 29.54386 -403.694639)
			(xy 29.567641 -403.611057) (xy 29.599033 -403.530025) (xy 29.637767 -403.452236) (xy 29.683514 -403.378352)
			(xy 29.735883 -403.309005) (xy 29.794427 -403.244785) (xy 29.858647 -403.186241) (xy 29.927994 -403.133872)
			(xy 30.001878 -403.088125) (xy 30.079667 -403.049391) (xy 30.160699 -403.017999) (xy 30.244281 -402.994218)
			(xy 30.329701 -402.97825) (xy 30.41623 -402.970232) (xy 30.50313 -402.970232) (xy 30.589659 -402.97825)
			(xy 30.675079 -402.994218) (xy 30.758661 -403.017999) (xy 30.839693 -403.049391) (xy 30.917482 -403.088125)
			(xy 30.991366 -403.133872) (xy 31.060713 -403.186241) (xy 31.124933 -403.244785) (xy 31.183477 -403.309005)
			(xy 31.235846 -403.378352) (xy 31.281593 -403.452236) (xy 31.320327 -403.530025) (xy 31.351719 -403.611057)
			(xy 31.3755 -403.694639) (xy 31.391468 -403.780059) (xy 31.399486 -403.866588) (xy 31.399988 -403.910038)
			(xy 31.399486 -403.953488) (xy 34.599874 -403.953488) (xy 34.599874 -403.866588) (xy 34.607892 -403.780059)
			(xy 34.62386 -403.694639) (xy 34.647641 -403.611057) (xy 34.679033 -403.530025) (xy 34.717767 -403.452236)
			(xy 34.763514 -403.378352) (xy 34.815883 -403.309005) (xy 34.874427 -403.244785) (xy 34.938647 -403.186241)
			(xy 35.007994 -403.133872) (xy 35.081878 -403.088125) (xy 35.159667 -403.049391) (xy 35.240699 -403.017999)
			(xy 35.324281 -402.994218) (xy 35.409701 -402.97825) (xy 35.49623 -402.970232) (xy 35.58313 -402.970232)
			(xy 35.669659 -402.97825) (xy 35.755079 -402.994218) (xy 35.838661 -403.017999) (xy 35.919693 -403.049391)
			(xy 35.997482 -403.088125) (xy 36.071366 -403.133872) (xy 36.140713 -403.186241) (xy 36.204933 -403.244785)
			(xy 36.263477 -403.309005) (xy 36.315846 -403.378352) (xy 36.361593 -403.452236) (xy 36.400327 -403.530025)
			(xy 36.431719 -403.611057) (xy 36.4555 -403.694639) (xy 36.471468 -403.780059) (xy 36.479486 -403.866588)
			(xy 36.479988 -403.910038) (xy 36.479486 -403.953488) (xy 36.471468 -404.040017) (xy 36.4555 -404.125437)
			(xy 36.431719 -404.209019) (xy 36.400327 -404.290051) (xy 36.361593 -404.36784) (xy 36.315846 -404.441724)
			(xy 36.263477 -404.511071) (xy 36.204933 -404.575291) (xy 36.140713 -404.633835) (xy 36.071366 -404.686204)
			(xy 35.997482 -404.731951) (xy 35.919693 -404.770685) (xy 35.838661 -404.802077) (xy 35.755079 -404.825858)
			(xy 35.669659 -404.841826) (xy 35.58313 -404.849844) (xy 35.49623 -404.849844) (xy 35.409701 -404.841826)
			(xy 35.324281 -404.825858) (xy 35.240699 -404.802077) (xy 35.159667 -404.770685) (xy 35.081878 -404.731951)
			(xy 35.007994 -404.686204) (xy 34.938647 -404.633835) (xy 34.874427 -404.575291) (xy 34.815883 -404.511071)
			(xy 34.763514 -404.441724) (xy 34.717767 -404.36784) (xy 34.679033 -404.290051) (xy 34.647641 -404.209019)
			(xy 34.62386 -404.125437) (xy 34.607892 -404.040017) (xy 34.599874 -403.953488) (xy 31.399486 -403.953488)
			(xy 31.391468 -404.040017) (xy 31.3755 -404.125437) (xy 31.351719 -404.209019) (xy 31.320327 -404.290051)
			(xy 31.281593 -404.36784) (xy 31.235846 -404.441724) (xy 31.183477 -404.511071) (xy 31.124933 -404.575291)
			(xy 31.060713 -404.633835) (xy 30.991366 -404.686204) (xy 30.917482 -404.731951) (xy 30.839693 -404.770685)
			(xy 30.758661 -404.802077) (xy 30.675079 -404.825858) (xy 30.589659 -404.841826) (xy 30.50313 -404.849844)
			(xy 30.41623 -404.849844) (xy 30.329701 -404.841826) (xy 30.244281 -404.825858) (xy 30.160699 -404.802077)
			(xy 30.079667 -404.770685) (xy 30.001878 -404.731951) (xy 29.927994 -404.686204) (xy 29.858647 -404.633835)
			(xy 29.794427 -404.575291) (xy 29.735883 -404.511071) (xy 29.683514 -404.441724) (xy 29.637767 -404.36784)
			(xy 29.599033 -404.290051) (xy 29.567641 -404.209019) (xy 29.54386 -404.125437) (xy 29.527892 -404.040017)
			(xy 29.519874 -403.953488) (xy 29.254196 -403.953488) (xy 29.254196 -406.493488) (xy 29.519874 -406.493488)
			(xy 29.519874 -406.406588) (xy 29.527892 -406.320059) (xy 29.54386 -406.234639) (xy 29.567641 -406.151057)
			(xy 29.599033 -406.070025) (xy 29.637767 -405.992236) (xy 29.683514 -405.918352) (xy 29.735883 -405.849005)
			(xy 29.794427 -405.784785) (xy 29.858647 -405.726241) (xy 29.927994 -405.673872) (xy 30.001878 -405.628125)
			(xy 30.079667 -405.589391) (xy 30.160699 -405.557999) (xy 30.244281 -405.534218) (xy 30.329701 -405.51825)
			(xy 30.41623 -405.510232) (xy 30.50313 -405.510232) (xy 30.589659 -405.51825) (xy 30.675079 -405.534218)
			(xy 30.758661 -405.557999) (xy 30.839693 -405.589391) (xy 30.917482 -405.628125) (xy 30.991366 -405.673872)
			(xy 31.060713 -405.726241) (xy 31.124933 -405.784785) (xy 31.183477 -405.849005) (xy 31.235846 -405.918352)
			(xy 31.281593 -405.992236) (xy 31.320327 -406.070025) (xy 31.351719 -406.151057) (xy 31.3755 -406.234639)
			(xy 31.391468 -406.320059) (xy 31.399486 -406.406588) (xy 31.399988 -406.450038) (xy 31.399486 -406.493488)
			(xy 34.599874 -406.493488) (xy 34.599874 -406.406588) (xy 34.607892 -406.320059) (xy 34.62386 -406.234639)
			(xy 34.647641 -406.151057) (xy 34.679033 -406.070025) (xy 34.717767 -405.992236) (xy 34.763514 -405.918352)
			(xy 34.815883 -405.849005) (xy 34.874427 -405.784785) (xy 34.938647 -405.726241) (xy 35.007994 -405.673872)
			(xy 35.081878 -405.628125) (xy 35.159667 -405.589391) (xy 35.240699 -405.557999) (xy 35.324281 -405.534218)
			(xy 35.409701 -405.51825) (xy 35.49623 -405.510232) (xy 35.58313 -405.510232) (xy 35.669659 -405.51825)
			(xy 35.755079 -405.534218) (xy 35.838661 -405.557999) (xy 35.919693 -405.589391) (xy 35.997482 -405.628125)
			(xy 36.071366 -405.673872) (xy 36.140713 -405.726241) (xy 36.204933 -405.784785) (xy 36.263477 -405.849005)
			(xy 36.315846 -405.918352) (xy 36.361593 -405.992236) (xy 36.400327 -406.070025) (xy 36.431719 -406.151057)
			(xy 36.4555 -406.234639) (xy 36.471468 -406.320059) (xy 36.479486 -406.406588) (xy 36.479988 -406.450038)
			(xy 36.479486 -406.493488) (xy 36.471468 -406.580017) (xy 36.4555 -406.665437) (xy 36.431719 -406.749019)
			(xy 36.400327 -406.830051) (xy 36.361593 -406.90784) (xy 36.329254 -406.96007) (xy 39.818564 -406.96007)
			(xy 39.819058 -406.902661) (xy 39.826902 -406.788113) (xy 39.842544 -406.674366) (xy 39.865911 -406.561952)
			(xy 39.896896 -406.451394) (xy 39.935352 -406.343209) (xy 39.981101 -406.2379) (xy 40.03393 -406.135958)
			(xy 40.093592 -406.037859) (xy 40.159809 -405.94406) (xy 40.232272 -405.854998) (xy 40.310645 -405.771089)
			(xy 40.39456 -405.692723) (xy 40.483627 -405.620266) (xy 40.577431 -405.554056) (xy 40.675535 -405.494402)
			(xy 40.777481 -405.441581) (xy 40.882793 -405.395839) (xy 40.990981 -405.357391) (xy 41.101541 -405.326415)
			(xy 41.213957 -405.303056) (xy 41.327705 -405.287423) (xy 41.442254 -405.279588) (xy 41.557072 -405.279588)
			(xy 41.671621 -405.287423) (xy 41.785369 -405.303056) (xy 41.897785 -405.326415) (xy 42.008345 -405.357391)
			(xy 42.116533 -405.395839) (xy 42.221845 -405.441581) (xy 42.323791 -405.494402) (xy 42.421895 -405.554056)
			(xy 42.501239 -405.61006) (xy 43.327577 -405.61006) (xy 43.331612 -405.534356) (xy 43.343671 -405.459511)
			(xy 43.363617 -405.38637) (xy 43.391224 -405.315765) (xy 43.42618 -405.248494) (xy 43.468088 -405.185319)
			(xy 43.516474 -405.126957) (xy 43.57079 -405.074069) (xy 43.630419 -405.027254) (xy 43.694687 -404.987042)
			(xy 43.762864 -404.95389) (xy 43.83418 -404.928172) (xy 43.907825 -404.91018) (xy 43.982965 -404.900118)
			(xy 44.058749 -404.898099) (xy 44.134319 -404.904148) (xy 44.208817 -404.918195) (xy 44.2814 -404.940081)
			(xy 44.351246 -404.969558) (xy 44.417563 -405.006293) (xy 44.479599 -405.049868) (xy 44.536652 -405.09979)
			(xy 44.588076 -405.155494) (xy 44.633287 -405.216349) (xy 44.671774 -405.281664) (xy 44.7031 -405.3507)
			(xy 44.72691 -405.422675) (xy 44.742935 -405.496773) (xy 44.750994 -405.572154) (xy 44.751498 -405.61006)
			(xy 45.867577 -405.61006) (xy 45.871612 -405.534356) (xy 45.883671 -405.459511) (xy 45.903617 -405.38637)
			(xy 45.931224 -405.315765) (xy 45.96618 -405.248494) (xy 46.008088 -405.185319) (xy 46.056474 -405.126957)
			(xy 46.11079 -405.074069) (xy 46.170419 -405.027254) (xy 46.234687 -404.987042) (xy 46.302864 -404.95389)
			(xy 46.37418 -404.928172) (xy 46.447825 -404.91018) (xy 46.522965 -404.900118) (xy 46.598749 -404.898099)
			(xy 46.674319 -404.904148) (xy 46.748817 -404.918195) (xy 46.8214 -404.940081) (xy 46.891246 -404.969558)
			(xy 46.957563 -405.006293) (xy 47.019599 -405.049868) (xy 47.076652 -405.09979) (xy 47.128076 -405.155494)
			(xy 47.173287 -405.216349) (xy 47.211774 -405.281664) (xy 47.2431 -405.3507) (xy 47.26691 -405.422675)
			(xy 47.282935 -405.496773) (xy 47.290994 -405.572154) (xy 47.291498 -405.61006) (xy 48.407577 -405.61006)
			(xy 48.411612 -405.534356) (xy 48.423671 -405.459511) (xy 48.443617 -405.38637) (xy 48.471224 -405.315765)
			(xy 48.50618 -405.248494) (xy 48.548088 -405.185319) (xy 48.596474 -405.126957) (xy 48.65079 -405.074069)
			(xy 48.710419 -405.027254) (xy 48.774687 -404.987042) (xy 48.842864 -404.95389) (xy 48.91418 -404.928172)
			(xy 48.987825 -404.91018) (xy 49.062965 -404.900118) (xy 49.138749 -404.898099) (xy 49.214319 -404.904148)
			(xy 49.288817 -404.918195) (xy 49.3614 -404.940081) (xy 49.431246 -404.969558) (xy 49.497563 -405.006293)
			(xy 49.559599 -405.049868) (xy 49.616652 -405.09979) (xy 49.668076 -405.155494) (xy 49.713287 -405.216349)
			(xy 49.751774 -405.281664) (xy 49.7831 -405.3507) (xy 49.80691 -405.422675) (xy 49.822935 -405.496773)
			(xy 49.830994 -405.572154) (xy 49.831498 -405.61006) (xy 50.947577 -405.61006) (xy 50.951612 -405.534356)
			(xy 50.963671 -405.459511) (xy 50.983617 -405.38637) (xy 51.011224 -405.315765) (xy 51.04618 -405.248494)
			(xy 51.088088 -405.185319) (xy 51.136474 -405.126957) (xy 51.19079 -405.074069) (xy 51.250419 -405.027254)
			(xy 51.314687 -404.987042) (xy 51.382864 -404.95389) (xy 51.45418 -404.928172) (xy 51.527825 -404.91018)
			(xy 51.602965 -404.900118) (xy 51.678749 -404.898099) (xy 51.754319 -404.904148) (xy 51.828817 -404.918195)
			(xy 51.9014 -404.940081) (xy 51.971246 -404.969558) (xy 52.037563 -405.006293) (xy 52.099599 -405.049868)
			(xy 52.156652 -405.09979) (xy 52.208076 -405.155494) (xy 52.253287 -405.216349) (xy 52.291774 -405.281664)
			(xy 52.3231 -405.3507) (xy 52.34691 -405.422675) (xy 52.362935 -405.496773) (xy 52.370994 -405.572154)
			(xy 52.371498 -405.61006) (xy 53.487577 -405.61006) (xy 53.491612 -405.534356) (xy 53.503671 -405.459511)
			(xy 53.523617 -405.38637) (xy 53.551224 -405.315765) (xy 53.58618 -405.248494) (xy 53.628088 -405.185319)
			(xy 53.676474 -405.126957) (xy 53.73079 -405.074069) (xy 53.790419 -405.027254) (xy 53.854687 -404.987042)
			(xy 53.922864 -404.95389) (xy 53.99418 -404.928172) (xy 54.067825 -404.91018) (xy 54.142965 -404.900118)
			(xy 54.218749 -404.898099) (xy 54.294319 -404.904148) (xy 54.368817 -404.918195) (xy 54.4414 -404.940081)
			(xy 54.511246 -404.969558) (xy 54.577563 -405.006293) (xy 54.639599 -405.049868) (xy 54.696652 -405.09979)
			(xy 54.748076 -405.155494) (xy 54.793287 -405.216349) (xy 54.831774 -405.281664) (xy 54.8631 -405.3507)
			(xy 54.88691 -405.422675) (xy 54.902935 -405.496773) (xy 54.910994 -405.572154) (xy 54.911498 -405.61006)
			(xy 56.027577 -405.61006) (xy 56.031612 -405.534356) (xy 56.043671 -405.459511) (xy 56.063617 -405.38637)
			(xy 56.091224 -405.315765) (xy 56.12618 -405.248494) (xy 56.168088 -405.185319) (xy 56.216474 -405.126957)
			(xy 56.27079 -405.074069) (xy 56.330419 -405.027254) (xy 56.394687 -404.987042) (xy 56.462864 -404.95389)
			(xy 56.53418 -404.928172) (xy 56.607825 -404.91018) (xy 56.682965 -404.900118) (xy 56.758749 -404.898099)
			(xy 56.834319 -404.904148) (xy 56.908817 -404.918195) (xy 56.9814 -404.940081) (xy 57.051246 -404.969558)
			(xy 57.117563 -405.006293) (xy 57.179599 -405.049868) (xy 57.236652 -405.09979) (xy 57.288076 -405.155494)
			(xy 57.333287 -405.216349) (xy 57.371774 -405.281664) (xy 57.4031 -405.3507) (xy 57.42691 -405.422675)
			(xy 57.442935 -405.496773) (xy 57.450994 -405.572154) (xy 57.451498 -405.61006) (xy 58.567577 -405.61006)
			(xy 58.571612 -405.534356) (xy 58.583671 -405.459511) (xy 58.603617 -405.38637) (xy 58.631224 -405.315765)
			(xy 58.66618 -405.248494) (xy 58.708088 -405.185319) (xy 58.756474 -405.126957) (xy 58.81079 -405.074069)
			(xy 58.870419 -405.027254) (xy 58.934687 -404.987042) (xy 59.002864 -404.95389) (xy 59.07418 -404.928172)
			(xy 59.147825 -404.91018) (xy 59.222965 -404.900118) (xy 59.298749 -404.898099) (xy 59.374319 -404.904148)
			(xy 59.448817 -404.918195) (xy 59.5214 -404.940081) (xy 59.591246 -404.969558) (xy 59.657563 -405.006293)
			(xy 59.719599 -405.049868) (xy 59.776652 -405.09979) (xy 59.828076 -405.155494) (xy 59.873287 -405.216349)
			(xy 59.911774 -405.281664) (xy 59.9431 -405.3507) (xy 59.96691 -405.422675) (xy 59.982935 -405.496773)
			(xy 59.990994 -405.572154) (xy 59.991498 -405.61006) (xy 61.107577 -405.61006) (xy 61.111612 -405.534356)
			(xy 61.123671 -405.459511) (xy 61.143617 -405.38637) (xy 61.171224 -405.315765) (xy 61.20618 -405.248494)
			(xy 61.248088 -405.185319) (xy 61.296474 -405.126957) (xy 61.35079 -405.074069) (xy 61.410419 -405.027254)
			(xy 61.474687 -404.987042) (xy 61.542864 -404.95389) (xy 61.61418 -404.928172) (xy 61.687825 -404.91018)
			(xy 61.762965 -404.900118) (xy 61.838749 -404.898099) (xy 61.914319 -404.904148) (xy 61.988817 -404.918195)
			(xy 62.0614 -404.940081) (xy 62.131246 -404.969558) (xy 62.197563 -405.006293) (xy 62.259599 -405.049868)
			(xy 62.316652 -405.09979) (xy 62.368076 -405.155494) (xy 62.413287 -405.216349) (xy 62.451774 -405.281664)
			(xy 62.4831 -405.3507) (xy 62.50691 -405.422675) (xy 62.522935 -405.496773) (xy 62.530994 -405.572154)
			(xy 62.531498 -405.61006) (xy 62.530994 -405.647966) (xy 62.522935 -405.723347) (xy 62.50691 -405.797445)
			(xy 62.4831 -405.86942) (xy 62.451774 -405.938456) (xy 62.413287 -406.003771) (xy 62.368076 -406.064626)
			(xy 62.316652 -406.12033) (xy 62.259599 -406.170252) (xy 62.197563 -406.213827) (xy 62.131246 -406.250562)
			(xy 62.0614 -406.280039) (xy 61.988817 -406.301925) (xy 61.914319 -406.315972) (xy 61.838749 -406.322021)
			(xy 61.762965 -406.320002) (xy 61.687825 -406.30994) (xy 61.61418 -406.291948) (xy 61.542864 -406.26623)
			(xy 61.474687 -406.233078) (xy 61.410419 -406.192866) (xy 61.35079 -406.146051) (xy 61.296474 -406.093163)
			(xy 61.248088 -406.034801) (xy 61.20618 -405.971626) (xy 61.171224 -405.904355) (xy 61.143617 -405.83375)
			(xy 61.123671 -405.760609) (xy 61.111612 -405.685764) (xy 61.107577 -405.61006) (xy 59.991498 -405.61006)
			(xy 59.990994 -405.647966) (xy 59.982935 -405.723347) (xy 59.96691 -405.797445) (xy 59.9431 -405.86942)
			(xy 59.911774 -405.938456) (xy 59.873287 -406.003771) (xy 59.828076 -406.064626) (xy 59.776652 -406.12033)
			(xy 59.719599 -406.170252) (xy 59.657563 -406.213827) (xy 59.591246 -406.250562) (xy 59.5214 -406.280039)
			(xy 59.448817 -406.301925) (xy 59.374319 -406.315972) (xy 59.298749 -406.322021) (xy 59.222965 -406.320002)
			(xy 59.147825 -406.30994) (xy 59.07418 -406.291948) (xy 59.002864 -406.26623) (xy 58.934687 -406.233078)
			(xy 58.870419 -406.192866) (xy 58.81079 -406.146051) (xy 58.756474 -406.093163) (xy 58.708088 -406.034801)
			(xy 58.66618 -405.971626) (xy 58.631224 -405.904355) (xy 58.603617 -405.83375) (xy 58.583671 -405.760609)
			(xy 58.571612 -405.685764) (xy 58.567577 -405.61006) (xy 57.451498 -405.61006) (xy 57.450994 -405.647966)
			(xy 57.442935 -405.723347) (xy 57.42691 -405.797445) (xy 57.4031 -405.86942) (xy 57.371774 -405.938456)
			(xy 57.333287 -406.003771) (xy 57.288076 -406.064626) (xy 57.236652 -406.12033) (xy 57.179599 -406.170252)
			(xy 57.117563 -406.213827) (xy 57.051246 -406.250562) (xy 56.9814 -406.280039) (xy 56.908817 -406.301925)
			(xy 56.834319 -406.315972) (xy 56.758749 -406.322021) (xy 56.682965 -406.320002) (xy 56.607825 -406.30994)
			(xy 56.53418 -406.291948) (xy 56.462864 -406.26623) (xy 56.394687 -406.233078) (xy 56.330419 -406.192866)
			(xy 56.27079 -406.146051) (xy 56.216474 -406.093163) (xy 56.168088 -406.034801) (xy 56.12618 -405.971626)
			(xy 56.091224 -405.904355) (xy 56.063617 -405.83375) (xy 56.043671 -405.760609) (xy 56.031612 -405.685764)
			(xy 56.027577 -405.61006) (xy 54.911498 -405.61006) (xy 54.910994 -405.647966) (xy 54.902935 -405.723347)
			(xy 54.88691 -405.797445) (xy 54.8631 -405.86942) (xy 54.831774 -405.938456) (xy 54.793287 -406.003771)
			(xy 54.748076 -406.064626) (xy 54.696652 -406.12033) (xy 54.639599 -406.170252) (xy 54.577563 -406.213827)
			(xy 54.511246 -406.250562) (xy 54.4414 -406.280039) (xy 54.368817 -406.301925) (xy 54.294319 -406.315972)
			(xy 54.218749 -406.322021) (xy 54.142965 -406.320002) (xy 54.067825 -406.30994) (xy 53.99418 -406.291948)
			(xy 53.922864 -406.26623) (xy 53.854687 -406.233078) (xy 53.790419 -406.192866) (xy 53.73079 -406.146051)
			(xy 53.676474 -406.093163) (xy 53.628088 -406.034801) (xy 53.58618 -405.971626) (xy 53.551224 -405.904355)
			(xy 53.523617 -405.83375) (xy 53.503671 -405.760609) (xy 53.491612 -405.685764) (xy 53.487577 -405.61006)
			(xy 52.371498 -405.61006) (xy 52.370994 -405.647966) (xy 52.362935 -405.723347) (xy 52.34691 -405.797445)
			(xy 52.3231 -405.86942) (xy 52.291774 -405.938456) (xy 52.253287 -406.003771) (xy 52.208076 -406.064626)
			(xy 52.156652 -406.12033) (xy 52.099599 -406.170252) (xy 52.037563 -406.213827) (xy 51.971246 -406.250562)
			(xy 51.9014 -406.280039) (xy 51.828817 -406.301925) (xy 51.754319 -406.315972) (xy 51.678749 -406.322021)
			(xy 51.602965 -406.320002) (xy 51.527825 -406.30994) (xy 51.45418 -406.291948) (xy 51.382864 -406.26623)
			(xy 51.314687 -406.233078) (xy 51.250419 -406.192866) (xy 51.19079 -406.146051) (xy 51.136474 -406.093163)
			(xy 51.088088 -406.034801) (xy 51.04618 -405.971626) (xy 51.011224 -405.904355) (xy 50.983617 -405.83375)
			(xy 50.963671 -405.760609) (xy 50.951612 -405.685764) (xy 50.947577 -405.61006) (xy 49.831498 -405.61006)
			(xy 49.830994 -405.647966) (xy 49.822935 -405.723347) (xy 49.80691 -405.797445) (xy 49.7831 -405.86942)
			(xy 49.751774 -405.938456) (xy 49.713287 -406.003771) (xy 49.668076 -406.064626) (xy 49.616652 -406.12033)
			(xy 49.559599 -406.170252) (xy 49.497563 -406.213827) (xy 49.431246 -406.250562) (xy 49.3614 -406.280039)
			(xy 49.288817 -406.301925) (xy 49.214319 -406.315972) (xy 49.138749 -406.322021) (xy 49.062965 -406.320002)
			(xy 48.987825 -406.30994) (xy 48.91418 -406.291948) (xy 48.842864 -406.26623) (xy 48.774687 -406.233078)
			(xy 48.710419 -406.192866) (xy 48.65079 -406.146051) (xy 48.596474 -406.093163) (xy 48.548088 -406.034801)
			(xy 48.50618 -405.971626) (xy 48.471224 -405.904355) (xy 48.443617 -405.83375) (xy 48.423671 -405.760609)
			(xy 48.411612 -405.685764) (xy 48.407577 -405.61006) (xy 47.291498 -405.61006) (xy 47.290994 -405.647966)
			(xy 47.282935 -405.723347) (xy 47.26691 -405.797445) (xy 47.2431 -405.86942) (xy 47.211774 -405.938456)
			(xy 47.173287 -406.003771) (xy 47.128076 -406.064626) (xy 47.076652 -406.12033) (xy 47.019599 -406.170252)
			(xy 46.957563 -406.213827) (xy 46.891246 -406.250562) (xy 46.8214 -406.280039) (xy 46.748817 -406.301925)
			(xy 46.674319 -406.315972) (xy 46.598749 -406.322021) (xy 46.522965 -406.320002) (xy 46.447825 -406.30994)
			(xy 46.37418 -406.291948) (xy 46.302864 -406.26623) (xy 46.234687 -406.233078) (xy 46.170419 -406.192866)
			(xy 46.11079 -406.146051) (xy 46.056474 -406.093163) (xy 46.008088 -406.034801) (xy 45.96618 -405.971626)
			(xy 45.931224 -405.904355) (xy 45.903617 -405.83375) (xy 45.883671 -405.760609) (xy 45.871612 -405.685764)
			(xy 45.867577 -405.61006) (xy 44.751498 -405.61006) (xy 44.750994 -405.647966) (xy 44.742935 -405.723347)
			(xy 44.72691 -405.797445) (xy 44.7031 -405.86942) (xy 44.671774 -405.938456) (xy 44.633287 -406.003771)
			(xy 44.588076 -406.064626) (xy 44.536652 -406.12033) (xy 44.479599 -406.170252) (xy 44.417563 -406.213827)
			(xy 44.351246 -406.250562) (xy 44.2814 -406.280039) (xy 44.208817 -406.301925) (xy 44.134319 -406.315972)
			(xy 44.058749 -406.322021) (xy 43.982965 -406.320002) (xy 43.907825 -406.30994) (xy 43.83418 -406.291948)
			(xy 43.762864 -406.26623) (xy 43.694687 -406.233078) (xy 43.630419 -406.192866) (xy 43.57079 -406.146051)
			(xy 43.516474 -406.093163) (xy 43.468088 -406.034801) (xy 43.42618 -405.971626) (xy 43.391224 -405.904355)
			(xy 43.363617 -405.83375) (xy 43.343671 -405.760609) (xy 43.331612 -405.685764) (xy 43.327577 -405.61006)
			(xy 42.501239 -405.61006) (xy 42.515699 -405.620266) (xy 42.604766 -405.692723) (xy 42.688681 -405.771089)
			(xy 42.767054 -405.854998) (xy 42.839517 -405.94406) (xy 42.905734 -406.037859) (xy 42.965396 -406.135958)
			(xy 43.018225 -406.2379) (xy 43.063974 -406.343209) (xy 43.10243 -406.451394) (xy 43.133415 -406.561952)
			(xy 43.156782 -406.674366) (xy 43.172424 -406.788113) (xy 43.180268 -406.902661) (xy 43.180762 -406.96007)
			(xy 43.180576 -406.993253) (xy 43.177909 -407.059567) (xy 43.175428 -407.092658) (xy 43.170272 -407.150942)
			(xy 43.152948 -407.266671) (xy 43.127616 -407.380914) (xy 43.094401 -407.493119) (xy 43.053462 -407.602742)
			(xy 43.004999 -407.709253) (xy 42.949245 -407.812135) (xy 42.886471 -407.910891) (xy 42.816981 -408.005042)
			(xy 42.741111 -408.094132) (xy 42.659229 -408.177729) (xy 42.571732 -408.25543) (xy 42.500813 -408.31008)
			(xy 43.327577 -408.31008) (xy 43.331612 -408.234376) (xy 43.343671 -408.159531) (xy 43.363617 -408.08639)
			(xy 43.391224 -408.015785) (xy 43.42618 -407.948514) (xy 43.468088 -407.885339) (xy 43.516474 -407.826977)
			(xy 43.57079 -407.774089) (xy 43.630419 -407.727274) (xy 43.694687 -407.687062) (xy 43.762864 -407.65391)
			(xy 43.83418 -407.628192) (xy 43.907825 -407.6102) (xy 43.982965 -407.600138) (xy 44.058749 -407.598119)
			(xy 44.134319 -407.604168) (xy 44.208817 -407.618215) (xy 44.2814 -407.640101) (xy 44.351246 -407.669578)
			(xy 44.417563 -407.706313) (xy 44.479599 -407.749888) (xy 44.536652 -407.79981) (xy 44.588076 -407.855514)
			(xy 44.633287 -407.916369) (xy 44.671774 -407.981684) (xy 44.7031 -408.05072) (xy 44.72691 -408.122695)
			(xy 44.742935 -408.196793) (xy 44.750994 -408.272174) (xy 44.751498 -408.31008) (xy 45.867577 -408.31008)
			(xy 45.871612 -408.234376) (xy 45.883671 -408.159531) (xy 45.903617 -408.08639) (xy 45.931224 -408.015785)
			(xy 45.96618 -407.948514) (xy 46.008088 -407.885339) (xy 46.056474 -407.826977) (xy 46.11079 -407.774089)
			(xy 46.170419 -407.727274) (xy 46.234687 -407.687062) (xy 46.302864 -407.65391) (xy 46.37418 -407.628192)
			(xy 46.447825 -407.6102) (xy 46.522965 -407.600138) (xy 46.598749 -407.598119) (xy 46.674319 -407.604168)
			(xy 46.748817 -407.618215) (xy 46.8214 -407.640101) (xy 46.891246 -407.669578) (xy 46.957563 -407.706313)
			(xy 47.019599 -407.749888) (xy 47.076652 -407.79981) (xy 47.128076 -407.855514) (xy 47.173287 -407.916369)
			(xy 47.211774 -407.981684) (xy 47.2431 -408.05072) (xy 47.26691 -408.122695) (xy 47.282935 -408.196793)
			(xy 47.290994 -408.272174) (xy 47.291498 -408.31008) (xy 48.407577 -408.31008) (xy 48.411612 -408.234376)
			(xy 48.423671 -408.159531) (xy 48.443617 -408.08639) (xy 48.471224 -408.015785) (xy 48.50618 -407.948514)
			(xy 48.548088 -407.885339) (xy 48.596474 -407.826977) (xy 48.65079 -407.774089) (xy 48.710419 -407.727274)
			(xy 48.774687 -407.687062) (xy 48.842864 -407.65391) (xy 48.91418 -407.628192) (xy 48.987825 -407.6102)
			(xy 49.062965 -407.600138) (xy 49.138749 -407.598119) (xy 49.214319 -407.604168) (xy 49.288817 -407.618215)
			(xy 49.3614 -407.640101) (xy 49.431246 -407.669578) (xy 49.497563 -407.706313) (xy 49.559599 -407.749888)
			(xy 49.616652 -407.79981) (xy 49.668076 -407.855514) (xy 49.713287 -407.916369) (xy 49.751774 -407.981684)
			(xy 49.7831 -408.05072) (xy 49.80691 -408.122695) (xy 49.822935 -408.196793) (xy 49.830994 -408.272174)
			(xy 49.831498 -408.31008) (xy 50.947577 -408.31008) (xy 50.951612 -408.234376) (xy 50.963671 -408.159531)
			(xy 50.983617 -408.08639) (xy 51.011224 -408.015785) (xy 51.04618 -407.948514) (xy 51.088088 -407.885339)
			(xy 51.136474 -407.826977) (xy 51.19079 -407.774089) (xy 51.250419 -407.727274) (xy 51.314687 -407.687062)
			(xy 51.382864 -407.65391) (xy 51.45418 -407.628192) (xy 51.527825 -407.6102) (xy 51.602965 -407.600138)
			(xy 51.678749 -407.598119) (xy 51.754319 -407.604168) (xy 51.828817 -407.618215) (xy 51.9014 -407.640101)
			(xy 51.971246 -407.669578) (xy 52.037563 -407.706313) (xy 52.099599 -407.749888) (xy 52.156652 -407.79981)
			(xy 52.208076 -407.855514) (xy 52.253287 -407.916369) (xy 52.291774 -407.981684) (xy 52.3231 -408.05072)
			(xy 52.34691 -408.122695) (xy 52.362935 -408.196793) (xy 52.370994 -408.272174) (xy 52.371498 -408.31008)
			(xy 53.487577 -408.31008) (xy 53.491612 -408.234376) (xy 53.503671 -408.159531) (xy 53.523617 -408.08639)
			(xy 53.551224 -408.015785) (xy 53.58618 -407.948514) (xy 53.628088 -407.885339) (xy 53.676474 -407.826977)
			(xy 53.73079 -407.774089) (xy 53.790419 -407.727274) (xy 53.854687 -407.687062) (xy 53.922864 -407.65391)
			(xy 53.99418 -407.628192) (xy 54.067825 -407.6102) (xy 54.142965 -407.600138) (xy 54.218749 -407.598119)
			(xy 54.294319 -407.604168) (xy 54.368817 -407.618215) (xy 54.4414 -407.640101) (xy 54.511246 -407.669578)
			(xy 54.577563 -407.706313) (xy 54.639599 -407.749888) (xy 54.696652 -407.79981) (xy 54.748076 -407.855514)
			(xy 54.793287 -407.916369) (xy 54.831774 -407.981684) (xy 54.8631 -408.05072) (xy 54.88691 -408.122695)
			(xy 54.902935 -408.196793) (xy 54.910994 -408.272174) (xy 54.911498 -408.31008) (xy 56.027577 -408.31008)
			(xy 56.031612 -408.234376) (xy 56.043671 -408.159531) (xy 56.063617 -408.08639) (xy 56.091224 -408.015785)
			(xy 56.12618 -407.948514) (xy 56.168088 -407.885339) (xy 56.216474 -407.826977) (xy 56.27079 -407.774089)
			(xy 56.330419 -407.727274) (xy 56.394687 -407.687062) (xy 56.462864 -407.65391) (xy 56.53418 -407.628192)
			(xy 56.607825 -407.6102) (xy 56.682965 -407.600138) (xy 56.758749 -407.598119) (xy 56.834319 -407.604168)
			(xy 56.908817 -407.618215) (xy 56.9814 -407.640101) (xy 57.051246 -407.669578) (xy 57.117563 -407.706313)
			(xy 57.179599 -407.749888) (xy 57.236652 -407.79981) (xy 57.288076 -407.855514) (xy 57.333287 -407.916369)
			(xy 57.371774 -407.981684) (xy 57.4031 -408.05072) (xy 57.42691 -408.122695) (xy 57.442935 -408.196793)
			(xy 57.450994 -408.272174) (xy 57.451498 -408.31008) (xy 58.567577 -408.31008) (xy 58.571612 -408.234376)
			(xy 58.583671 -408.159531) (xy 58.603617 -408.08639) (xy 58.631224 -408.015785) (xy 58.66618 -407.948514)
			(xy 58.708088 -407.885339) (xy 58.756474 -407.826977) (xy 58.81079 -407.774089) (xy 58.870419 -407.727274)
			(xy 58.934687 -407.687062) (xy 59.002864 -407.65391) (xy 59.07418 -407.628192) (xy 59.147825 -407.6102)
			(xy 59.222965 -407.600138) (xy 59.298749 -407.598119) (xy 59.374319 -407.604168) (xy 59.448817 -407.618215)
			(xy 59.5214 -407.640101) (xy 59.591246 -407.669578) (xy 59.657563 -407.706313) (xy 59.719599 -407.749888)
			(xy 59.776652 -407.79981) (xy 59.828076 -407.855514) (xy 59.873287 -407.916369) (xy 59.911774 -407.981684)
			(xy 59.9431 -408.05072) (xy 59.96691 -408.122695) (xy 59.982935 -408.196793) (xy 59.990994 -408.272174)
			(xy 59.991498 -408.31008) (xy 61.107577 -408.31008) (xy 61.111612 -408.234376) (xy 61.123671 -408.159531)
			(xy 61.143617 -408.08639) (xy 61.171224 -408.015785) (xy 61.20618 -407.948514) (xy 61.248088 -407.885339)
			(xy 61.296474 -407.826977) (xy 61.35079 -407.774089) (xy 61.410419 -407.727274) (xy 61.474687 -407.687062)
			(xy 61.542864 -407.65391) (xy 61.61418 -407.628192) (xy 61.687825 -407.6102) (xy 61.762965 -407.600138)
			(xy 61.838749 -407.598119) (xy 61.914319 -407.604168) (xy 61.988817 -407.618215) (xy 62.0614 -407.640101)
			(xy 62.131246 -407.669578) (xy 62.197563 -407.706313) (xy 62.259599 -407.749888) (xy 62.316652 -407.79981)
			(xy 62.368076 -407.855514) (xy 62.413287 -407.916369) (xy 62.451774 -407.981684) (xy 62.4831 -408.05072)
			(xy 62.50691 -408.122695) (xy 62.522935 -408.196793) (xy 62.530994 -408.272174) (xy 62.531498 -408.31008)
			(xy 62.530994 -408.347986) (xy 62.522935 -408.423367) (xy 62.50691 -408.497465) (xy 62.4831 -408.56944)
			(xy 62.451774 -408.638476) (xy 62.413287 -408.703791) (xy 62.368076 -408.764646) (xy 62.316652 -408.82035)
			(xy 62.259599 -408.870272) (xy 62.197563 -408.913847) (xy 62.131246 -408.950582) (xy 62.0614 -408.980059)
			(xy 61.988817 -409.001945) (xy 61.914319 -409.015992) (xy 61.838749 -409.022041) (xy 61.762965 -409.020022)
			(xy 61.687825 -409.00996) (xy 61.61418 -408.991968) (xy 61.542864 -408.96625) (xy 61.474687 -408.933098)
			(xy 61.410419 -408.892886) (xy 61.35079 -408.846071) (xy 61.296474 -408.793183) (xy 61.248088 -408.734821)
			(xy 61.20618 -408.671646) (xy 61.171224 -408.604375) (xy 61.143617 -408.53377) (xy 61.123671 -408.460629)
			(xy 61.111612 -408.385784) (xy 61.107577 -408.31008) (xy 59.991498 -408.31008) (xy 59.990994 -408.347986)
			(xy 59.982935 -408.423367) (xy 59.96691 -408.497465) (xy 59.9431 -408.56944) (xy 59.911774 -408.638476)
			(xy 59.873287 -408.703791) (xy 59.828076 -408.764646) (xy 59.776652 -408.82035) (xy 59.719599 -408.870272)
			(xy 59.657563 -408.913847) (xy 59.591246 -408.950582) (xy 59.5214 -408.980059) (xy 59.448817 -409.001945)
			(xy 59.374319 -409.015992) (xy 59.298749 -409.022041) (xy 59.222965 -409.020022) (xy 59.147825 -409.00996)
			(xy 59.07418 -408.991968) (xy 59.002864 -408.96625) (xy 58.934687 -408.933098) (xy 58.870419 -408.892886)
			(xy 58.81079 -408.846071) (xy 58.756474 -408.793183) (xy 58.708088 -408.734821) (xy 58.66618 -408.671646)
			(xy 58.631224 -408.604375) (xy 58.603617 -408.53377) (xy 58.583671 -408.460629) (xy 58.571612 -408.385784)
			(xy 58.567577 -408.31008) (xy 57.451498 -408.31008) (xy 57.450994 -408.347986) (xy 57.442935 -408.423367)
			(xy 57.42691 -408.497465) (xy 57.4031 -408.56944) (xy 57.371774 -408.638476) (xy 57.333287 -408.703791)
			(xy 57.288076 -408.764646) (xy 57.236652 -408.82035) (xy 57.179599 -408.870272) (xy 57.117563 -408.913847)
			(xy 57.051246 -408.950582) (xy 56.9814 -408.980059) (xy 56.908817 -409.001945) (xy 56.834319 -409.015992)
			(xy 56.758749 -409.022041) (xy 56.682965 -409.020022) (xy 56.607825 -409.00996) (xy 56.53418 -408.991968)
			(xy 56.462864 -408.96625) (xy 56.394687 -408.933098) (xy 56.330419 -408.892886) (xy 56.27079 -408.846071)
			(xy 56.216474 -408.793183) (xy 56.168088 -408.734821) (xy 56.12618 -408.671646) (xy 56.091224 -408.604375)
			(xy 56.063617 -408.53377) (xy 56.043671 -408.460629) (xy 56.031612 -408.385784) (xy 56.027577 -408.31008)
			(xy 54.911498 -408.31008) (xy 54.910994 -408.347986) (xy 54.902935 -408.423367) (xy 54.88691 -408.497465)
			(xy 54.8631 -408.56944) (xy 54.831774 -408.638476) (xy 54.793287 -408.703791) (xy 54.748076 -408.764646)
			(xy 54.696652 -408.82035) (xy 54.639599 -408.870272) (xy 54.577563 -408.913847) (xy 54.511246 -408.950582)
			(xy 54.4414 -408.980059) (xy 54.368817 -409.001945) (xy 54.294319 -409.015992) (xy 54.218749 -409.022041)
			(xy 54.142965 -409.020022) (xy 54.067825 -409.00996) (xy 53.99418 -408.991968) (xy 53.922864 -408.96625)
			(xy 53.854687 -408.933098) (xy 53.790419 -408.892886) (xy 53.73079 -408.846071) (xy 53.676474 -408.793183)
			(xy 53.628088 -408.734821) (xy 53.58618 -408.671646) (xy 53.551224 -408.604375) (xy 53.523617 -408.53377)
			(xy 53.503671 -408.460629) (xy 53.491612 -408.385784) (xy 53.487577 -408.31008) (xy 52.371498 -408.31008)
			(xy 52.370994 -408.347986) (xy 52.362935 -408.423367) (xy 52.34691 -408.497465) (xy 52.3231 -408.56944)
			(xy 52.291774 -408.638476) (xy 52.253287 -408.703791) (xy 52.208076 -408.764646) (xy 52.156652 -408.82035)
			(xy 52.099599 -408.870272) (xy 52.037563 -408.913847) (xy 51.971246 -408.950582) (xy 51.9014 -408.980059)
			(xy 51.828817 -409.001945) (xy 51.754319 -409.015992) (xy 51.678749 -409.022041) (xy 51.602965 -409.020022)
			(xy 51.527825 -409.00996) (xy 51.45418 -408.991968) (xy 51.382864 -408.96625) (xy 51.314687 -408.933098)
			(xy 51.250419 -408.892886) (xy 51.19079 -408.846071) (xy 51.136474 -408.793183) (xy 51.088088 -408.734821)
			(xy 51.04618 -408.671646) (xy 51.011224 -408.604375) (xy 50.983617 -408.53377) (xy 50.963671 -408.460629)
			(xy 50.951612 -408.385784) (xy 50.947577 -408.31008) (xy 49.831498 -408.31008) (xy 49.830994 -408.347986)
			(xy 49.822935 -408.423367) (xy 49.80691 -408.497465) (xy 49.7831 -408.56944) (xy 49.751774 -408.638476)
			(xy 49.713287 -408.703791) (xy 49.668076 -408.764646) (xy 49.616652 -408.82035) (xy 49.559599 -408.870272)
			(xy 49.497563 -408.913847) (xy 49.431246 -408.950582) (xy 49.3614 -408.980059) (xy 49.288817 -409.001945)
			(xy 49.214319 -409.015992) (xy 49.138749 -409.022041) (xy 49.062965 -409.020022) (xy 48.987825 -409.00996)
			(xy 48.91418 -408.991968) (xy 48.842864 -408.96625) (xy 48.774687 -408.933098) (xy 48.710419 -408.892886)
			(xy 48.65079 -408.846071) (xy 48.596474 -408.793183) (xy 48.548088 -408.734821) (xy 48.50618 -408.671646)
			(xy 48.471224 -408.604375) (xy 48.443617 -408.53377) (xy 48.423671 -408.460629) (xy 48.411612 -408.385784)
			(xy 48.407577 -408.31008) (xy 47.291498 -408.31008) (xy 47.290994 -408.347986) (xy 47.282935 -408.423367)
			(xy 47.26691 -408.497465) (xy 47.2431 -408.56944) (xy 47.211774 -408.638476) (xy 47.173287 -408.703791)
			(xy 47.128076 -408.764646) (xy 47.076652 -408.82035) (xy 47.019599 -408.870272) (xy 46.957563 -408.913847)
			(xy 46.891246 -408.950582) (xy 46.8214 -408.980059) (xy 46.748817 -409.001945) (xy 46.674319 -409.015992)
			(xy 46.598749 -409.022041) (xy 46.522965 -409.020022) (xy 46.447825 -409.00996) (xy 46.37418 -408.991968)
			(xy 46.302864 -408.96625) (xy 46.234687 -408.933098) (xy 46.170419 -408.892886) (xy 46.11079 -408.846071)
			(xy 46.056474 -408.793183) (xy 46.008088 -408.734821) (xy 45.96618 -408.671646) (xy 45.931224 -408.604375)
			(xy 45.903617 -408.53377) (xy 45.883671 -408.460629) (xy 45.871612 -408.385784) (xy 45.867577 -408.31008)
			(xy 44.751498 -408.31008) (xy 44.750994 -408.347986) (xy 44.742935 -408.423367) (xy 44.72691 -408.497465)
			(xy 44.7031 -408.56944) (xy 44.671774 -408.638476) (xy 44.633287 -408.703791) (xy 44.588076 -408.764646)
			(xy 44.536652 -408.82035) (xy 44.479599 -408.870272) (xy 44.417563 -408.913847) (xy 44.351246 -408.950582)
			(xy 44.2814 -408.980059) (xy 44.208817 -409.001945) (xy 44.134319 -409.015992) (xy 44.058749 -409.022041)
			(xy 43.982965 -409.020022) (xy 43.907825 -409.00996) (xy 43.83418 -408.991968) (xy 43.762864 -408.96625)
			(xy 43.694687 -408.933098) (xy 43.630419 -408.892886) (xy 43.57079 -408.846071) (xy 43.516474 -408.793183)
			(xy 43.468088 -408.734821) (xy 43.42618 -408.671646) (xy 43.391224 -408.604375) (xy 43.363617 -408.53377)
			(xy 43.343671 -408.460629) (xy 43.331612 -408.385784) (xy 43.327577 -408.31008) (xy 42.500813 -408.31008)
			(xy 42.479042 -408.326857) (xy 42.381609 -408.391665) (xy 42.279905 -408.44954) (xy 42.174422 -408.500202)
			(xy 42.065671 -408.543404) (xy 41.954179 -408.578939) (xy 41.840485 -408.606634) (xy 41.725141 -408.626354)
			(xy 41.608704 -408.638005) (xy 41.491739 -408.64153) (xy 41.374812 -408.636912) (xy 41.258489 -408.624173)
			(xy 41.143334 -408.603375) (xy 41.029905 -408.574618) (xy 40.91875 -408.538042) (xy 40.810407 -408.493825)
			(xy 40.705403 -408.442179) (xy 40.604244 -408.383356) (xy 40.507421 -408.31764) (xy 40.415403 -408.245349)
			(xy 40.328636 -408.166834) (xy 40.247539 -408.082474) (xy 40.172506 -407.992679) (xy 40.103899 -407.897883)
			(xy 40.042051 -407.798544) (xy 39.987262 -407.695145) (xy 39.939796 -407.588186) (xy 39.899884 -407.478185)
			(xy 39.86772 -407.365674) (xy 39.843457 -407.251199) (xy 39.827215 -407.135313) (xy 39.819072 -407.018579)
			(xy 39.818564 -406.96007) (xy 36.329254 -406.96007) (xy 36.315846 -406.981724) (xy 36.263477 -407.051071)
			(xy 36.204933 -407.115291) (xy 36.140713 -407.173835) (xy 36.071366 -407.226204) (xy 35.997482 -407.271951)
			(xy 35.919693 -407.310685) (xy 35.838661 -407.342077) (xy 35.755079 -407.365858) (xy 35.669659 -407.381826)
			(xy 35.58313 -407.389844) (xy 35.49623 -407.389844) (xy 35.409701 -407.381826) (xy 35.324281 -407.365858)
			(xy 35.240699 -407.342077) (xy 35.159667 -407.310685) (xy 35.081878 -407.271951) (xy 35.007994 -407.226204)
			(xy 34.938647 -407.173835) (xy 34.874427 -407.115291) (xy 34.815883 -407.051071) (xy 34.763514 -406.981724)
			(xy 34.717767 -406.90784) (xy 34.679033 -406.830051) (xy 34.647641 -406.749019) (xy 34.62386 -406.665437)
			(xy 34.607892 -406.580017) (xy 34.599874 -406.493488) (xy 31.399486 -406.493488) (xy 31.391468 -406.580017)
			(xy 31.3755 -406.665437) (xy 31.351719 -406.749019) (xy 31.320327 -406.830051) (xy 31.281593 -406.90784)
			(xy 31.235846 -406.981724) (xy 31.183477 -407.051071) (xy 31.124933 -407.115291) (xy 31.060713 -407.173835)
			(xy 30.991366 -407.226204) (xy 30.917482 -407.271951) (xy 30.839693 -407.310685) (xy 30.758661 -407.342077)
			(xy 30.675079 -407.365858) (xy 30.589659 -407.381826) (xy 30.50313 -407.389844) (xy 30.41623 -407.389844)
			(xy 30.329701 -407.381826) (xy 30.244281 -407.365858) (xy 30.160699 -407.342077) (xy 30.079667 -407.310685)
			(xy 30.001878 -407.271951) (xy 29.927994 -407.226204) (xy 29.858647 -407.173835) (xy 29.794427 -407.115291)
			(xy 29.735883 -407.051071) (xy 29.683514 -406.981724) (xy 29.637767 -406.90784) (xy 29.599033 -406.830051)
			(xy 29.567641 -406.749019) (xy 29.54386 -406.665437) (xy 29.527892 -406.580017) (xy 29.519874 -406.493488)
			(xy 29.254196 -406.493488) (xy 29.254196 -418.677513) (xy 47.978812 -418.677513) (xy 47.978812 -418.596403)
			(xy 47.986762 -418.515684) (xy 48.002585 -418.436133) (xy 48.02613 -418.358517) (xy 48.057169 -418.283581)
			(xy 48.095404 -418.212049) (xy 48.140466 -418.144609) (xy 48.191921 -418.08191) (xy 48.249274 -418.024557)
			(xy 48.311973 -417.973102) (xy 48.379413 -417.92804) (xy 48.450945 -417.889805) (xy 48.525881 -417.858766)
			(xy 48.603497 -417.835221) (xy 48.683048 -417.819398) (xy 48.763767 -417.811448) (xy 48.844877 -417.811448)
			(xy 48.925596 -417.819398) (xy 49.005147 -417.835221) (xy 49.082763 -417.858766) (xy 49.157699 -417.889805)
			(xy 49.229231 -417.92804) (xy 49.296671 -417.973102) (xy 49.35937 -418.024557) (xy 49.416723 -418.08191)
			(xy 49.468178 -418.144609) (xy 49.51324 -418.212049) (xy 49.551475 -418.283581) (xy 49.582514 -418.358517)
			(xy 49.606059 -418.436133) (xy 49.621882 -418.515684) (xy 49.629832 -418.596403) (xy 49.63033 -418.636958)
			(xy 49.629832 -418.677513) (xy 51.478932 -418.677513) (xy 51.478932 -418.596403) (xy 51.486882 -418.515684)
			(xy 51.502705 -418.436133) (xy 51.52625 -418.358517) (xy 51.557289 -418.283581) (xy 51.595524 -418.212049)
			(xy 51.640586 -418.144609) (xy 51.692041 -418.08191) (xy 51.749394 -418.024557) (xy 51.812093 -417.973102)
			(xy 51.879533 -417.92804) (xy 51.951065 -417.889805) (xy 52.026001 -417.858766) (xy 52.103617 -417.835221)
			(xy 52.183168 -417.819398) (xy 52.263887 -417.811448) (xy 52.344997 -417.811448) (xy 52.425716 -417.819398)
			(xy 52.505267 -417.835221) (xy 52.582883 -417.858766) (xy 52.657819 -417.889805) (xy 52.729351 -417.92804)
			(xy 52.796791 -417.973102) (xy 52.85949 -418.024557) (xy 52.916843 -418.08191) (xy 52.968298 -418.144609)
			(xy 53.01336 -418.212049) (xy 53.051595 -418.283581) (xy 53.082634 -418.358517) (xy 53.106179 -418.436133)
			(xy 53.122002 -418.515684) (xy 53.129952 -418.596403) (xy 53.13045 -418.636958) (xy 53.129952 -418.677513)
			(xy 53.122002 -418.758232) (xy 53.106179 -418.837783) (xy 53.082634 -418.915399) (xy 53.051595 -418.990335)
			(xy 53.01336 -419.061867) (xy 52.968298 -419.129307) (xy 52.916843 -419.192006) (xy 52.85949 -419.249359)
			(xy 52.796791 -419.300814) (xy 52.729351 -419.345876) (xy 52.657819 -419.384111) (xy 52.582883 -419.41515)
			(xy 52.505267 -419.438695) (xy 52.425716 -419.454518) (xy 52.344997 -419.462468) (xy 52.263887 -419.462468)
			(xy 52.183168 -419.454518) (xy 52.103617 -419.438695) (xy 52.026001 -419.41515) (xy 51.951065 -419.384111)
			(xy 51.879533 -419.345876) (xy 51.812093 -419.300814) (xy 51.749394 -419.249359) (xy 51.692041 -419.192006)
			(xy 51.640586 -419.129307) (xy 51.595524 -419.061867) (xy 51.557289 -418.990335) (xy 51.52625 -418.915399)
			(xy 51.502705 -418.837783) (xy 51.486882 -418.758232) (xy 51.478932 -418.677513) (xy 49.629832 -418.677513)
			(xy 49.621882 -418.758232) (xy 49.606059 -418.837783) (xy 49.582514 -418.915399) (xy 49.551475 -418.990335)
			(xy 49.51324 -419.061867) (xy 49.468178 -419.129307) (xy 49.416723 -419.192006) (xy 49.35937 -419.249359)
			(xy 49.296671 -419.300814) (xy 49.229231 -419.345876) (xy 49.157699 -419.384111) (xy 49.082763 -419.41515)
			(xy 49.005147 -419.438695) (xy 48.925596 -419.454518) (xy 48.844877 -419.462468) (xy 48.763767 -419.462468)
			(xy 48.683048 -419.454518) (xy 48.603497 -419.438695) (xy 48.525881 -419.41515) (xy 48.450945 -419.384111)
			(xy 48.379413 -419.345876) (xy 48.311973 -419.300814) (xy 48.249274 -419.249359) (xy 48.191921 -419.192006)
			(xy 48.140466 -419.129307) (xy 48.095404 -419.061867) (xy 48.057169 -418.990335) (xy 48.02613 -418.915399)
			(xy 48.002585 -418.837783) (xy 47.986762 -418.758232) (xy 47.978812 -418.677513) (xy 29.254196 -418.677513)
			(xy 29.254196 -420.06012) (xy 86.877404 -420.06012) (xy 86.881424 -419.869469) (xy 86.893478 -419.679156)
			(xy 86.913544 -419.489521) (xy 86.941587 -419.3009) (xy 86.977556 -419.11363) (xy 87.021388 -418.928042)
			(xy 87.073005 -418.744467) (xy 87.132315 -418.563231) (xy 87.199213 -418.384656) (xy 87.273579 -418.209061)
			(xy 87.355281 -418.036756) (xy 87.444175 -417.868049) (xy 87.540101 -417.703239) (xy 87.64289 -417.54262)
			(xy 87.752359 -417.386477) (xy 87.868313 -417.235088) (xy 87.990547 -417.088721) (xy 88.118841 -416.947637)
			(xy 88.252969 -416.812088) (xy 88.392693 -416.682313) (xy 88.537763 -416.558543) (xy 88.687921 -416.441)
			(xy 88.842902 -416.329891) (xy 89.002429 -416.225414) (xy 89.166218 -416.127755) (xy 89.333978 -416.037088)
			(xy 89.505412 -415.953574) (xy 89.680214 -415.877361) (xy 89.858073 -415.808585) (xy 90.038674 -415.747367)
			(xy 90.221694 -415.693818) (xy 90.40681 -415.648032) (xy 90.593691 -415.61009) (xy 90.782006 -415.580061)
			(xy 90.971419 -415.557996) (xy 91.161593 -415.543937) (xy 91.352192 -415.537907) (xy 91.542875 -415.539917)
			(xy 91.733304 -415.549964) (xy 91.92314 -415.56803) (xy 92.112046 -415.594083) (xy 92.299685 -415.628076)
			(xy 92.485725 -415.669949) (xy 92.669834 -415.719628) (xy 92.851685 -415.777024) (xy 93.030955 -415.842035)
			(xy 93.207325 -415.914546) (xy 93.380481 -415.994427) (xy 93.550116 -416.081537) (xy 93.715928 -416.175721)
			(xy 93.877622 -416.276812) (xy 94.03491 -416.384628) (xy 94.187513 -416.49898) (xy 94.335161 -416.619663)
			(xy 94.477589 -416.746464) (xy 94.614545 -416.879155) (xy 94.745786 -417.017503) (xy 94.871078 -417.16126)
			(xy 94.990198 -417.310171) (xy 95.102934 -417.463972) (xy 95.209087 -417.622388) (xy 95.308467 -417.785139)
			(xy 95.400897 -417.951934) (xy 95.486214 -418.122478) (xy 95.564266 -418.296466) (xy 95.634913 -418.473591)
			(xy 95.698031 -418.653536) (xy 95.753507 -418.835982) (xy 95.801242 -419.020605) (xy 95.841152 -419.207075)
			(xy 95.873165 -419.395063) (xy 95.897225 -419.584233) (xy 95.913288 -419.774249) (xy 95.921327 -419.964773)
			(xy 95.92183 -420.06012) (xy 95.921327 -420.155467) (xy 95.913288 -420.345991) (xy 95.897225 -420.536007)
			(xy 95.873165 -420.725177) (xy 95.841152 -420.913165) (xy 95.801242 -421.099635) (xy 95.753507 -421.284258)
			(xy 95.698031 -421.466704) (xy 95.634913 -421.646649) (xy 95.564266 -421.823774) (xy 95.486214 -421.997762)
			(xy 95.400897 -422.168306) (xy 95.308467 -422.335101) (xy 95.209087 -422.497852) (xy 95.102934 -422.656268)
			(xy 94.990198 -422.810069) (xy 94.871078 -422.95898) (xy 94.745786 -423.102737) (xy 94.614545 -423.241085)
			(xy 94.477589 -423.373776) (xy 94.335161 -423.500577) (xy 94.187513 -423.62126) (xy 94.03491 -423.735612)
			(xy 93.877622 -423.843428) (xy 93.715928 -423.944519) (xy 93.550116 -424.038703) (xy 93.380481 -424.125813)
			(xy 93.207325 -424.205694) (xy 93.030955 -424.278205) (xy 92.851685 -424.343216) (xy 92.669834 -424.400612)
			(xy 92.485725 -424.450291) (xy 92.299685 -424.492164) (xy 92.112046 -424.526157) (xy 91.92314 -424.55221)
			(xy 91.733304 -424.570276) (xy 91.542875 -424.580323) (xy 91.352192 -424.582333) (xy 91.161593 -424.576303)
			(xy 90.971419 -424.562244) (xy 90.782006 -424.540179) (xy 90.593691 -424.51015) (xy 90.40681 -424.472208)
			(xy 90.221694 -424.426422) (xy 90.038674 -424.372873) (xy 89.858073 -424.311655) (xy 89.680214 -424.242879)
			(xy 89.505412 -424.166666) (xy 89.333978 -424.083152) (xy 89.166218 -423.992485) (xy 89.002429 -423.894826)
			(xy 88.842902 -423.790349) (xy 88.687921 -423.67924) (xy 88.537763 -423.561697) (xy 88.392693 -423.437927)
			(xy 88.252969 -423.308152) (xy 88.118841 -423.172603) (xy 87.990547 -423.031519) (xy 87.868313 -422.885152)
			(xy 87.752359 -422.733763) (xy 87.64289 -422.57762) (xy 87.540101 -422.417001) (xy 87.444175 -422.252191)
			(xy 87.355281 -422.083484) (xy 87.273579 -421.911179) (xy 87.199213 -421.735584) (xy 87.132315 -421.557009)
			(xy 87.073005 -421.375773) (xy 87.021388 -421.192198) (xy 86.977556 -421.00661) (xy 86.941587 -420.81934)
			(xy 86.913544 -420.630719) (xy 86.893478 -420.441084) (xy 86.881424 -420.250771) (xy 86.877404 -420.06012)
			(xy 29.254196 -420.06012) (xy 29.254196 -420.765732) (xy 73.130916 -420.765732) (xy 73.134987 -420.71011)
			(xy 73.147113 -420.655673) (xy 73.167036 -420.603582) (xy 73.194332 -420.554947) (xy 73.228418 -420.510804)
			(xy 73.268567 -420.472095) (xy 73.313925 -420.439644) (xy 73.363525 -420.414143) (xy 73.416309 -420.396136)
			(xy 73.471152 -420.386006) (xy 73.526886 -420.383969) (xy 73.582323 -420.390069) (xy 73.63628 -420.404175)
			(xy 73.687609 -420.425987) (xy 73.735215 -420.455041) (xy 73.778083 -420.490716) (xy 73.8153 -420.532253)
			(xy 73.846073 -420.578766) (xy 73.869745 -420.629263) (xy 73.885813 -420.68267) (xy 73.893933 -420.737846)
			(xy 73.894442 -420.765732) (xy 74.316842 -420.765732) (xy 74.320913 -420.71011) (xy 74.333039 -420.655673)
			(xy 74.352962 -420.603582) (xy 74.380258 -420.554947) (xy 74.414344 -420.510804) (xy 74.454493 -420.472095)
			(xy 74.499851 -420.439644) (xy 74.549451 -420.414143) (xy 74.602235 -420.396136) (xy 74.657078 -420.386006)
			(xy 74.712812 -420.383969) (xy 74.768249 -420.390069) (xy 74.822206 -420.404175) (xy 74.873535 -420.425987)
			(xy 74.921141 -420.455041) (xy 74.964009 -420.490716) (xy 75.001226 -420.532253) (xy 75.031999 -420.578766)
			(xy 75.055671 -420.629263) (xy 75.071739 -420.68267) (xy 75.079859 -420.737846) (xy 75.080368 -420.765732)
			(xy 75.079859 -420.793618) (xy 75.071739 -420.848794) (xy 75.055671 -420.902201) (xy 75.031999 -420.952698)
			(xy 75.001226 -420.999211) (xy 74.964009 -421.040748) (xy 74.921141 -421.076423) (xy 74.873535 -421.105477)
			(xy 74.822206 -421.127289) (xy 74.768249 -421.141395) (xy 74.712812 -421.147495) (xy 74.657078 -421.145458)
			(xy 74.602235 -421.135328) (xy 74.549451 -421.117321) (xy 74.499851 -421.09182) (xy 74.454493 -421.059369)
			(xy 74.414344 -421.02066) (xy 74.380258 -420.976517) (xy 74.352962 -420.927882) (xy 74.333039 -420.875791)
			(xy 74.320913 -420.821354) (xy 74.316842 -420.765732) (xy 73.894442 -420.765732) (xy 73.893933 -420.793618)
			(xy 73.885813 -420.848794) (xy 73.869745 -420.902201) (xy 73.846073 -420.952698) (xy 73.8153 -420.999211)
			(xy 73.778083 -421.040748) (xy 73.735215 -421.076423) (xy 73.687609 -421.105477) (xy 73.63628 -421.127289)
			(xy 73.582323 -421.141395) (xy 73.526886 -421.147495) (xy 73.471152 -421.145458) (xy 73.416309 -421.135328)
			(xy 73.363525 -421.117321) (xy 73.313925 -421.09182) (xy 73.268567 -421.059369) (xy 73.228418 -421.02066)
			(xy 73.194332 -420.976517) (xy 73.167036 -420.927882) (xy 73.147113 -420.875791) (xy 73.134987 -420.821354)
			(xy 73.130916 -420.765732) (xy 29.254196 -420.765732) (xy 29.254196 -421.610282) (xy 71.775826 -421.610282)
			(xy 71.779897 -421.55466) (xy 71.792023 -421.500223) (xy 71.811946 -421.448132) (xy 71.839242 -421.399497)
			(xy 71.873328 -421.355354) (xy 71.913477 -421.316645) (xy 71.958835 -421.284194) (xy 72.008435 -421.258693)
			(xy 72.061219 -421.240686) (xy 72.116062 -421.230556) (xy 72.171796 -421.228519) (xy 72.227233 -421.234619)
			(xy 72.28119 -421.248725) (xy 72.332519 -421.270537) (xy 72.380125 -421.299591) (xy 72.422993 -421.335266)
			(xy 72.46021 -421.376803) (xy 72.490983 -421.423316) (xy 72.514655 -421.473813) (xy 72.530723 -421.52722)
			(xy 72.538843 -421.582396) (xy 72.539352 -421.610282) (xy 72.538843 -421.638168) (xy 72.530723 -421.693344)
			(xy 72.514655 -421.746751) (xy 72.490983 -421.797248) (xy 72.46021 -421.843761) (xy 72.422993 -421.885298)
			(xy 72.380125 -421.920973) (xy 72.332519 -421.950027) (xy 72.28119 -421.971839) (xy 72.227233 -421.985945)
			(xy 72.171796 -421.992045) (xy 72.116062 -421.990008) (xy 72.061219 -421.979878) (xy 72.008435 -421.961871)
			(xy 71.958835 -421.93637) (xy 71.913477 -421.903919) (xy 71.873328 -421.86521) (xy 71.839242 -421.821067)
			(xy 71.811946 -421.772432) (xy 71.792023 -421.720341) (xy 71.779897 -421.665904) (xy 71.775826 -421.610282)
			(xy 29.254196 -421.610282) (xy 29.254196 -422.444389) (xy 55.277413 -422.444389) (xy 55.281302 -422.39004)
			(xy 55.292886 -422.336797) (xy 55.31193 -422.285745) (xy 55.338045 -422.237923) (xy 55.3707 -422.194305)
			(xy 55.409231 -422.155778) (xy 55.452853 -422.123126) (xy 55.500677 -422.097015) (xy 55.551731 -422.077976)
			(xy 55.604974 -422.066397) (xy 55.659324 -422.062513) (xy 55.713673 -422.066404) (xy 55.766915 -422.07799)
			(xy 55.817967 -422.097035) (xy 55.865788 -422.123152) (xy 55.887874 -422.13911) (xy 55.906886 -422.152706)
			(xy 55.948769 -422.173438) (xy 55.993737 -422.186164) (xy 56.040274 -422.190454) (xy 56.086811 -422.186164)
			(xy 56.131779 -422.173438) (xy 56.173662 -422.152706) (xy 56.192674 -422.13911) (xy 56.214746 -422.123124)
			(xy 56.262574 -422.096996) (xy 56.313634 -422.077942) (xy 56.366886 -422.066349) (xy 56.421246 -422.062453)
			(xy 56.475607 -422.066334) (xy 56.528863 -422.077912) (xy 56.579928 -422.096952) (xy 56.627764 -422.123066)
			(xy 56.671396 -422.155722) (xy 56.709936 -422.194255) (xy 56.7426 -422.237882) (xy 56.768721 -422.285713)
			(xy 56.78777 -422.336775) (xy 56.799357 -422.390029) (xy 56.803247 -422.444389) (xy 57.164106 -422.444389)
			(xy 57.167995 -422.390038) (xy 57.17958 -422.336794) (xy 57.198624 -422.285741) (xy 57.22474 -422.237917)
			(xy 57.257397 -422.194298) (xy 57.295929 -422.15577) (xy 57.339553 -422.123118) (xy 57.387379 -422.097007)
			(xy 57.438434 -422.077968) (xy 57.49168 -422.066389) (xy 57.546031 -422.062506) (xy 57.600382 -422.066398)
			(xy 57.653625 -422.077985) (xy 57.704677 -422.097032) (xy 57.752499 -422.123151) (xy 57.774586 -422.13911)
			(xy 57.793598 -422.152706) (xy 57.835481 -422.173438) (xy 57.880449 -422.186164) (xy 57.926986 -422.190454)
			(xy 57.973523 -422.186164) (xy 58.018491 -422.173438) (xy 58.060374 -422.152706) (xy 58.079386 -422.13911)
			(xy 58.101458 -422.123125) (xy 58.149285 -422.096999) (xy 58.200344 -422.077947) (xy 58.253595 -422.066355)
			(xy 58.307953 -422.062461) (xy 58.362313 -422.066342) (xy 58.415566 -422.077921) (xy 58.46663 -422.09696)
			(xy 58.514464 -422.123074) (xy 58.558094 -422.15573) (xy 58.596633 -422.194262) (xy 58.629295 -422.237888)
			(xy 58.655416 -422.285718) (xy 58.674463 -422.336779) (xy 58.68605 -422.39003) (xy 58.689939 -422.444389)
			(xy 58.686053 -422.498748) (xy 58.674469 -422.552001) (xy 58.655425 -422.603062) (xy 58.629307 -422.650894)
			(xy 58.596647 -422.694521) (xy 58.55811 -422.733056) (xy 58.514482 -422.765714) (xy 58.466649 -422.791831)
			(xy 58.415587 -422.810873) (xy 58.362334 -422.822455) (xy 58.307975 -422.826339) (xy 58.253616 -422.822448)
			(xy 58.200365 -422.810859) (xy 58.149305 -422.79181) (xy 58.101476 -422.765687) (xy 58.079386 -422.749726)
			(xy 58.060374 -422.73613) (xy 58.018491 -422.715398) (xy 57.973523 -422.702672) (xy 57.926986 -422.698382)
			(xy 57.880449 -422.702672) (xy 57.835481 -422.715398) (xy 57.793598 -422.73613) (xy 57.774586 -422.749726)
			(xy 57.752481 -422.76566) (xy 57.704658 -422.791777) (xy 57.653604 -422.810821) (xy 57.60036 -422.822405)
			(xy 57.546009 -422.826294) (xy 57.491658 -422.822408) (xy 57.438414 -422.810826) (xy 57.387359 -422.791784)
			(xy 57.339534 -422.765671) (xy 57.295913 -422.733016) (xy 57.257383 -422.694486) (xy 57.224729 -422.650864)
			(xy 57.198615 -422.60304) (xy 57.179574 -422.551985) (xy 57.167992 -422.49874) (xy 57.164106 -422.444389)
			(xy 56.803247 -422.444389) (xy 56.79936 -422.49875) (xy 56.787776 -422.552004) (xy 56.76873 -422.603067)
			(xy 56.742611 -422.6509) (xy 56.70995 -422.694528) (xy 56.671412 -422.733064) (xy 56.627782 -422.765723)
			(xy 56.579948 -422.791839) (xy 56.528884 -422.810882) (xy 56.475629 -422.822463) (xy 56.421268 -422.826347)
			(xy 56.366908 -422.822454) (xy 56.313655 -422.810864) (xy 56.262594 -422.791813) (xy 56.214764 -422.765688)
			(xy 56.192674 -422.749726) (xy 56.173662 -422.73613) (xy 56.131779 -422.715398) (xy 56.086811 -422.702672)
			(xy 56.040274 -422.698382) (xy 55.993737 -422.702672) (xy 55.948769 -422.715398) (xy 55.906886 -422.73613)
			(xy 55.887874 -422.749726) (xy 55.86577 -422.765659) (xy 55.817947 -422.791774) (xy 55.766895 -422.810816)
			(xy 55.713652 -422.822399) (xy 55.659302 -422.826287) (xy 55.604953 -422.8224) (xy 55.55171 -422.810817)
			(xy 55.500658 -422.791776) (xy 55.452835 -422.765662) (xy 55.409215 -422.733008) (xy 55.370686 -422.694479)
			(xy 55.338033 -422.650858) (xy 55.311921 -422.603035) (xy 55.29288 -422.551982) (xy 55.281299 -422.498739)
			(xy 55.277413 -422.444389) (xy 29.254196 -422.444389) (xy 29.254196 -424.277974) (xy 55.277434 -424.277974)
			(xy 55.281325 -424.223628) (xy 55.292911 -424.170388) (xy 55.311955 -424.11934) (xy 55.338071 -424.071522)
			(xy 55.370726 -424.027907) (xy 55.409257 -423.989383) (xy 55.452877 -423.956735) (xy 55.5007 -423.930628)
			(xy 55.551752 -423.911592) (xy 55.604993 -423.900016) (xy 55.65934 -423.896134) (xy 55.713686 -423.900027)
			(xy 55.766924 -423.911614) (xy 55.817972 -423.930661) (xy 55.86579 -423.956778) (xy 55.887874 -423.972736)
			(xy 55.906886 -423.986332) (xy 55.948769 -424.007064) (xy 55.993737 -424.01979) (xy 56.040274 -424.02408)
			(xy 56.086811 -424.01979) (xy 56.131779 -424.007064) (xy 56.173662 -423.986332) (xy 56.192674 -423.972736)
			(xy 56.214722 -423.956715) (xy 56.262551 -423.930584) (xy 56.313613 -423.911527) (xy 56.366868 -423.899931)
			(xy 56.421231 -423.896033) (xy 56.475595 -423.899911) (xy 56.528854 -423.911488) (xy 56.579923 -423.930526)
			(xy 56.627762 -423.95664) (xy 56.671398 -423.989296) (xy 56.709942 -424.02783) (xy 56.742609 -424.071458)
			(xy 56.768734 -424.11929) (xy 56.787785 -424.170355) (xy 56.799375 -424.22361) (xy 56.803267 -424.277974)
			(xy 57.164127 -424.277974) (xy 57.168018 -424.223626) (xy 57.179604 -424.170385) (xy 57.198649 -424.119335)
			(xy 57.224766 -424.071516) (xy 57.257423 -424.0279) (xy 57.295955 -423.989375) (xy 57.339577 -423.956727)
			(xy 57.387402 -423.930619) (xy 57.438455 -423.911584) (xy 57.491698 -423.900008) (xy 57.546046 -423.896127)
			(xy 57.600394 -423.900021) (xy 57.653634 -423.91161) (xy 57.704683 -423.930658) (xy 57.752501 -423.956777)
			(xy 57.774586 -423.972736) (xy 57.793598 -423.986332) (xy 57.835481 -424.007064) (xy 57.880449 -424.01979)
			(xy 57.926986 -424.02408) (xy 57.973523 -424.01979) (xy 58.018491 -424.007064) (xy 58.060374 -423.986332)
			(xy 58.079386 -423.972736) (xy 58.101433 -423.956716) (xy 58.149262 -423.930587) (xy 58.200323 -423.911531)
			(xy 58.253576 -423.899937) (xy 58.307938 -423.89604) (xy 58.3623 -423.899919) (xy 58.415557 -423.911496)
			(xy 58.466624 -423.930535) (xy 58.514462 -423.956648) (xy 58.558096 -423.989304) (xy 58.596638 -424.027837)
			(xy 58.629304 -424.071464) (xy 58.655428 -424.119295) (xy 58.674479 -424.170358) (xy 58.686068 -424.223612)
			(xy 58.68996 -424.277974) (xy 59.405102 -424.277974) (xy 59.408993 -424.22362) (xy 59.420581 -424.170374)
			(xy 59.439629 -424.119319) (xy 59.46575 -424.071495) (xy 59.498411 -424.027875) (xy 59.536948 -423.989348)
			(xy 59.580576 -423.956697) (xy 59.628407 -423.930589) (xy 59.679467 -423.911554) (xy 59.732716 -423.89998)
			(xy 59.78707 -423.896102) (xy 59.841423 -423.9) (xy 59.894668 -423.911594) (xy 59.945721 -423.930648)
			(xy 59.993542 -423.956774) (xy 60.015628 -423.972736) (xy 60.03464 -423.986332) (xy 60.076523 -424.007064)
			(xy 60.121491 -424.01979) (xy 60.168028 -424.02408) (xy 60.214565 -424.01979) (xy 60.259533 -424.007064)
			(xy 60.301416 -423.986332) (xy 60.320428 -423.972736) (xy 60.342474 -423.956719) (xy 60.3903 -423.930597)
			(xy 60.441357 -423.911548) (xy 60.494606 -423.899958) (xy 60.548961 -423.896065) (xy 60.603318 -423.899947)
			(xy 60.656569 -423.911526) (xy 60.707629 -423.930565) (xy 60.755461 -423.956677) (xy 60.799089 -423.989331)
			(xy 60.837626 -424.027862) (xy 60.870287 -424.071484) (xy 60.896408 -424.119311) (xy 60.915456 -424.170369)
			(xy 60.927044 -424.223618) (xy 60.930935 -424.277974) (xy 61.309112 -424.277974) (xy 61.313003 -424.223622)
			(xy 61.32459 -424.170378) (xy 61.343637 -424.119325) (xy 61.369756 -424.071503) (xy 61.402416 -424.027884)
			(xy 61.440951 -423.989358) (xy 61.484576 -423.956709) (xy 61.532405 -423.930601) (xy 61.583462 -423.911565)
			(xy 61.636709 -423.89999) (xy 61.691061 -423.896112) (xy 61.745412 -423.900008) (xy 61.798655 -423.9116)
			(xy 61.849707 -423.930651) (xy 61.897527 -423.956775) (xy 61.919612 -423.972736) (xy 61.938624 -423.986332)
			(xy 61.980507 -424.007064) (xy 62.025475 -424.01979) (xy 62.072012 -424.02408) (xy 62.118549 -424.01979)
			(xy 62.163517 -424.007064) (xy 62.2054 -423.986332) (xy 62.224412 -423.972736) (xy 62.246459 -423.956718)
			(xy 62.294286 -423.930593) (xy 62.345344 -423.911541) (xy 62.398595 -423.89995) (xy 62.452952 -423.896055)
			(xy 62.507311 -423.899937) (xy 62.560564 -423.911515) (xy 62.611627 -423.930554) (xy 62.659461 -423.956666)
			(xy 62.703092 -423.989321) (xy 62.741631 -424.027852) (xy 62.774294 -424.071476) (xy 62.800416 -424.119305)
			(xy 62.819465 -424.170365) (xy 62.831053 -424.223616) (xy 62.834945 -424.277974) (xy 62.83106 -424.332332)
			(xy 62.819479 -424.385585) (xy 62.800438 -424.436647) (xy 62.774322 -424.484479) (xy 62.741665 -424.528108)
			(xy 62.703132 -424.566645) (xy 62.659506 -424.599305) (xy 62.611675 -424.625424) (xy 62.560615 -424.644471)
			(xy 62.507363 -424.656056) (xy 62.453005 -424.659945) (xy 62.398647 -424.656057) (xy 62.345395 -424.644473)
			(xy 62.294334 -424.625429) (xy 62.246503 -424.599311) (xy 62.224412 -424.583352) (xy 62.2054 -424.569756)
			(xy 62.163517 -424.549024) (xy 62.118549 -424.536298) (xy 62.072012 -424.532008) (xy 62.025475 -424.536298)
			(xy 61.980507 -424.549024) (xy 61.938624 -424.569756) (xy 61.919612 -424.583352) (xy 61.897482 -424.599254)
			(xy 61.849659 -424.625371) (xy 61.798605 -424.644415) (xy 61.74536 -424.656) (xy 61.691008 -424.659888)
			(xy 61.636657 -424.656002) (xy 61.583412 -424.64442) (xy 61.532357 -424.625378) (xy 61.484532 -424.599263)
			(xy 61.440911 -424.566607) (xy 61.402381 -424.528076) (xy 61.369728 -424.484453) (xy 61.343615 -424.436627)
			(xy 61.324575 -424.385571) (xy 61.312995 -424.332325) (xy 61.309112 -424.277974) (xy 60.930935 -424.277974)
			(xy 60.927051 -424.33233) (xy 60.915471 -424.38558) (xy 60.89643 -424.436641) (xy 60.870316 -424.484471)
			(xy 60.837661 -424.528098) (xy 60.799129 -424.566634) (xy 60.755505 -424.599294) (xy 60.707678 -424.625413)
			(xy 60.656619 -424.644459) (xy 60.60337 -424.656045) (xy 60.549014 -424.659935) (xy 60.494658 -424.656049)
			(xy 60.441408 -424.644467) (xy 60.390348 -424.625425) (xy 60.342519 -424.599309) (xy 60.320428 -424.583352)
			(xy 60.301416 -424.569756) (xy 60.259533 -424.549024) (xy 60.214565 -424.536298) (xy 60.168028 -424.532008)
			(xy 60.121491 -424.536298) (xy 60.076523 -424.549024) (xy 60.03464 -424.569756) (xy 60.015628 -424.583352)
			(xy 59.993498 -424.599255) (xy 59.945673 -424.625374) (xy 59.894618 -424.644421) (xy 59.841371 -424.656008)
			(xy 59.787018 -424.659898) (xy 59.732664 -424.656013) (xy 59.679416 -424.644431) (xy 59.628359 -424.625389)
			(xy 59.580532 -424.599274) (xy 59.536908 -424.566618) (xy 59.498376 -424.528085) (xy 59.465721 -424.484461)
			(xy 59.439607 -424.436633) (xy 59.420566 -424.385575) (xy 59.408986 -424.332328) (xy 59.405102 -424.277974)
			(xy 58.68996 -424.277974) (xy 58.686076 -424.332336) (xy 58.674494 -424.385592) (xy 58.65545 -424.436657)
			(xy 58.629333 -424.484492) (xy 58.596673 -424.528123) (xy 58.558136 -424.566662) (xy 58.514506 -424.599323)
			(xy 58.466672 -424.625443) (xy 58.415608 -424.644489) (xy 58.362352 -424.656073) (xy 58.30799 -424.65996)
			(xy 58.253629 -424.65607) (xy 58.200374 -424.644484) (xy 58.14931 -424.625435) (xy 58.101478 -424.599313)
			(xy 58.079386 -424.583352) (xy 58.060374 -424.569756) (xy 58.018491 -424.549024) (xy 57.973523 -424.536298)
			(xy 57.926986 -424.532008) (xy 57.880449 -424.536298) (xy 57.835481 -424.549024) (xy 57.793598 -424.569756)
			(xy 57.774586 -424.583352) (xy 57.752457 -424.599251) (xy 57.704635 -424.625364) (xy 57.653583 -424.644405)
			(xy 57.600342 -424.655987) (xy 57.545994 -424.659873) (xy 57.491646 -424.655985) (xy 57.438404 -424.644402)
			(xy 57.387354 -424.625359) (xy 57.339532 -424.599245) (xy 57.295915 -424.56659) (xy 57.257388 -424.528061)
			(xy 57.224738 -424.48444) (xy 57.198627 -424.436617) (xy 57.179589 -424.385564) (xy 57.168011 -424.332322)
			(xy 57.164127 -424.277974) (xy 56.803267 -424.277974) (xy 56.799383 -424.332337) (xy 56.7878 -424.385595)
			(xy 56.768756 -424.436662) (xy 56.742637 -424.484498) (xy 56.709976 -424.52813) (xy 56.671438 -424.56667)
			(xy 56.627806 -424.599332) (xy 56.579971 -424.625452) (xy 56.528904 -424.644497) (xy 56.475647 -424.656081)
			(xy 56.421284 -424.659967) (xy 56.36692 -424.656077) (xy 56.313664 -424.644488) (xy 56.262599 -424.625438)
			(xy 56.214766 -424.599314) (xy 56.192674 -424.583352) (xy 56.173662 -424.569756) (xy 56.131779 -424.549024)
			(xy 56.086811 -424.536298) (xy 56.040274 -424.532008) (xy 55.993737 -424.536298) (xy 55.948769 -424.549024)
			(xy 55.906886 -424.569756) (xy 55.887874 -424.583352) (xy 55.865745 -424.59925) (xy 55.817924 -424.625361)
			(xy 55.766874 -424.6444) (xy 55.713633 -424.655981) (xy 55.659287 -424.659866) (xy 55.604941 -424.655977)
			(xy 55.551701 -424.644393) (xy 55.500652 -424.62535) (xy 55.452833 -424.599236) (xy 55.409217 -424.566582)
			(xy 55.370692 -424.528053) (xy 55.338042 -424.484434) (xy 55.311933 -424.436612) (xy 55.292896 -424.385561)
			(xy 55.281318 -424.33232) (xy 55.277434 -424.277974) (xy 29.254196 -424.277974) (xy 29.254196 -426.179012)
			(xy 55.277383 -426.179012) (xy 55.281269 -426.124658) (xy 55.292851 -426.071411) (xy 55.311893 -426.020354)
			(xy 55.338007 -425.972526) (xy 55.370663 -425.928902) (xy 55.409194 -425.89037) (xy 55.452817 -425.857713)
			(xy 55.500644 -425.831597) (xy 55.5517 -425.812554) (xy 55.604948 -425.80097) (xy 55.659301 -425.797083)
			(xy 55.713655 -425.800971) (xy 55.766902 -425.812554) (xy 55.817958 -425.831598) (xy 55.865785 -425.857714)
			(xy 55.887874 -425.873672) (xy 55.906886 -425.887268) (xy 55.948769 -425.908) (xy 55.993737 -425.920726)
			(xy 56.040274 -425.925016) (xy 56.086811 -425.920726) (xy 56.131779 -425.908) (xy 56.173662 -425.887268)
			(xy 56.192674 -425.873672) (xy 56.214782 -425.857737) (xy 56.262608 -425.831615) (xy 56.313665 -425.812565)
			(xy 56.366913 -425.800976) (xy 56.421269 -425.797084) (xy 56.475626 -425.800967) (xy 56.528876 -425.812548)
			(xy 56.579936 -425.831589) (xy 56.627767 -425.857703) (xy 56.671393 -425.89036) (xy 56.709928 -425.928893)
			(xy 56.742586 -425.972518) (xy 56.768703 -426.020347) (xy 56.787747 -426.071406) (xy 56.79933 -426.124656)
			(xy 56.803216 -426.179012) (xy 57.164076 -426.179012) (xy 57.167962 -426.124657) (xy 57.179544 -426.071408)
			(xy 57.198587 -426.020349) (xy 57.224702 -425.97252) (xy 57.257359 -425.928895) (xy 57.295892 -425.890362)
			(xy 57.339517 -425.857705) (xy 57.387345 -425.831589) (xy 57.438404 -425.812545) (xy 57.491653 -425.800962)
			(xy 57.546008 -425.797076) (xy 57.600363 -425.800965) (xy 57.653612 -425.81255) (xy 57.704669 -425.831595)
			(xy 57.752497 -425.857713) (xy 57.774586 -425.873672) (xy 57.793598 -425.887268) (xy 57.835481 -425.908)
			(xy 57.880449 -425.920726) (xy 57.926986 -425.925016) (xy 57.973523 -425.920726) (xy 58.018491 -425.908)
			(xy 58.060374 -425.887268) (xy 58.079386 -425.873672) (xy 58.101493 -425.857738) (xy 58.149319 -425.831617)
			(xy 58.200375 -425.81257) (xy 58.253622 -425.800982) (xy 58.307976 -425.797091) (xy 58.362331 -425.800975)
			(xy 58.415579 -425.812556) (xy 58.466638 -425.831598) (xy 58.514466 -425.857712) (xy 58.558091 -425.890368)
			(xy 58.596625 -425.9289) (xy 58.629282 -425.972524) (xy 58.655397 -426.020351) (xy 58.67444 -426.071409)
			(xy 58.686023 -426.124657) (xy 58.689909 -426.179012) (xy 59.405051 -426.179012) (xy 59.408937 -426.124651)
			(xy 59.420521 -426.071396) (xy 59.439567 -426.020333) (xy 59.465686 -425.972499) (xy 59.498347 -425.92887)
			(xy 59.536885 -425.890334) (xy 59.580516 -425.857675) (xy 59.628351 -425.831558) (xy 59.679415 -425.812516)
			(xy 59.732671 -425.800934) (xy 59.787032 -425.797051) (xy 59.841393 -425.800943) (xy 59.894646 -425.812534)
			(xy 59.945707 -425.831585) (xy 59.993538 -425.85771) (xy 60.015628 -425.873672) (xy 60.03464 -425.887268)
			(xy 60.076523 -425.908) (xy 60.121491 -425.920726) (xy 60.168028 -425.925016) (xy 60.214565 -425.920726)
			(xy 60.259533 -425.908) (xy 60.301416 -425.887268) (xy 60.320428 -425.873672) (xy 60.342534 -425.857741)
			(xy 60.390357 -425.831628) (xy 60.441409 -425.812586) (xy 60.494651 -425.801003) (xy 60.549 -425.797116)
			(xy 60.603349 -425.801003) (xy 60.656591 -425.812586) (xy 60.707643 -425.831628) (xy 60.755466 -425.857741)
			(xy 60.799085 -425.890395) (xy 60.837613 -425.928924) (xy 60.870265 -425.972544) (xy 60.896377 -426.020368)
			(xy 60.915418 -426.07142) (xy 60.926998 -426.124663) (xy 60.930884 -426.179012) (xy 61.30906 -426.179012)
			(xy 61.312947 -426.124653) (xy 61.32453 -426.071401) (xy 61.343574 -426.020339) (xy 61.369692 -425.972507)
			(xy 61.402352 -425.92888) (xy 61.440888 -425.890345) (xy 61.484516 -425.857686) (xy 61.532349 -425.83157)
			(xy 61.583411 -425.812527) (xy 61.636664 -425.800945) (xy 61.691023 -425.79706) (xy 61.745381 -425.800952)
			(xy 61.798633 -425.81254) (xy 61.849693 -425.831589) (xy 61.897522 -425.857711) (xy 61.919612 -425.873672)
			(xy 61.938624 -425.887268) (xy 61.980507 -425.908) (xy 62.025475 -425.920726) (xy 62.072012 -425.925016)
			(xy 62.118549 -425.920726) (xy 62.163517 -425.908) (xy 62.2054 -425.887268) (xy 62.224412 -425.873672)
			(xy 62.246519 -425.85774) (xy 62.294342 -425.831624) (xy 62.345396 -425.81258) (xy 62.39864 -425.800995)
			(xy 62.452991 -425.797107) (xy 62.507342 -425.800993) (xy 62.560587 -425.812575) (xy 62.611641 -425.831616)
			(xy 62.659466 -425.85773) (xy 62.703087 -425.890385) (xy 62.741617 -425.928915) (xy 62.774271 -425.972536)
			(xy 62.800385 -426.020361) (xy 62.819426 -426.071416) (xy 62.831008 -426.124661) (xy 62.834893 -426.179012)
			(xy 62.831004 -426.233363) (xy 62.819419 -426.286607) (xy 62.800375 -426.33766) (xy 62.774258 -426.385484)
			(xy 62.741602 -426.429103) (xy 62.703069 -426.467631) (xy 62.659446 -426.500283) (xy 62.611619 -426.526394)
			(xy 62.560564 -426.545432) (xy 62.507318 -426.557011) (xy 62.452967 -426.560893) (xy 62.398616 -426.557001)
			(xy 62.345373 -426.545414) (xy 62.29432 -426.526366) (xy 62.246498 -426.500247) (xy 62.224412 -426.484288)
			(xy 62.2054 -426.470692) (xy 62.163517 -426.44996) (xy 62.118549 -426.437234) (xy 62.072012 -426.432944)
			(xy 62.025475 -426.437234) (xy 61.980507 -426.44996) (xy 61.938624 -426.470692) (xy 61.919612 -426.484288)
			(xy 61.897542 -426.500276) (xy 61.849715 -426.526401) (xy 61.798656 -426.545453) (xy 61.745405 -426.557045)
			(xy 61.691047 -426.56094) (xy 61.636688 -426.557058) (xy 61.583434 -426.54548) (xy 61.53237 -426.52644)
			(xy 61.484537 -426.500327) (xy 61.440906 -426.467671) (xy 61.402367 -426.429138) (xy 61.369705 -426.385513)
			(xy 61.343584 -426.337683) (xy 61.324537 -426.286622) (xy 61.31295 -426.233371) (xy 61.30906 -426.179012)
			(xy 60.930884 -426.179012) (xy 60.926995 -426.233361) (xy 60.915411 -426.286603) (xy 60.896367 -426.337654)
			(xy 60.870252 -426.385476) (xy 60.837597 -426.429094) (xy 60.799067 -426.467621) (xy 60.755445 -426.500272)
			(xy 60.707621 -426.526382) (xy 60.656568 -426.545421) (xy 60.603325 -426.557) (xy 60.548976 -426.560884)
			(xy 60.494627 -426.556993) (xy 60.441386 -426.545407) (xy 60.390335 -426.526362) (xy 60.342514 -426.500246)
			(xy 60.320428 -426.484288) (xy 60.301416 -426.470692) (xy 60.259533 -426.44996) (xy 60.214565 -426.437234)
			(xy 60.168028 -426.432944) (xy 60.121491 -426.437234) (xy 60.076523 -426.44996) (xy 60.03464 -426.470692)
			(xy 60.015628 -426.484288) (xy 59.993558 -426.500277) (xy 59.945729 -426.526405) (xy 59.894669 -426.54546)
			(xy 59.841416 -426.557053) (xy 59.787056 -426.560949) (xy 59.732694 -426.557069) (xy 59.679438 -426.545491)
			(xy 59.628373 -426.526452) (xy 59.580536 -426.500338) (xy 59.536904 -426.467682) (xy 59.498363 -426.429148)
			(xy 59.465699 -426.385521) (xy 59.439577 -426.337689) (xy 59.420528 -426.286627) (xy 59.408941 -426.233373)
			(xy 59.405051 -426.179012) (xy 58.689909 -426.179012) (xy 58.686019 -426.233366) (xy 58.674434 -426.286614)
			(xy 58.655387 -426.337671) (xy 58.629269 -426.385497) (xy 58.596609 -426.429119) (xy 58.558073 -426.467648)
			(xy 58.514446 -426.500301) (xy 58.466616 -426.526412) (xy 58.415556 -426.545451) (xy 58.362307 -426.557028)
			(xy 58.307952 -426.560909) (xy 58.253598 -426.557014) (xy 58.200351 -426.545424) (xy 58.149297 -426.526373)
			(xy 58.101473 -426.500249) (xy 58.079386 -426.484288) (xy 58.060374 -426.470692) (xy 58.018491 -426.44996)
			(xy 57.973523 -426.437234) (xy 57.926986 -426.432944) (xy 57.880449 -426.437234) (xy 57.835481 -426.44996)
			(xy 57.793598 -426.470692) (xy 57.774586 -426.484288) (xy 57.752517 -426.500274) (xy 57.704691 -426.526395)
			(xy 57.653635 -426.545443) (xy 57.600387 -426.557032) (xy 57.546032 -426.560924) (xy 57.491676 -426.557041)
			(xy 57.438427 -426.545462) (xy 57.387367 -426.526421) (xy 57.339537 -426.500308) (xy 57.29591 -426.467654)
			(xy 57.257375 -426.429123) (xy 57.224715 -426.3855) (xy 57.198597 -426.337673) (xy 57.179551 -426.286615)
			(xy 57.167965 -426.233367) (xy 57.164076 -426.179012) (xy 56.803216 -426.179012) (xy 56.799326 -426.233368)
			(xy 56.78774 -426.286617) (xy 56.768693 -426.337675) (xy 56.742573 -426.385503) (xy 56.709912 -426.429126)
			(xy 56.671375 -426.467656) (xy 56.627746 -426.500309) (xy 56.579914 -426.526421) (xy 56.528853 -426.545459)
			(xy 56.475602 -426.557036) (xy 56.421245 -426.560916) (xy 56.36689 -426.55702) (xy 56.313642 -426.545428)
			(xy 56.262586 -426.526375) (xy 56.214761 -426.50025) (xy 56.192674 -426.484288) (xy 56.173662 -426.470692)
			(xy 56.131779 -426.44996) (xy 56.086811 -426.437234) (xy 56.040274 -426.432944) (xy 55.993737 -426.437234)
			(xy 55.948769 -426.44996) (xy 55.906886 -426.470692) (xy 55.887874 -426.484288) (xy 55.865805 -426.500273)
			(xy 55.81798 -426.526392) (xy 55.766925 -426.545439) (xy 55.713679 -426.557026) (xy 55.659325 -426.560917)
			(xy 55.604971 -426.557033) (xy 55.551723 -426.545453) (xy 55.500666 -426.526413) (xy 55.452837 -426.5003)
			(xy 55.409212 -426.467646) (xy 55.370678 -426.429116) (xy 55.33802 -426.385494) (xy 55.311903 -426.337668)
			(xy 55.292857 -426.286612) (xy 55.281272 -426.233366) (xy 55.277383 -426.179012) (xy 29.254196 -426.179012)
			(xy 29.254196 -427.854094) (xy 55.277407 -427.854094) (xy 55.281295 -427.799744) (xy 55.292879 -427.7465)
			(xy 55.311922 -427.695447) (xy 55.338037 -427.647624) (xy 55.370692 -427.604004) (xy 55.409223 -427.565476)
			(xy 55.452845 -427.532823) (xy 55.50067 -427.506711) (xy 55.551724 -427.487672) (xy 55.604969 -427.476092)
			(xy 55.659319 -427.472207) (xy 55.713669 -427.476097) (xy 55.766912 -427.487683) (xy 55.817965 -427.506727)
			(xy 55.865787 -427.532844) (xy 55.887874 -427.548802) (xy 55.906886 -427.562398) (xy 55.948769 -427.58313)
			(xy 55.993737 -427.595856) (xy 56.040274 -427.600146) (xy 56.086811 -427.595856) (xy 56.131779 -427.58313)
			(xy 56.173662 -427.562398) (xy 56.192674 -427.548802) (xy 56.214753 -427.532826) (xy 56.262581 -427.5067)
			(xy 56.313641 -427.487647) (xy 56.366892 -427.476055) (xy 56.421251 -427.47216) (xy 56.475611 -427.476041)
			(xy 56.528866 -427.48762) (xy 56.57993 -427.50666) (xy 56.627764 -427.532774) (xy 56.671395 -427.56543)
			(xy 56.709934 -427.603963) (xy 56.742597 -427.647589) (xy 56.768718 -427.69542) (xy 56.787765 -427.746482)
			(xy 56.799351 -427.799734) (xy 56.80324 -427.854094) (xy 57.1641 -427.854094) (xy 57.167988 -427.799742)
			(xy 57.179572 -427.746497) (xy 57.198616 -427.695443) (xy 57.224732 -427.647618) (xy 57.257389 -427.603997)
			(xy 57.295921 -427.565468) (xy 57.339545 -427.532815) (xy 57.387372 -427.506703) (xy 57.438428 -427.487663)
			(xy 57.491674 -427.476084) (xy 57.546026 -427.4722) (xy 57.600378 -427.476091) (xy 57.653622 -427.487678)
			(xy 57.704676 -427.506725) (xy 57.752499 -427.532843) (xy 57.774586 -427.548802) (xy 57.793598 -427.562398)
			(xy 57.835481 -427.58313) (xy 57.880449 -427.595856) (xy 57.926986 -427.600146) (xy 57.973523 -427.595856)
			(xy 58.018491 -427.58313) (xy 58.060374 -427.562398) (xy 58.079386 -427.548802) (xy 58.101465 -427.532827)
			(xy 58.149292 -427.506703) (xy 58.20035 -427.487652) (xy 58.2536 -427.476061) (xy 58.307958 -427.472167)
			(xy 58.362316 -427.476049) (xy 58.415569 -427.487628) (xy 58.466631 -427.506668) (xy 58.514464 -427.532782)
			(xy 58.558093 -427.565438) (xy 58.596631 -427.60397) (xy 58.629292 -427.647595) (xy 58.655412 -427.695425)
			(xy 58.674458 -427.746485) (xy 58.686044 -427.799736) (xy 58.689933 -427.854094) (xy 59.405075 -427.854094)
			(xy 59.408964 -427.799736) (xy 59.420549 -427.746486) (xy 59.439596 -427.695426) (xy 59.465716 -427.647597)
			(xy 59.498377 -427.603972) (xy 59.536915 -427.56544) (xy 59.580544 -427.532786) (xy 59.628377 -427.506673)
			(xy 59.679439 -427.487634) (xy 59.732692 -427.476056) (xy 59.78705 -427.472175) (xy 59.841407 -427.47607)
			(xy 59.894656 -427.487662) (xy 59.945714 -427.506714) (xy 59.99354 -427.53284) (xy 60.015628 -427.548802)
			(xy 60.03464 -427.562398) (xy 60.076523 -427.58313) (xy 60.121491 -427.595856) (xy 60.168028 -427.600146)
			(xy 60.214565 -427.595856) (xy 60.259533 -427.58313) (xy 60.301416 -427.562398) (xy 60.320428 -427.548802)
			(xy 60.342506 -427.532831) (xy 60.39033 -427.506713) (xy 60.441385 -427.487668) (xy 60.49463 -427.476082)
			(xy 60.548982 -427.472192) (xy 60.603334 -427.476077) (xy 60.656581 -427.487658) (xy 60.707637 -427.506698)
			(xy 60.755463 -427.532811) (xy 60.799087 -427.565465) (xy 60.837619 -427.603995) (xy 60.870276 -427.647616)
			(xy 60.896392 -427.695441) (xy 60.915435 -427.746496) (xy 60.927019 -427.799742) (xy 60.930908 -427.854094)
			(xy 61.309084 -427.854094) (xy 61.312973 -427.799739) (xy 61.324558 -427.74649) (xy 61.343604 -427.695432)
			(xy 61.369722 -427.647605) (xy 61.402382 -427.603982) (xy 61.440917 -427.565451) (xy 61.484544 -427.532797)
			(xy 61.532375 -427.506684) (xy 61.583435 -427.487645) (xy 61.636685 -427.476066) (xy 61.691041 -427.472184)
			(xy 61.745396 -427.476078) (xy 61.798643 -427.487668) (xy 61.849699 -427.506718) (xy 61.897524 -427.532841)
			(xy 61.919612 -427.548802) (xy 61.938624 -427.562398) (xy 61.980507 -427.58313) (xy 62.025475 -427.595856)
			(xy 62.072012 -427.600146) (xy 62.118549 -427.595856) (xy 62.163517 -427.58313) (xy 62.2054 -427.562398)
			(xy 62.224412 -427.548802) (xy 62.246491 -427.53283) (xy 62.294316 -427.506709) (xy 62.345372 -427.487662)
			(xy 62.398619 -427.476074) (xy 62.452973 -427.472183) (xy 62.507327 -427.476066) (xy 62.560576 -427.487646)
			(xy 62.611635 -427.506687) (xy 62.659464 -427.5328) (xy 62.703089 -427.565455) (xy 62.741624 -427.603986)
			(xy 62.774282 -427.647608) (xy 62.800399 -427.695435) (xy 62.819444 -427.746492) (xy 62.831029 -427.79974)
			(xy 62.834917 -427.854094) (xy 62.831031 -427.908448) (xy 62.819448 -427.961696) (xy 62.800404 -428.012754)
			(xy 62.774288 -428.060582) (xy 62.741631 -428.104205) (xy 62.703098 -428.142738) (xy 62.659474 -428.175393)
			(xy 62.611646 -428.201508) (xy 62.560588 -428.22055) (xy 62.507339 -428.232132) (xy 62.452985 -428.236017)
			(xy 62.398631 -428.232128) (xy 62.345383 -428.220542) (xy 62.294327 -428.201496) (xy 62.246501 -428.175377)
			(xy 62.224412 -428.159418) (xy 62.2054 -428.145822) (xy 62.163517 -428.12509) (xy 62.118549 -428.112364)
			(xy 62.072012 -428.108074) (xy 62.025475 -428.112364) (xy 61.980507 -428.12509) (xy 61.938624 -428.145822)
			(xy 61.919612 -428.159418) (xy 61.897514 -428.175365) (xy 61.849688 -428.201487) (xy 61.798632 -428.220536)
			(xy 61.745384 -428.232124) (xy 61.691029 -428.236016) (xy 61.636673 -428.232132) (xy 61.583424 -428.220552)
			(xy 61.532364 -428.201511) (xy 61.484534 -428.175397) (xy 61.440908 -428.142741) (xy 61.402374 -428.104209)
			(xy 61.369716 -428.060585) (xy 61.343599 -428.012757) (xy 61.324555 -427.961698) (xy 61.312971 -427.908449)
			(xy 61.309084 -427.854094) (xy 60.930908 -427.854094) (xy 60.927021 -427.908446) (xy 60.915439 -427.961692)
			(xy 60.896397 -428.012748) (xy 60.870282 -428.060574) (xy 60.837627 -428.104196) (xy 60.799096 -428.142727)
			(xy 60.755473 -428.175382) (xy 60.707648 -428.201497) (xy 60.656592 -428.220539) (xy 60.603346 -428.232121)
			(xy 60.548994 -428.236008) (xy 60.494642 -428.232119) (xy 60.441396 -428.220535) (xy 60.390341 -428.201492)
			(xy 60.342516 -428.175376) (xy 60.320428 -428.159418) (xy 60.301416 -428.145822) (xy 60.259533 -428.12509)
			(xy 60.214565 -428.112364) (xy 60.168028 -428.108074) (xy 60.121491 -428.112364) (xy 60.076523 -428.12509)
			(xy 60.03464 -428.145822) (xy 60.015628 -428.159418) (xy 59.99353 -428.175367) (xy 59.945703 -428.201491)
			(xy 59.894645 -428.220542) (xy 59.841395 -428.232132) (xy 59.787038 -428.236025) (xy 59.73268 -428.232143)
			(xy 59.679428 -428.220563) (xy 59.628366 -428.201522) (xy 59.580534 -428.175408) (xy 59.536906 -428.142752)
			(xy 59.498369 -428.104218) (xy 59.465709 -428.060593) (xy 59.439591 -428.012763) (xy 59.420546 -427.961703)
			(xy 59.408962 -427.908452) (xy 59.405075 -427.854094) (xy 58.689933 -427.854094) (xy 58.686046 -427.908452)
			(xy 58.674462 -427.961703) (xy 58.655417 -428.012764) (xy 58.629299 -428.060594) (xy 58.596639 -428.104221)
			(xy 58.558103 -428.142755) (xy 58.514474 -428.175412) (xy 58.466642 -428.201527) (xy 58.41558 -428.220569)
			(xy 58.362328 -428.232149) (xy 58.30797 -428.236033) (xy 58.253612 -428.232141) (xy 58.200362 -428.220552)
			(xy 58.149303 -428.201502) (xy 58.101475 -428.175379) (xy 58.079386 -428.159418) (xy 58.060374 -428.145822)
			(xy 58.018491 -428.12509) (xy 57.973523 -428.112364) (xy 57.926986 -428.108074) (xy 57.880449 -428.112364)
			(xy 57.835481 -428.12509) (xy 57.793598 -428.145822) (xy 57.774586 -428.159418) (xy 57.752489 -428.175363)
			(xy 57.704665 -428.20148) (xy 57.653611 -428.220525) (xy 57.600366 -428.232111) (xy 57.546014 -428.236)
			(xy 57.491662 -428.232115) (xy 57.438416 -428.220533) (xy 57.387361 -428.201492) (xy 57.339535 -428.175378)
			(xy 57.295912 -428.142724) (xy 57.257381 -428.104194) (xy 57.224726 -428.060572) (xy 57.198611 -428.012747)
			(xy 57.179569 -427.961691) (xy 57.167986 -427.908446) (xy 57.1641 -427.854094) (xy 56.80324 -427.854094)
			(xy 56.799353 -427.908454) (xy 56.787768 -427.961707) (xy 56.768723 -428.012769) (xy 56.742603 -428.0606)
			(xy 56.709942 -428.104228) (xy 56.671404 -428.142762) (xy 56.627775 -428.17542) (xy 56.579941 -428.201535)
			(xy 56.528877 -428.220577) (xy 56.475623 -428.232157) (xy 56.421263 -428.23604) (xy 56.366904 -428.232147)
			(xy 56.313652 -428.220556) (xy 56.262592 -428.201505) (xy 56.214763 -428.17538) (xy 56.192674 -428.159418)
			(xy 56.173662 -428.145822) (xy 56.131779 -428.12509) (xy 56.086811 -428.112364) (xy 56.040274 -428.108074)
			(xy 55.993737 -428.112364) (xy 55.948769 -428.12509) (xy 55.906886 -428.145822) (xy 55.887874 -428.159418)
			(xy 55.865777 -428.175362) (xy 55.817954 -428.201478) (xy 55.766901 -428.220521) (xy 55.713657 -428.232105)
			(xy 55.659307 -428.235993) (xy 55.604957 -428.232107) (xy 55.551713 -428.220525) (xy 55.500659 -428.201484)
			(xy 55.452835 -428.17537) (xy 55.409214 -428.142716) (xy 55.370685 -428.104187) (xy 55.338031 -428.060566)
			(xy 55.311917 -428.012742) (xy 55.292875 -427.961688) (xy 55.281294 -427.908444) (xy 55.277407 -427.854094)
			(xy 29.254196 -427.854094) (xy 29.254196 -429.865311) (xy 55.233845 -429.865311) (xy 55.237732 -429.810948)
			(xy 55.249317 -429.757692) (xy 55.268363 -429.706627) (xy 55.294483 -429.658793) (xy 55.327146 -429.615163)
			(xy 55.365686 -429.576627) (xy 55.409318 -429.543967) (xy 55.457154 -429.517851) (xy 55.50822 -429.498808)
			(xy 55.561477 -429.487228) (xy 55.61584 -429.483345) (xy 55.670202 -429.487239) (xy 55.723456 -429.498831)
			(xy 55.774519 -429.517884) (xy 55.82235 -429.544011) (xy 55.84444 -429.559974) (xy 55.863452 -429.57357)
			(xy 55.905335 -429.594302) (xy 55.950303 -429.607028) (xy 55.99684 -429.611318) (xy 56.043377 -429.607028)
			(xy 56.088345 -429.594302) (xy 56.130228 -429.57357) (xy 56.14924 -429.559974) (xy 56.171344 -429.544042)
			(xy 56.219166 -429.51793) (xy 56.270217 -429.498889) (xy 56.323458 -429.487308) (xy 56.377806 -429.483422)
			(xy 56.432153 -429.48731) (xy 56.485394 -429.498892) (xy 56.536444 -429.517934) (xy 56.584265 -429.544048)
			(xy 56.627883 -429.576701) (xy 56.66641 -429.615229) (xy 56.699061 -429.658849) (xy 56.725172 -429.706671)
			(xy 56.744212 -429.757722) (xy 56.755793 -429.810963) (xy 56.759678 -429.865311) (xy 57.120698 -429.865311)
			(xy 57.124584 -429.81096) (xy 57.136165 -429.757716) (xy 57.155205 -429.706662) (xy 57.181318 -429.658837)
			(xy 57.213971 -429.615215) (xy 57.252499 -429.576684) (xy 57.296119 -429.544029) (xy 57.343943 -429.517914)
			(xy 57.394996 -429.49887) (xy 57.44824 -429.487286) (xy 57.50259 -429.483398) (xy 57.55694 -429.487284)
			(xy 57.610185 -429.498865) (xy 57.661239 -429.517905) (xy 57.709064 -429.544018) (xy 57.731152 -429.559974)
			(xy 57.750164 -429.57357) (xy 57.792047 -429.594302) (xy 57.837015 -429.607028) (xy 57.883552 -429.611318)
			(xy 57.930089 -429.607028) (xy 57.975057 -429.594302) (xy 58.01694 -429.57357) (xy 58.035952 -429.559974)
			(xy 58.058058 -429.544034) (xy 58.105886 -429.517908) (xy 58.156945 -429.498855) (xy 58.210196 -429.487264)
			(xy 58.264555 -429.483369) (xy 58.318915 -429.487251) (xy 58.372169 -429.49883) (xy 58.423233 -429.517871)
			(xy 58.471067 -429.543986) (xy 58.514697 -429.576643) (xy 58.553235 -429.615178) (xy 58.585896 -429.658805)
			(xy 58.612015 -429.706636) (xy 58.63106 -429.757698) (xy 58.642644 -429.810951) (xy 58.646531 -429.865311)
			(xy 59.361673 -429.865311) (xy 59.365559 -429.810955) (xy 59.377142 -429.757705) (xy 59.396185 -429.706645)
			(xy 59.422301 -429.658816) (xy 59.454959 -429.61519) (xy 59.493493 -429.576657) (xy 59.537119 -429.544)
			(xy 59.584948 -429.517884) (xy 59.636008 -429.498841) (xy 59.689258 -429.487258) (xy 59.743614 -429.483373)
			(xy 59.79797 -429.487262) (xy 59.851219 -429.498849) (xy 59.902277 -429.517895) (xy 59.950105 -429.544015)
			(xy 59.972194 -429.559974) (xy 59.991206 -429.57357) (xy 60.033089 -429.594302) (xy 60.078057 -429.607028)
			(xy 60.124594 -429.611318) (xy 60.171131 -429.607028) (xy 60.216099 -429.594302) (xy 60.257982 -429.57357)
			(xy 60.276994 -429.559974) (xy 60.299099 -429.544038) (xy 60.346924 -429.517918) (xy 60.397979 -429.498872)
			(xy 60.451226 -429.487285) (xy 60.505579 -429.483394) (xy 60.559933 -429.487279) (xy 60.613181 -429.49886)
			(xy 60.664238 -429.517901) (xy 60.712066 -429.544015) (xy 60.75569 -429.576671) (xy 60.794223 -429.615202)
			(xy 60.826879 -429.658826) (xy 60.852995 -429.706653) (xy 60.872037 -429.75771) (xy 60.88362 -429.810957)
			(xy 60.887506 -429.865311) (xy 61.265682 -429.865311) (xy 61.269568 -429.810957) (xy 61.28115 -429.757709)
			(xy 61.300193 -429.706652) (xy 61.326308 -429.658824) (xy 61.358963 -429.6152) (xy 61.397495 -429.576667)
			(xy 61.441119 -429.544011) (xy 61.488946 -429.517895) (xy 61.540003 -429.498852) (xy 61.593251 -429.487269)
			(xy 61.647605 -429.483382) (xy 61.701959 -429.48727) (xy 61.755206 -429.498855) (xy 61.806263 -429.517899)
			(xy 61.854089 -429.544016) (xy 61.876178 -429.559974) (xy 61.89519 -429.57357) (xy 61.937073 -429.594302)
			(xy 61.982041 -429.607028) (xy 62.028578 -429.611318) (xy 62.075115 -429.607028) (xy 62.120083 -429.594302)
			(xy 62.161966 -429.57357) (xy 62.180978 -429.559974) (xy 62.203084 -429.544036) (xy 62.25091 -429.517915)
			(xy 62.301966 -429.498865) (xy 62.355215 -429.487277) (xy 62.40957 -429.483385) (xy 62.463926 -429.487268)
			(xy 62.517177 -429.498849) (xy 62.568236 -429.51789) (xy 62.616066 -429.544004) (xy 62.659693 -429.57666)
			(xy 62.698227 -429.615193) (xy 62.730885 -429.658818) (xy 62.757002 -429.706646) (xy 62.776046 -429.757705)
			(xy 62.787629 -429.810955) (xy 62.791515 -429.865311) (xy 62.787626 -429.919667) (xy 62.77604 -429.972915)
			(xy 62.756993 -430.023973) (xy 62.730874 -430.0718) (xy 62.698213 -430.115423) (xy 62.663869 -430.149762)
			(xy 72.868035 -430.149762) (xy 72.872042 -429.947012) (xy 72.884055 -429.744578) (xy 72.904056 -429.542777)
			(xy 72.932015 -429.341923) (xy 72.967886 -429.142331) (xy 73.011615 -428.944312) (xy 73.063133 -428.748175)
			(xy 73.122359 -428.554227) (xy 73.189201 -428.362769) (xy 73.263555 -428.174102) (xy 73.345304 -427.98852)
			(xy 73.434322 -427.806312) (xy 73.530468 -427.627763) (xy 73.633593 -427.453152) (xy 73.743536 -427.282752)
			(xy 73.860125 -427.116828) (xy 73.983178 -426.955639) (xy 74.112503 -426.799438) (xy 74.247898 -426.648468)
			(xy 74.389151 -426.502964) (xy 74.536043 -426.363155) (xy 74.688343 -426.229258) (xy 74.845814 -426.101483)
			(xy 75.008211 -425.980028) (xy 75.175278 -425.865084) (xy 75.346757 -425.75683) (xy 75.522378 -425.655435)
			(xy 75.701868 -425.561057) (xy 75.884946 -425.473845) (xy 76.071327 -425.393933) (xy 76.26072 -425.321446)
			(xy 76.452828 -425.256499) (xy 76.647352 -425.199191) (xy 76.843988 -425.149614) (xy 77.04243 -425.107843)
			(xy 77.242367 -425.073945) (xy 77.443486 -425.047973) (xy 77.645475 -425.029966) (xy 77.848018 -425.019953)
			(xy 78.050798 -425.017949) (xy 78.253499 -425.023959) (xy 78.455804 -425.037971) (xy 78.657398 -425.059966)
			(xy 78.857965 -425.089907) (xy 79.057193 -425.127748) (xy 79.254771 -425.173431) (xy 79.450389 -425.226884)
			(xy 79.643743 -425.288023) (xy 79.834531 -425.356754) (xy 80.022454 -425.432968) (xy 80.20722 -425.516547)
			(xy 80.388539 -425.60736) (xy 80.56613 -425.705265) (xy 80.739713 -425.81011) (xy 80.909019 -425.921731)
			(xy 81.073784 -426.039953) (xy 81.233749 -426.164593) (xy 81.388665 -426.295454) (xy 81.53829 -426.432334)
			(xy 81.68239 -426.575018) (xy 81.820742 -426.723284) (xy 81.953127 -426.8769) (xy 82.079341 -427.035625)
			(xy 82.199185 -427.199214) (xy 82.312473 -427.367409) (xy 82.419028 -427.539948) (xy 82.518683 -427.716563)
			(xy 82.611283 -427.896976) (xy 82.696683 -428.080907) (xy 82.77475 -428.268068) (xy 82.845362 -428.458168)
			(xy 82.908408 -428.650908) (xy 82.963791 -428.845989) (xy 83.011423 -429.043106) (xy 83.051231 -429.24195)
			(xy 83.083153 -429.442212) (xy 83.107137 -429.643578) (xy 83.123148 -429.845735) (xy 83.131159 -430.048367)
			(xy 83.13166 -430.149762) (xy 83.131159 -430.251157) (xy 83.123148 -430.453789) (xy 83.107137 -430.655946)
			(xy 83.083153 -430.857312) (xy 83.051231 -431.057574) (xy 83.011423 -431.256418) (xy 82.963791 -431.453535)
			(xy 82.908408 -431.648616) (xy 82.845362 -431.841356) (xy 82.77475 -432.031456) (xy 82.696683 -432.218617)
			(xy 82.611283 -432.402548) (xy 82.518683 -432.582961) (xy 82.419028 -432.759576) (xy 82.312473 -432.932115)
			(xy 82.199185 -433.10031) (xy 82.079341 -433.263899) (xy 81.953127 -433.422624) (xy 81.820742 -433.57624)
			(xy 81.68239 -433.724506) (xy 81.53829 -433.86719) (xy 81.388665 -434.00407) (xy 81.233749 -434.134931)
			(xy 81.073784 -434.259571) (xy 80.909019 -434.377793) (xy 80.739713 -434.489414) (xy 80.56613 -434.594259)
			(xy 80.388539 -434.692164) (xy 80.20722 -434.782977) (xy 80.022454 -434.866556) (xy 79.834531 -434.94277)
			(xy 79.643743 -435.011501) (xy 79.450389 -435.07264) (xy 79.254771 -435.126093) (xy 79.057193 -435.171776)
			(xy 78.857965 -435.209617) (xy 78.657398 -435.239558) (xy 78.455804 -435.261553) (xy 78.253499 -435.275565)
			(xy 78.050798 -435.281575) (xy 77.848018 -435.279571) (xy 77.645475 -435.269558) (xy 77.443486 -435.251551)
			(xy 77.242367 -435.225579) (xy 77.04243 -435.191681) (xy 76.843988 -435.14991) (xy 76.647352 -435.100333)
			(xy 76.452828 -435.043025) (xy 76.26072 -434.978078) (xy 76.071327 -434.905591) (xy 75.884946 -434.825679)
			(xy 75.701868 -434.738467) (xy 75.522378 -434.644089) (xy 75.346757 -434.542694) (xy 75.175278 -434.43444)
			(xy 75.008211 -434.319496) (xy 74.845814 -434.198041) (xy 74.688343 -434.070266) (xy 74.536043 -433.936369)
			(xy 74.389151 -433.79656) (xy 74.247898 -433.651056) (xy 74.112503 -433.500086) (xy 73.983178 -433.343885)
			(xy 73.860125 -433.182696) (xy 73.743536 -433.016772) (xy 73.633593 -432.846372) (xy 73.530468 -432.671761)
			(xy 73.434322 -432.493212) (xy 73.345304 -432.311004) (xy 73.263555 -432.125422) (xy 73.189201 -431.936755)
			(xy 73.122359 -431.745297) (xy 73.063133 -431.551349) (xy 73.011615 -431.355212) (xy 72.967886 -431.157193)
			(xy 72.932015 -430.957601) (xy 72.904056 -430.756747) (xy 72.884055 -430.554946) (xy 72.872042 -430.352512)
			(xy 72.868035 -430.149762) (xy 62.663869 -430.149762) (xy 62.659676 -430.153954) (xy 62.616048 -430.186607)
			(xy 62.568217 -430.212719) (xy 62.517156 -430.231757) (xy 62.463905 -430.243335) (xy 62.409549 -430.247215)
			(xy 62.355193 -430.24332) (xy 62.301946 -430.231728) (xy 62.25089 -430.212676) (xy 62.203065 -430.186552)
			(xy 62.180978 -430.17059) (xy 62.161966 -430.156994) (xy 62.120083 -430.136262) (xy 62.075115 -430.123536)
			(xy 62.028578 -430.119246) (xy 61.982041 -430.123536) (xy 61.937073 -430.136262) (xy 61.89519 -430.156994)
			(xy 61.876178 -430.17059) (xy 61.854107 -430.186572) (xy 61.806282 -430.212692) (xy 61.755227 -430.231739)
			(xy 61.70198 -430.243326) (xy 61.647626 -430.247218) (xy 61.593272 -430.243334) (xy 61.540024 -430.231754)
			(xy 61.488966 -430.212714) (xy 61.441137 -430.186601) (xy 61.397512 -430.153947) (xy 61.358978 -430.115416)
			(xy 61.326319 -430.071794) (xy 61.300202 -430.023968) (xy 61.281156 -429.972912) (xy 61.269571 -429.919665)
			(xy 61.265682 -429.865311) (xy 60.887506 -429.865311) (xy 60.883617 -429.919664) (xy 60.872031 -429.972911)
			(xy 60.852986 -430.023967) (xy 60.826868 -430.071793) (xy 60.794209 -430.115414) (xy 60.755674 -430.153943)
			(xy 60.712048 -430.186596) (xy 60.664219 -430.212708) (xy 60.61316 -430.231746) (xy 60.559912 -430.243324)
			(xy 60.505558 -430.247206) (xy 60.451204 -430.243312) (xy 60.397959 -430.231722) (xy 60.346904 -430.212673)
			(xy 60.299081 -430.18655) (xy 60.276994 -430.17059) (xy 60.257982 -430.156994) (xy 60.216099 -430.136262)
			(xy 60.171131 -430.123536) (xy 60.124594 -430.119246) (xy 60.078057 -430.123536) (xy 60.033089 -430.136262)
			(xy 59.991206 -430.156994) (xy 59.972194 -430.17059) (xy 59.950123 -430.186574) (xy 59.902297 -430.212696)
			(xy 59.85124 -430.231745) (xy 59.797991 -430.243335) (xy 59.743635 -430.247227) (xy 59.689279 -430.243345)
			(xy 59.636028 -430.231765) (xy 59.584968 -430.212725) (xy 59.537137 -430.186612) (xy 59.493509 -430.153957)
			(xy 59.454973 -430.115426) (xy 59.422313 -430.071802) (xy 59.396194 -430.023974) (xy 59.377148 -429.972916)
			(xy 59.365562 -429.919667) (xy 59.361673 -429.865311) (xy 58.646531 -429.865311) (xy 58.642641 -429.91967)
			(xy 58.631054 -429.972922) (xy 58.612006 -430.023983) (xy 58.585884 -430.071813) (xy 58.553221 -430.115439)
			(xy 58.514681 -430.153971) (xy 58.471049 -430.186626) (xy 58.423213 -430.212738) (xy 58.372149 -430.231776)
			(xy 58.318894 -430.243352) (xy 58.264534 -430.247231) (xy 58.210175 -430.243333) (xy 58.156925 -430.231739)
			(xy 58.105866 -430.212683) (xy 58.05804 -430.186554) (xy 58.035952 -430.17059) (xy 58.01694 -430.156994)
			(xy 57.975057 -430.136262) (xy 57.930089 -430.123536) (xy 57.883552 -430.119246) (xy 57.837015 -430.123536)
			(xy 57.792047 -430.136262) (xy 57.750164 -430.156994) (xy 57.731152 -430.17059) (xy 57.709082 -430.18657)
			(xy 57.661259 -430.212686) (xy 57.610205 -430.231729) (xy 57.556962 -430.243313) (xy 57.502612 -430.247202)
			(xy 57.448261 -430.243317) (xy 57.395017 -430.231736) (xy 57.343962 -430.212695) (xy 57.296138 -430.186583)
			(xy 57.252516 -430.15393) (xy 57.213985 -430.115401) (xy 57.181329 -430.071781) (xy 57.155214 -430.023958)
			(xy 57.136171 -429.972905) (xy 57.124587 -429.919661) (xy 57.120698 -429.865311) (xy 56.759678 -429.865311)
			(xy 56.75579 -429.919658) (xy 56.744206 -429.972899) (xy 56.725163 -430.023949) (xy 56.699049 -430.07177)
			(xy 56.666396 -430.115387) (xy 56.627867 -430.153913) (xy 56.584247 -430.186564) (xy 56.536425 -430.212675)
			(xy 56.485373 -430.231714) (xy 56.432131 -430.243293) (xy 56.377784 -430.247178) (xy 56.323437 -430.243289)
			(xy 56.270196 -430.231705) (xy 56.219146 -430.212661) (xy 56.171326 -430.186547) (xy 56.14924 -430.17059)
			(xy 56.130228 -430.156994) (xy 56.088345 -430.136262) (xy 56.043377 -430.123536) (xy 55.99684 -430.119246)
			(xy 55.950303 -430.123536) (xy 55.905335 -430.136262) (xy 55.863452 -430.156994) (xy 55.84444 -430.17059)
			(xy 55.822368 -430.186578) (xy 55.774538 -430.212707) (xy 55.723477 -430.231763) (xy 55.670223 -430.243358)
			(xy 55.615862 -430.247255) (xy 55.561499 -430.243375) (xy 55.508241 -430.231798) (xy 55.457174 -430.212758)
			(xy 55.409336 -430.186644) (xy 55.365702 -430.153987) (xy 55.32716 -430.115453) (xy 55.294495 -430.071825)
			(xy 55.268372 -430.023992) (xy 55.249323 -429.972928) (xy 55.237735 -429.919673) (xy 55.233845 -429.865311)
			(xy 29.254196 -429.865311) (xy 29.254196 -431.755798) (xy 55.233863 -431.755798) (xy 55.237751 -431.701438)
			(xy 55.249337 -431.648185) (xy 55.268384 -431.597123) (xy 55.294505 -431.549292) (xy 55.327168 -431.505665)
			(xy 55.365707 -431.467131) (xy 55.409338 -431.434475) (xy 55.457173 -431.408361) (xy 55.508238 -431.389321)
			(xy 55.561493 -431.377743) (xy 55.615853 -431.373863) (xy 55.670213 -431.377759) (xy 55.723464 -431.389351)
			(xy 55.774523 -431.408405) (xy 55.822351 -431.434533) (xy 55.84444 -431.450496) (xy 55.863452 -431.464092)
			(xy 55.905335 -431.484824) (xy 55.950303 -431.49755) (xy 55.99684 -431.50184) (xy 56.043377 -431.49755)
			(xy 56.088345 -431.484824) (xy 56.130228 -431.464092) (xy 56.14924 -431.450496) (xy 56.171323 -431.434534)
			(xy 56.219146 -431.408419) (xy 56.270199 -431.389376) (xy 56.323442 -431.377793) (xy 56.377792 -431.373904)
			(xy 56.432142 -431.37779) (xy 56.485386 -431.389372) (xy 56.53644 -431.408413) (xy 56.584264 -431.434526)
			(xy 56.627885 -431.467179) (xy 56.666414 -431.505708) (xy 56.699069 -431.549328) (xy 56.725183 -431.597151)
			(xy 56.744225 -431.648204) (xy 56.755808 -431.701448) (xy 56.759696 -431.755798) (xy 57.120715 -431.755798)
			(xy 57.124603 -431.70145) (xy 57.136185 -431.648208) (xy 57.155227 -431.597157) (xy 57.18134 -431.549335)
			(xy 57.213993 -431.505717) (xy 57.252521 -431.467189) (xy 57.29614 -431.434537) (xy 57.343962 -431.408424)
			(xy 57.395014 -431.389384) (xy 57.448255 -431.377802) (xy 57.502603 -431.373915) (xy 57.556951 -431.377803)
			(xy 57.610192 -431.389385) (xy 57.661244 -431.408427) (xy 57.709065 -431.43454) (xy 57.731152 -431.450496)
			(xy 57.750164 -431.464092) (xy 57.792047 -431.484824) (xy 57.837015 -431.49755) (xy 57.883552 -431.50184)
			(xy 57.930089 -431.49755) (xy 57.975057 -431.484824) (xy 58.01694 -431.464092) (xy 58.035952 -431.450496)
			(xy 58.058038 -431.434527) (xy 58.105867 -431.408398) (xy 58.156928 -431.389342) (xy 58.210181 -431.377748)
			(xy 58.264542 -431.373852) (xy 58.318905 -431.377732) (xy 58.372162 -431.38931) (xy 58.423228 -431.40835)
			(xy 58.471065 -431.434464) (xy 58.514698 -431.467121) (xy 58.553239 -431.505656) (xy 58.585903 -431.549284)
			(xy 58.612025 -431.597117) (xy 58.631073 -431.648181) (xy 58.64266 -431.701436) (xy 58.646548 -431.755798)
			(xy 59.36169 -431.755798) (xy 59.365578 -431.701444) (xy 59.377162 -431.648197) (xy 59.396206 -431.597141)
			(xy 59.422323 -431.549314) (xy 59.454981 -431.505692) (xy 59.493514 -431.467162) (xy 59.537139 -431.434507)
			(xy 59.584967 -431.408394) (xy 59.636025 -431.389354) (xy 59.689273 -431.377774) (xy 59.743627 -431.37389)
			(xy 59.79798 -431.377782) (xy 59.851227 -431.389369) (xy 59.902282 -431.408417) (xy 59.950106 -431.434537)
			(xy 59.972194 -431.450496) (xy 59.991206 -431.464092) (xy 60.033089 -431.484824) (xy 60.078057 -431.49755)
			(xy 60.124594 -431.50184) (xy 60.171131 -431.49755) (xy 60.216099 -431.484824) (xy 60.257982 -431.464092)
			(xy 60.276994 -431.450496) (xy 60.299079 -431.43453) (xy 60.346905 -431.408408) (xy 60.397962 -431.389358)
			(xy 60.45121 -431.377769) (xy 60.505566 -431.373877) (xy 60.559923 -431.37776) (xy 60.613173 -431.389339)
			(xy 60.664234 -431.40838) (xy 60.712064 -431.434494) (xy 60.755692 -431.467149) (xy 60.794227 -431.505681)
			(xy 60.826887 -431.549305) (xy 60.853005 -431.597133) (xy 60.87205 -431.648192) (xy 60.883635 -431.701441)
			(xy 60.887523 -431.755798) (xy 61.2657 -431.755798) (xy 61.269588 -431.701446) (xy 61.281171 -431.648201)
			(xy 61.300214 -431.597147) (xy 61.32633 -431.549322) (xy 61.358985 -431.505701) (xy 61.397517 -431.467172)
			(xy 61.44114 -431.434519) (xy 61.488965 -431.408406) (xy 61.540021 -431.389365) (xy 61.593266 -431.377785)
			(xy 61.647618 -431.3739) (xy 61.701969 -431.37779) (xy 61.755214 -431.389375) (xy 61.806267 -431.408421)
			(xy 61.854091 -431.434538) (xy 61.876178 -431.450496) (xy 61.89519 -431.464092) (xy 61.937073 -431.484824)
			(xy 61.982041 -431.49755) (xy 62.028578 -431.50184) (xy 62.075115 -431.49755) (xy 62.120083 -431.484824)
			(xy 62.161966 -431.464092) (xy 62.180978 -431.450496) (xy 62.203063 -431.434529) (xy 62.25089 -431.408404)
			(xy 62.301949 -431.389352) (xy 62.355199 -431.377761) (xy 62.409557 -431.373867) (xy 62.463916 -431.377749)
			(xy 62.517169 -431.389328) (xy 62.568232 -431.408368) (xy 62.616065 -431.434482) (xy 62.659694 -431.467138)
			(xy 62.698232 -431.505671) (xy 62.730893 -431.549297) (xy 62.757013 -431.597127) (xy 62.776059 -431.648188)
			(xy 62.787645 -431.701439) (xy 62.791533 -431.755798) (xy 62.787645 -431.810156) (xy 62.776061 -431.863408)
			(xy 62.757015 -431.914469) (xy 62.730896 -431.962299) (xy 62.698235 -432.005925) (xy 62.659698 -432.044459)
			(xy 62.616069 -432.077115) (xy 62.568236 -432.10323) (xy 62.517173 -432.122271) (xy 62.463921 -432.13385)
			(xy 62.409562 -432.137733) (xy 62.355204 -432.133839) (xy 62.301953 -432.122249) (xy 62.250895 -432.103198)
			(xy 62.203067 -432.077074) (xy 62.180978 -432.061112) (xy 62.161966 -432.047516) (xy 62.120083 -432.026784)
			(xy 62.075115 -432.014058) (xy 62.028578 -432.009768) (xy 61.982041 -432.014058) (xy 61.937073 -432.026784)
			(xy 61.89519 -432.047516) (xy 61.876178 -432.061112) (xy 61.854087 -432.077065) (xy 61.806263 -432.103181)
			(xy 61.755209 -432.122226) (xy 61.701964 -432.133811) (xy 61.647613 -432.1377) (xy 61.593262 -432.133815)
			(xy 61.540016 -432.122233) (xy 61.488961 -432.103192) (xy 61.441135 -432.077079) (xy 61.397513 -432.044425)
			(xy 61.358982 -432.005895) (xy 61.326327 -431.962274) (xy 61.300212 -431.914449) (xy 61.28117 -431.863394)
			(xy 61.269587 -431.810149) (xy 61.2657 -431.755798) (xy 60.887523 -431.755798) (xy 60.883636 -431.810154)
			(xy 60.872052 -431.863403) (xy 60.853007 -431.914462) (xy 60.826889 -431.962291) (xy 60.794231 -432.005916)
			(xy 60.755695 -432.044448) (xy 60.712069 -432.077104) (xy 60.664238 -432.103218) (xy 60.613178 -432.122259)
			(xy 60.559927 -432.13384) (xy 60.505571 -432.137723) (xy 60.451215 -432.133831) (xy 60.397966 -432.122243)
			(xy 60.346909 -432.103194) (xy 60.299083 -432.077072) (xy 60.276994 -432.061112) (xy 60.257982 -432.047516)
			(xy 60.216099 -432.026784) (xy 60.171131 -432.014058) (xy 60.124594 -432.009768) (xy 60.078057 -432.014058)
			(xy 60.033089 -432.026784) (xy 59.991206 -432.047516) (xy 59.972194 -432.061112) (xy 59.950102 -432.077066)
			(xy 59.902277 -432.103185) (xy 59.851222 -432.122232) (xy 59.797976 -432.133819) (xy 59.743622 -432.13771)
			(xy 59.689268 -432.133825) (xy 59.636021 -432.122245) (xy 59.584963 -432.103204) (xy 59.537135 -432.07709)
			(xy 59.493511 -432.044435) (xy 59.454978 -432.005904) (xy 59.422321 -431.962282) (xy 59.396204 -431.914455)
			(xy 59.377161 -431.863398) (xy 59.365578 -431.810151) (xy 59.36169 -431.755798) (xy 58.646548 -431.755798)
			(xy 58.64266 -431.81016) (xy 58.631075 -431.863415) (xy 58.612027 -431.914479) (xy 58.585906 -431.962312)
			(xy 58.553243 -432.00594) (xy 58.514702 -432.044476) (xy 58.471069 -432.077133) (xy 58.423233 -432.103248)
			(xy 58.372166 -432.122289) (xy 58.31891 -432.133868) (xy 58.264547 -432.137748) (xy 58.210186 -432.133853)
			(xy 58.156932 -432.122259) (xy 58.105871 -432.103204) (xy 58.058042 -432.077076) (xy 58.035952 -432.061112)
			(xy 58.01694 -432.047516) (xy 57.975057 -432.026784) (xy 57.930089 -432.014058) (xy 57.883552 -432.009768)
			(xy 57.837015 -432.014058) (xy 57.792047 -432.026784) (xy 57.750164 -432.047516) (xy 57.731152 -432.061112)
			(xy 57.709061 -432.077062) (xy 57.661239 -432.103175) (xy 57.610188 -432.122216) (xy 57.556946 -432.133798)
			(xy 57.502598 -432.137685) (xy 57.44825 -432.133797) (xy 57.395009 -432.122215) (xy 57.343958 -432.103174)
			(xy 57.296136 -432.077061) (xy 57.252517 -432.044408) (xy 57.21399 -432.00588) (xy 57.181337 -431.962261)
			(xy 57.155225 -431.914439) (xy 57.136184 -431.863387) (xy 57.124602 -431.810146) (xy 57.120715 -431.755798)
			(xy 56.759696 -431.755798) (xy 56.755809 -431.810148) (xy 56.744227 -431.863391) (xy 56.725185 -431.914444)
			(xy 56.699071 -431.962268) (xy 56.666418 -432.005889) (xy 56.627888 -432.044418) (xy 56.584268 -432.077072)
			(xy 56.536444 -432.103185) (xy 56.485391 -432.122227) (xy 56.432147 -432.133809) (xy 56.377797 -432.137696)
			(xy 56.323447 -432.133808) (xy 56.270204 -432.122225) (xy 56.219151 -432.103183) (xy 56.171328 -432.077069)
			(xy 56.14924 -432.061112) (xy 56.130228 -432.047516) (xy 56.088345 -432.026784) (xy 56.043377 -432.014058)
			(xy 55.99684 -432.009768) (xy 55.950303 -432.014058) (xy 55.905335 -432.026784) (xy 55.863452 -432.047516)
			(xy 55.84444 -432.061112) (xy 55.822347 -432.07707) (xy 55.774519 -432.103197) (xy 55.723459 -432.12225)
			(xy 55.670208 -432.133842) (xy 55.615848 -432.137737) (xy 55.561488 -432.133856) (xy 55.508233 -432.122277)
			(xy 55.457169 -432.103237) (xy 55.409334 -432.077122) (xy 55.365703 -432.044466) (xy 55.327165 -432.005931)
			(xy 55.294503 -431.962304) (xy 55.268382 -431.914473) (xy 55.249336 -431.863411) (xy 55.237751 -431.810158)
			(xy 55.233863 -431.755798) (xy 29.254196 -431.755798) (xy 29.254196 -433.796871) (xy 55.233898 -433.796871)
			(xy 55.23779 -433.742517) (xy 55.249378 -433.689269) (xy 55.268427 -433.638213) (xy 55.294549 -433.590388)
			(xy 55.327212 -433.546768) (xy 55.36575 -433.508241) (xy 55.40938 -433.47559) (xy 55.457212 -433.449482)
			(xy 55.508273 -433.430448) (xy 55.561524 -433.418874) (xy 55.61588 -433.414998) (xy 55.670234 -433.418897)
			(xy 55.723479 -433.430493) (xy 55.774533 -433.449548) (xy 55.822354 -433.475677) (xy 55.84444 -433.49164)
			(xy 55.863452 -433.505236) (xy 55.905335 -433.525968) (xy 55.950303 -433.538694) (xy 55.99684 -433.542984)
			(xy 56.043377 -433.538694) (xy 56.088345 -433.525968) (xy 56.130228 -433.505236) (xy 56.14924 -433.49164)
			(xy 56.171282 -433.475619) (xy 56.219108 -433.449498) (xy 56.270164 -433.43045) (xy 56.323411 -433.418861)
			(xy 56.377766 -433.414969) (xy 56.432121 -433.418852) (xy 56.485371 -433.430431) (xy 56.53643 -433.44947)
			(xy 56.58426 -433.475582) (xy 56.627888 -433.508235) (xy 56.666424 -433.546765) (xy 56.699084 -433.590387)
			(xy 56.725204 -433.638213) (xy 56.744252 -433.689269) (xy 56.755839 -433.742517) (xy 56.759731 -433.796871)
			(xy 57.120751 -433.796871) (xy 57.124641 -433.742529) (xy 57.136226 -433.689293) (xy 57.15527 -433.638248)
			(xy 57.181384 -433.590432) (xy 57.214037 -433.54682) (xy 57.252564 -433.508298) (xy 57.296181 -433.475652)
			(xy 57.344001 -433.449545) (xy 57.395049 -433.43051) (xy 57.448286 -433.418933) (xy 57.50263 -433.415051)
			(xy 57.556972 -433.418942) (xy 57.610208 -433.430527) (xy 57.661253 -433.44957) (xy 57.709068 -433.475684)
			(xy 57.731152 -433.49164) (xy 57.750164 -433.505236) (xy 57.792047 -433.525968) (xy 57.837015 -433.538694)
			(xy 57.883552 -433.542984) (xy 57.930089 -433.538694) (xy 57.975057 -433.525968) (xy 58.01694 -433.505236)
			(xy 58.035952 -433.49164) (xy 58.057996 -433.475611) (xy 58.105828 -433.449477) (xy 58.156892 -433.430416)
			(xy 58.21015 -433.418817) (xy 58.264516 -433.414916) (xy 58.318884 -433.418793) (xy 58.372146 -433.430368)
			(xy 58.423219 -433.449407) (xy 58.471062 -433.47552) (xy 58.514702 -433.508177) (xy 58.553249 -433.546713)
			(xy 58.585919 -433.590343) (xy 58.612046 -433.638178) (xy 58.6311 -433.689245) (xy 58.642691 -433.742505)
			(xy 58.646584 -433.796871) (xy 59.361725 -433.796871) (xy 59.365617 -433.742523) (xy 59.377203 -433.689282)
			(xy 59.396249 -433.638231) (xy 59.422367 -433.590411) (xy 59.455025 -433.546795) (xy 59.493557 -433.508271)
			(xy 59.53718 -433.475623) (xy 59.585006 -433.449515) (xy 59.63606 -433.43048) (xy 59.689304 -433.418905)
			(xy 59.743653 -433.415026) (xy 59.798002 -433.41892) (xy 59.851242 -433.43051) (xy 59.902291 -433.44956)
			(xy 59.950109 -433.47568) (xy 59.972194 -433.49164) (xy 59.991206 -433.505236) (xy 60.033089 -433.525968)
			(xy 60.078057 -433.538694) (xy 60.124594 -433.542984) (xy 60.171131 -433.538694) (xy 60.216099 -433.525968)
			(xy 60.257982 -433.505236) (xy 60.276994 -433.49164) (xy 60.299037 -433.475615) (xy 60.346866 -433.449487)
			(xy 60.397927 -433.430432) (xy 60.451179 -433.418838) (xy 60.50554 -433.414941) (xy 60.559902 -433.418821)
			(xy 60.613158 -433.430398) (xy 60.664224 -433.449437) (xy 60.712061 -433.47555) (xy 60.755695 -433.508205)
			(xy 60.794237 -433.546738) (xy 60.826902 -433.590364) (xy 60.853026 -433.638195) (xy 60.872077 -433.689257)
			(xy 60.883666 -433.74251) (xy 60.887559 -433.796871) (xy 61.265735 -433.796871) (xy 61.269626 -433.742525)
			(xy 61.281212 -433.689286) (xy 61.300257 -433.638238) (xy 61.326373 -433.590419) (xy 61.359029 -433.546805)
			(xy 61.39756 -433.508281) (xy 61.441181 -433.475634) (xy 61.489004 -433.449527) (xy 61.540056 -433.430492)
			(xy 61.593297 -433.418916) (xy 61.647644 -433.415035) (xy 61.70199 -433.418928) (xy 61.755229 -433.430517)
			(xy 61.806277 -433.449564) (xy 61.854094 -433.475682) (xy 61.876178 -433.49164) (xy 61.89519 -433.505236)
			(xy 61.937073 -433.525968) (xy 61.982041 -433.538694) (xy 62.028578 -433.542984) (xy 62.075115 -433.538694)
			(xy 62.120083 -433.525968) (xy 62.161966 -433.505236) (xy 62.180978 -433.49164) (xy 62.203022 -433.475613)
			(xy 62.250852 -433.449483) (xy 62.301914 -433.430426) (xy 62.355168 -433.41883) (xy 62.409531 -433.414932)
			(xy 62.463895 -433.41881) (xy 62.517153 -433.430387) (xy 62.568222 -433.449425) (xy 62.616062 -433.475538)
			(xy 62.659697 -433.508194) (xy 62.698241 -433.546728) (xy 62.730908 -433.590356) (xy 62.757034 -433.638188)
			(xy 62.776086 -433.689252) (xy 62.787676 -433.742508) (xy 62.791568 -433.796871) (xy 62.787684 -433.851235)
			(xy 62.776102 -433.904492) (xy 62.757058 -433.955559) (xy 62.73094 -434.003396) (xy 62.698279 -434.047028)
			(xy 62.659741 -434.085568) (xy 62.61611 -434.11823) (xy 62.568275 -434.144351) (xy 62.517209 -434.163397)
			(xy 62.463952 -434.174981) (xy 62.409588 -434.178868) (xy 62.355225 -434.174978) (xy 62.301969 -434.16339)
			(xy 62.250904 -434.144341) (xy 62.20307 -434.118218) (xy 62.180978 -434.102256) (xy 62.161966 -434.08866)
			(xy 62.120083 -434.067928) (xy 62.075115 -434.055202) (xy 62.028578 -434.050912) (xy 61.982041 -434.055202)
			(xy 61.937073 -434.067928) (xy 61.89519 -434.08866) (xy 61.876178 -434.102256) (xy 61.854045 -434.118149)
			(xy 61.806224 -434.14426) (xy 61.755174 -434.1633) (xy 61.701933 -434.17488) (xy 61.647587 -434.178765)
			(xy 61.59324 -434.174876) (xy 61.540001 -434.163292) (xy 61.488952 -434.144249) (xy 61.441132 -434.118135)
			(xy 61.397516 -434.085481) (xy 61.358992 -434.046952) (xy 61.326342 -434.003332) (xy 61.300233 -433.95551)
			(xy 61.281196 -433.904459) (xy 61.269618 -433.851218) (xy 61.265735 -433.796871) (xy 60.887559 -433.796871)
			(xy 60.883674 -433.851233) (xy 60.872093 -433.904488) (xy 60.85305 -433.955553) (xy 60.826933 -434.003388)
			(xy 60.794275 -434.047019) (xy 60.755738 -434.085557) (xy 60.71211 -434.118219) (xy 60.664277 -434.144339)
			(xy 60.613213 -434.163386) (xy 60.559959 -434.174971) (xy 60.505597 -434.178859) (xy 60.451236 -434.17497)
			(xy 60.397982 -434.163384) (xy 60.346918 -434.144337) (xy 60.299086 -434.118216) (xy 60.276994 -434.102256)
			(xy 60.257982 -434.08866) (xy 60.216099 -434.067928) (xy 60.171131 -434.055202) (xy 60.124594 -434.050912)
			(xy 60.078057 -434.055202) (xy 60.033089 -434.067928) (xy 59.991206 -434.08866) (xy 59.972194 -434.102256)
			(xy 59.950061 -434.118151) (xy 59.902239 -434.144264) (xy 59.851187 -434.163306) (xy 59.797944 -434.174888)
			(xy 59.743596 -434.178775) (xy 59.689247 -434.174887) (xy 59.636005 -434.163303) (xy 59.584954 -434.144261)
			(xy 59.537132 -434.118146) (xy 59.493514 -434.085491) (xy 59.454987 -434.046961) (xy 59.422336 -434.00334)
			(xy 59.396226 -433.955516) (xy 59.377187 -433.904463) (xy 59.365609 -433.85122) (xy 59.361725 -433.796871)
			(xy 58.646584 -433.796871) (xy 58.642699 -433.851238) (xy 58.631116 -433.904499) (xy 58.61207 -433.955569)
			(xy 58.58595 -434.003409) (xy 58.553286 -434.047043) (xy 58.514745 -434.085585) (xy 58.471111 -434.118249)
			(xy 58.423271 -434.144369) (xy 58.372201 -434.163415) (xy 58.318941 -434.174999) (xy 58.264573 -434.178884)
			(xy 58.210207 -434.174991) (xy 58.156948 -434.1634) (xy 58.10588 -434.144347) (xy 58.058045 -434.11822)
			(xy 58.035952 -434.102256) (xy 58.01694 -434.08866) (xy 57.975057 -434.067928) (xy 57.930089 -434.055202)
			(xy 57.883552 -434.050912) (xy 57.837015 -434.055202) (xy 57.792047 -434.067928) (xy 57.750164 -434.08866)
			(xy 57.731152 -434.102256) (xy 57.70902 -434.118147) (xy 57.661201 -434.144254) (xy 57.610153 -434.16329)
			(xy 57.556915 -434.174867) (xy 57.502572 -434.178749) (xy 57.448229 -434.174859) (xy 57.394994 -434.163274)
			(xy 57.343948 -434.144231) (xy 57.296133 -434.118117) (xy 57.25252 -434.085464) (xy 57.213999 -434.046937)
			(xy 57.181352 -434.003319) (xy 57.155246 -433.9555) (xy 57.13621 -433.904452) (xy 57.124633 -433.851214)
			(xy 57.120751 -433.796871) (xy 56.759731 -433.796871) (xy 56.755847 -433.851226) (xy 56.744268 -433.904476)
			(xy 56.725228 -433.955535) (xy 56.699115 -434.003365) (xy 56.666461 -434.046992) (xy 56.627931 -434.085527)
			(xy 56.584309 -434.118187) (xy 56.536483 -434.144306) (xy 56.485426 -434.163353) (xy 56.432178 -434.17494)
			(xy 56.377824 -434.178831) (xy 56.323468 -434.174947) (xy 56.270219 -434.163366) (xy 56.21916 -434.144326)
			(xy 56.171331 -434.118212) (xy 56.14924 -434.102256) (xy 56.130228 -434.08866) (xy 56.088345 -434.067928)
			(xy 56.043377 -434.055202) (xy 55.99684 -434.050912) (xy 55.950303 -434.055202) (xy 55.905335 -434.067928)
			(xy 55.863452 -434.08866) (xy 55.84444 -434.102256) (xy 55.822306 -434.118155) (xy 55.77448 -434.144275)
			(xy 55.723424 -434.163324) (xy 55.670177 -434.174911) (xy 55.615822 -434.178802) (xy 55.561467 -434.174917)
			(xy 55.508218 -434.163336) (xy 55.45716 -434.144294) (xy 55.409331 -434.118178) (xy 55.365706 -434.085522)
			(xy 55.327174 -434.046988) (xy 55.294518 -434.003363) (xy 55.268403 -433.955534) (xy 55.249362 -433.904475)
			(xy 55.237782 -433.851226) (xy 55.233898 -433.796871) (xy 29.254196 -433.796871) (xy 29.254196 -435.706816)
			(xy 55.233839 -435.706816) (xy 55.237725 -435.652452) (xy 55.249309 -435.599195) (xy 55.268355 -435.548129)
			(xy 55.294475 -435.500294) (xy 55.327138 -435.456663) (xy 55.365678 -435.418125) (xy 55.40931 -435.385465)
			(xy 55.457147 -435.359347) (xy 55.508214 -435.340303) (xy 55.561472 -435.328722) (xy 55.615835 -435.324839)
			(xy 55.670198 -435.328732) (xy 55.723454 -435.340323) (xy 55.774517 -435.359376) (xy 55.822349 -435.385503)
			(xy 55.84444 -435.401466) (xy 55.863452 -435.415062) (xy 55.905335 -435.435794) (xy 55.950303 -435.44852)
			(xy 55.99684 -435.45281) (xy 56.043377 -435.44852) (xy 56.088345 -435.435794) (xy 56.130228 -435.415062)
			(xy 56.14924 -435.401466) (xy 56.171352 -435.385545) (xy 56.219173 -435.359434) (xy 56.270223 -435.340394)
			(xy 56.323464 -435.328814) (xy 56.37781 -435.324928) (xy 56.432157 -435.328817) (xy 56.485397 -435.3404)
			(xy 56.536446 -435.359442) (xy 56.584266 -435.385556) (xy 56.627882 -435.418209) (xy 56.666408 -435.456737)
			(xy 56.699058 -435.500356) (xy 56.725169 -435.548178) (xy 56.744207 -435.599228) (xy 56.755787 -435.652469)
			(xy 56.759672 -435.706816) (xy 57.120691 -435.706816) (xy 57.124576 -435.652464) (xy 57.136157 -435.599219)
			(xy 57.155197 -435.548163) (xy 57.18131 -435.500338) (xy 57.213963 -435.456715) (xy 57.252492 -435.418183)
			(xy 57.296112 -435.385526) (xy 57.343936 -435.35941) (xy 57.39499 -435.340366) (xy 57.448234 -435.328781)
			(xy 57.502585 -435.324891) (xy 57.556937 -435.328777) (xy 57.610182 -435.340357) (xy 57.661237 -435.359398)
			(xy 57.709063 -435.38551) (xy 57.731152 -435.401466) (xy 57.750164 -435.415062) (xy 57.792047 -435.435794)
			(xy 57.837015 -435.44852) (xy 57.883552 -435.45281) (xy 57.930089 -435.44852) (xy 57.975057 -435.435794)
			(xy 58.01694 -435.415062) (xy 58.035952 -435.401466) (xy 58.058066 -435.385537) (xy 58.105893 -435.359412)
			(xy 58.156952 -435.34036) (xy 58.210202 -435.328769) (xy 58.26456 -435.324876) (xy 58.318919 -435.328758)
			(xy 58.372172 -435.340338) (xy 58.423235 -435.359379) (xy 58.471067 -435.385494) (xy 58.514696 -435.418151)
			(xy 58.553233 -435.456685) (xy 58.585893 -435.500312) (xy 58.612011 -435.548143) (xy 58.631055 -435.599205)
			(xy 58.642639 -435.652457) (xy 58.646524 -435.706816) (xy 59.361666 -435.706816) (xy 59.365552 -435.652458)
			(xy 59.377134 -435.599208) (xy 59.396177 -435.548147) (xy 59.422293 -435.500317) (xy 59.454951 -435.45669)
			(xy 59.493485 -435.418155) (xy 59.537111 -435.385497) (xy 59.584941 -435.35938) (xy 59.636001 -435.340336)
			(xy 59.689252 -435.328753) (xy 59.743609 -435.324866) (xy 59.797966 -435.328755) (xy 59.851216 -435.340341)
			(xy 59.902275 -435.359387) (xy 59.950104 -435.385507) (xy 59.972194 -435.401466) (xy 59.991206 -435.415062)
			(xy 60.033089 -435.435794) (xy 60.078057 -435.44852) (xy 60.124594 -435.45281) (xy 60.171131 -435.44852)
			(xy 60.216099 -435.435794) (xy 60.257982 -435.415062) (xy 60.276994 -435.401466) (xy 60.299107 -435.385541)
			(xy 60.346931 -435.359422) (xy 60.397986 -435.340376) (xy 60.451232 -435.328791) (xy 60.505584 -435.324901)
			(xy 60.559937 -435.328786) (xy 60.613184 -435.340367) (xy 60.66424 -435.359409) (xy 60.712067 -435.385523)
			(xy 60.75569 -435.418179) (xy 60.794221 -435.45671) (xy 60.826876 -435.500333) (xy 60.852991 -435.54816)
			(xy 60.872032 -435.599216) (xy 60.883614 -435.652463) (xy 60.887499 -435.706816) (xy 61.265676 -435.706816)
			(xy 61.269561 -435.652461) (xy 61.281143 -435.599212) (xy 61.300185 -435.548153) (xy 61.3263 -435.500325)
			(xy 61.358955 -435.456699) (xy 61.397487 -435.418166) (xy 61.441111 -435.385508) (xy 61.488939 -435.359391)
			(xy 61.539997 -435.340347) (xy 61.593245 -435.328763) (xy 61.6476 -435.324876) (xy 61.701955 -435.328763)
			(xy 61.755203 -435.340347) (xy 61.806261 -435.359391) (xy 61.854088 -435.385508) (xy 61.876178 -435.401466)
			(xy 61.89519 -435.415062) (xy 61.937073 -435.435794) (xy 61.982041 -435.44852) (xy 62.028578 -435.45281)
			(xy 62.075115 -435.44852) (xy 62.120083 -435.435794) (xy 62.161966 -435.415062) (xy 62.180978 -435.401466)
			(xy 62.203091 -435.385539) (xy 62.250917 -435.359418) (xy 62.301973 -435.34037) (xy 62.35522 -435.328782)
			(xy 62.409575 -435.324891) (xy 62.46393 -435.328775) (xy 62.517179 -435.340356) (xy 62.568238 -435.359398)
			(xy 62.616067 -435.385512) (xy 62.659692 -435.418168) (xy 62.698226 -435.456701) (xy 62.730883 -435.500325)
			(xy 62.756998 -435.548153) (xy 62.776041 -435.599212) (xy 62.787623 -435.65246) (xy 62.791509 -435.706816)
			(xy 62.787619 -435.76117) (xy 62.776032 -435.814418) (xy 62.756985 -435.865475) (xy 62.730866 -435.913301)
			(xy 62.698205 -435.956923) (xy 62.659669 -435.995452) (xy 62.616041 -436.028105) (xy 62.56821 -436.054215)
			(xy 62.517149 -436.073253) (xy 62.463899 -436.084829) (xy 62.409544 -436.088709) (xy 62.355189 -436.084813)
			(xy 62.301943 -436.073221) (xy 62.250888 -436.054169) (xy 62.203065 -436.028044) (xy 62.180978 -436.012082)
			(xy 62.161966 -435.998486) (xy 62.120083 -435.977754) (xy 62.075115 -435.965028) (xy 62.028578 -435.960738)
			(xy 61.982041 -435.965028) (xy 61.937073 -435.977754) (xy 61.89519 -435.998486) (xy 61.876178 -436.012082)
			(xy 61.854115 -436.028075) (xy 61.806289 -436.054196) (xy 61.755233 -436.073244) (xy 61.701986 -436.084832)
			(xy 61.647631 -436.088724) (xy 61.593276 -436.084841) (xy 61.540027 -436.073262) (xy 61.488967 -436.054222)
			(xy 61.441138 -436.028109) (xy 61.397511 -435.995455) (xy 61.358976 -435.956924) (xy 61.326316 -435.913302)
			(xy 61.300198 -435.865475) (xy 61.281152 -435.814418) (xy 61.269566 -435.76117) (xy 61.265676 -435.706816)
			(xy 60.887499 -435.706816) (xy 60.883609 -435.761168) (xy 60.872024 -435.814414) (xy 60.852978 -435.865469)
			(xy 60.82686 -435.913293) (xy 60.794201 -435.956913) (xy 60.755666 -435.995442) (xy 60.71204 -436.028093)
			(xy 60.664212 -436.054204) (xy 60.613154 -436.073241) (xy 60.559906 -436.084818) (xy 60.505553 -436.088699)
			(xy 60.451201 -436.084805) (xy 60.397956 -436.073215) (xy 60.346903 -436.054165) (xy 60.29908 -436.028043)
			(xy 60.276994 -436.012082) (xy 60.257982 -435.998486) (xy 60.216099 -435.977754) (xy 60.171131 -435.965028)
			(xy 60.124594 -435.960738) (xy 60.078057 -435.965028) (xy 60.033089 -435.977754) (xy 59.991206 -435.998486)
			(xy 59.972194 -436.012082) (xy 59.95013 -436.028077) (xy 59.902304 -436.0542) (xy 59.851246 -436.07325)
			(xy 59.797997 -436.08484) (xy 59.74364 -436.088734) (xy 59.689283 -436.084852) (xy 59.636031 -436.073273)
			(xy 59.584969 -436.054233) (xy 59.537137 -436.02812) (xy 59.493509 -435.995465) (xy 59.454971 -435.956934)
			(xy 59.42231 -435.91331) (xy 59.39619 -435.865481) (xy 59.377143 -435.814422) (xy 59.365556 -435.761173)
			(xy 59.361666 -435.706816) (xy 58.646524 -435.706816) (xy 58.642634 -435.761174) (xy 58.631047 -435.814425)
			(xy 58.611998 -435.865485) (xy 58.585876 -435.913314) (xy 58.553213 -435.956938) (xy 58.514673 -435.995469)
			(xy 58.471041 -436.028123) (xy 58.423206 -436.054234) (xy 58.372142 -436.073271) (xy 58.318888 -436.084846)
			(xy 58.264529 -436.088724) (xy 58.210171 -436.084826) (xy 58.156922 -436.073231) (xy 58.105865 -436.054175)
			(xy 58.058039 -436.028046) (xy 58.035952 -436.012082) (xy 58.01694 -435.998486) (xy 57.975057 -435.977754)
			(xy 57.930089 -435.965028) (xy 57.883552 -435.960738) (xy 57.837015 -435.965028) (xy 57.792047 -435.977754)
			(xy 57.750164 -435.998486) (xy 57.731152 -436.012082) (xy 57.709089 -436.028073) (xy 57.661266 -436.054189)
			(xy 57.610212 -436.073234) (xy 57.556967 -436.084819) (xy 57.502616 -436.088709) (xy 57.448265 -436.084824)
			(xy 57.395019 -436.073243) (xy 57.343964 -436.054203) (xy 57.296138 -436.028091) (xy 57.252515 -435.995438)
			(xy 57.213983 -435.956909) (xy 57.181327 -435.913289) (xy 57.15521 -435.865465) (xy 57.136166 -435.814411)
			(xy 57.124581 -435.761167) (xy 57.120691 -435.706816) (xy 56.759672 -435.706816) (xy 56.755783 -435.761162)
			(xy 56.744199 -435.814402) (xy 56.725156 -435.865451) (xy 56.699041 -435.91327) (xy 56.666388 -435.956886)
			(xy 56.627859 -435.995412) (xy 56.584239 -436.028061) (xy 56.536418 -436.054171) (xy 56.485367 -436.073209)
			(xy 56.432126 -436.084788) (xy 56.377779 -436.088672) (xy 56.323433 -436.084782) (xy 56.270193 -436.073197)
			(xy 56.219144 -436.054153) (xy 56.171325 -436.028039) (xy 56.14924 -436.012082) (xy 56.130228 -435.998486)
			(xy 56.088345 -435.977754) (xy 56.043377 -435.965028) (xy 55.99684 -435.960738) (xy 55.950303 -435.965028)
			(xy 55.905335 -435.977754) (xy 55.863452 -435.998486) (xy 55.84444 -436.012082) (xy 55.822375 -436.02808)
			(xy 55.774545 -436.054211) (xy 55.723484 -436.073268) (xy 55.670229 -436.084863) (xy 55.615866 -436.088761)
			(xy 55.561502 -436.084882) (xy 55.508244 -436.073305) (xy 55.457175 -436.054266) (xy 55.409336 -436.028152)
			(xy 55.365701 -435.995495) (xy 55.327158 -435.956961) (xy 55.294492 -435.913333) (xy 55.268368 -435.865499)
			(xy 55.249318 -435.814435) (xy 55.237729 -435.761179) (xy 55.233839 -435.706816) (xy 29.254196 -435.706816)
			(xy 29.254196 -436.828946) (xy 29.25473 -436.845566) (xy 29.263311 -436.877679) (xy 29.279904 -436.906481)
			(xy 29.29128 -436.918608) (xy 30.064681 -437.691784) (xy 69.392798 -437.691784) (xy 69.396869 -437.636162)
			(xy 69.408995 -437.581725) (xy 69.428918 -437.529634) (xy 69.456214 -437.480999) (xy 69.4903 -437.436856)
			(xy 69.530449 -437.398147) (xy 69.575807 -437.365696) (xy 69.625407 -437.340195) (xy 69.678191 -437.322188)
			(xy 69.733034 -437.312058) (xy 69.788768 -437.310021) (xy 69.844205 -437.316121) (xy 69.898162 -437.330227)
			(xy 69.949491 -437.352039) (xy 69.997097 -437.381093) (xy 70.039965 -437.416768) (xy 70.077182 -437.458305)
			(xy 70.107955 -437.504818) (xy 70.131627 -437.555315) (xy 70.147695 -437.608722) (xy 70.155815 -437.663898)
			(xy 70.156324 -437.691784) (xy 70.155815 -437.71967) (xy 70.152368 -437.743092) (xy 70.662544 -437.743092)
			(xy 70.666615 -437.68747) (xy 70.678741 -437.633033) (xy 70.698664 -437.580942) (xy 70.72596 -437.532307)
			(xy 70.760046 -437.488164) (xy 70.800195 -437.449455) (xy 70.845553 -437.417004) (xy 70.895153 -437.391503)
			(xy 70.947937 -437.373496) (xy 71.00278 -437.363366) (xy 71.058514 -437.361329) (xy 71.113951 -437.367429)
			(xy 71.167908 -437.381535) (xy 71.219237 -437.403347) (xy 71.266843 -437.432401) (xy 71.309711 -437.468076)
			(xy 71.346928 -437.509613) (xy 71.377701 -437.556126) (xy 71.401373 -437.606623) (xy 71.417441 -437.66003)
			(xy 71.425561 -437.715206) (xy 71.42607 -437.743092) (xy 71.425759 -437.76011) (xy 71.902064 -437.76011)
			(xy 71.906135 -437.704488) (xy 71.918261 -437.650051) (xy 71.938184 -437.59796) (xy 71.96548 -437.549325)
			(xy 71.999566 -437.505182) (xy 72.039715 -437.466473) (xy 72.085073 -437.434022) (xy 72.134673 -437.408521)
			(xy 72.187457 -437.390514) (xy 72.2423 -437.380384) (xy 72.298034 -437.378347) (xy 72.353471 -437.384447)
			(xy 72.407428 -437.398553) (xy 72.458757 -437.420365) (xy 72.506363 -437.449419) (xy 72.549231 -437.485094)
			(xy 72.586448 -437.526631) (xy 72.617221 -437.573144) (xy 72.640893 -437.623641) (xy 72.656961 -437.677048)
			(xy 72.665081 -437.732224) (xy 72.66559 -437.76011) (xy 72.665081 -437.787996) (xy 72.659092 -437.82869)
			(xy 73.150728 -437.82869) (xy 73.154799 -437.773068) (xy 73.166925 -437.718631) (xy 73.186848 -437.66654)
			(xy 73.214144 -437.617905) (xy 73.24823 -437.573762) (xy 73.288379 -437.535053) (xy 73.333737 -437.502602)
			(xy 73.383337 -437.477101) (xy 73.436121 -437.459094) (xy 73.490964 -437.448964) (xy 73.546698 -437.446927)
			(xy 73.602135 -437.453027) (xy 73.656092 -437.467133) (xy 73.707421 -437.488945) (xy 73.755027 -437.517999)
			(xy 73.797895 -437.553674) (xy 73.835112 -437.595211) (xy 73.865885 -437.641724) (xy 73.889557 -437.692221)
			(xy 73.905625 -437.745628) (xy 73.913745 -437.800804) (xy 73.914254 -437.82869) (xy 73.913745 -437.856576)
			(xy 73.905625 -437.911752) (xy 73.889557 -437.965159) (xy 73.865885 -438.015656) (xy 73.835112 -438.062169)
			(xy 73.797895 -438.103706) (xy 73.755027 -438.139381) (xy 73.707421 -438.168435) (xy 73.656092 -438.190247)
			(xy 73.602135 -438.204353) (xy 73.546698 -438.210453) (xy 73.490964 -438.208416) (xy 73.436121 -438.198286)
			(xy 73.383337 -438.180279) (xy 73.333737 -438.154778) (xy 73.288379 -438.122327) (xy 73.24823 -438.083618)
			(xy 73.214144 -438.039475) (xy 73.186848 -437.99084) (xy 73.166925 -437.938749) (xy 73.154799 -437.884312)
			(xy 73.150728 -437.82869) (xy 72.659092 -437.82869) (xy 72.656961 -437.843172) (xy 72.640893 -437.896579)
			(xy 72.617221 -437.947076) (xy 72.586448 -437.993589) (xy 72.549231 -438.035126) (xy 72.506363 -438.070801)
			(xy 72.458757 -438.099855) (xy 72.407428 -438.121667) (xy 72.353471 -438.135773) (xy 72.298034 -438.141873)
			(xy 72.2423 -438.139836) (xy 72.187457 -438.129706) (xy 72.134673 -438.111699) (xy 72.085073 -438.086198)
			(xy 72.039715 -438.053747) (xy 71.999566 -438.015038) (xy 71.96548 -437.970895) (xy 71.938184 -437.92226)
			(xy 71.918261 -437.870169) (xy 71.906135 -437.815732) (xy 71.902064 -437.76011) (xy 71.425759 -437.76011)
			(xy 71.425561 -437.770978) (xy 71.417441 -437.826154) (xy 71.401373 -437.879561) (xy 71.377701 -437.930058)
			(xy 71.346928 -437.976571) (xy 71.309711 -438.018108) (xy 71.266843 -438.053783) (xy 71.219237 -438.082837)
			(xy 71.167908 -438.104649) (xy 71.113951 -438.118755) (xy 71.058514 -438.124855) (xy 71.00278 -438.122818)
			(xy 70.947937 -438.112688) (xy 70.895153 -438.094681) (xy 70.845553 -438.06918) (xy 70.800195 -438.036729)
			(xy 70.760046 -437.99802) (xy 70.72596 -437.953877) (xy 70.698664 -437.905242) (xy 70.678741 -437.853151)
			(xy 70.666615 -437.798714) (xy 70.662544 -437.743092) (xy 70.152368 -437.743092) (xy 70.147695 -437.774846)
			(xy 70.131627 -437.828253) (xy 70.107955 -437.87875) (xy 70.077182 -437.925263) (xy 70.039965 -437.9668)
			(xy 69.997097 -438.002475) (xy 69.949491 -438.031529) (xy 69.898162 -438.053341) (xy 69.844205 -438.067447)
			(xy 69.788768 -438.073547) (xy 69.733034 -438.07151) (xy 69.678191 -438.06138) (xy 69.625407 -438.043373)
			(xy 69.575807 -438.017872) (xy 69.530449 -437.985421) (xy 69.4903 -437.946712) (xy 69.456214 -437.902569)
			(xy 69.428918 -437.853934) (xy 69.408995 -437.801843) (xy 69.396869 -437.747406) (xy 69.392798 -437.691784)
			(xy 30.064681 -437.691784) (xy 30.165802 -437.792876) (xy 31.295086 -438.92216) (xy 42.456862 -438.92216)
			(xy 43.338411 -439.803709) (xy 47.842668 -439.803709) (xy 47.842668 -439.722599) (xy 47.850618 -439.64188)
			(xy 47.866441 -439.562329) (xy 47.889986 -439.484713) (xy 47.921025 -439.409777) (xy 47.95926 -439.338245)
			(xy 48.004322 -439.270805) (xy 48.055777 -439.208106) (xy 48.11313 -439.150753) (xy 48.175829 -439.099298)
			(xy 48.243269 -439.054236) (xy 48.314801 -439.016001) (xy 48.389737 -438.984962) (xy 48.467353 -438.961417)
			(xy 48.546904 -438.945594) (xy 48.627623 -438.937644) (xy 48.708733 -438.937644) (xy 48.789452 -438.945594)
			(xy 48.869003 -438.961417) (xy 48.946619 -438.984962) (xy 49.021555 -439.016001) (xy 49.093087 -439.054236)
			(xy 49.160527 -439.099298) (xy 49.223226 -439.150753) (xy 49.280579 -439.208106) (xy 49.332034 -439.270805)
			(xy 49.377096 -439.338245) (xy 49.415331 -439.409777) (xy 49.44637 -439.484713) (xy 49.469915 -439.562329)
			(xy 49.485738 -439.64188) (xy 49.493688 -439.722599) (xy 49.494186 -439.763154) (xy 49.493688 -439.803709)
			(xy 51.342788 -439.803709) (xy 51.342788 -439.722599) (xy 51.350738 -439.64188) (xy 51.366561 -439.562329)
			(xy 51.390106 -439.484713) (xy 51.421145 -439.409777) (xy 51.45938 -439.338245) (xy 51.504442 -439.270805)
			(xy 51.555897 -439.208106) (xy 51.61325 -439.150753) (xy 51.675949 -439.099298) (xy 51.743389 -439.054236)
			(xy 51.814921 -439.016001) (xy 51.889857 -438.984962) (xy 51.967473 -438.961417) (xy 52.047024 -438.945594)
			(xy 52.127743 -438.937644) (xy 52.208853 -438.937644) (xy 52.289572 -438.945594) (xy 52.369123 -438.961417)
			(xy 52.446739 -438.984962) (xy 52.521675 -439.016001) (xy 52.593207 -439.054236) (xy 52.660647 -439.099298)
			(xy 52.723346 -439.150753) (xy 52.780699 -439.208106) (xy 52.832154 -439.270805) (xy 52.877216 -439.338245)
			(xy 52.915451 -439.409777) (xy 52.94649 -439.484713) (xy 52.970035 -439.562329) (xy 52.985858 -439.64188)
			(xy 52.993808 -439.722599) (xy 52.994306 -439.763154) (xy 52.993808 -439.803709) (xy 52.985858 -439.884428)
			(xy 52.970035 -439.963979) (xy 52.94649 -440.041595) (xy 52.915451 -440.116531) (xy 52.877216 -440.188063)
			(xy 52.832154 -440.255503) (xy 52.780699 -440.318202) (xy 52.723346 -440.375555) (xy 52.660647 -440.42701)
			(xy 52.593207 -440.472072) (xy 52.521675 -440.510307) (xy 52.446739 -440.541346) (xy 52.369123 -440.564891)
			(xy 52.289572 -440.580714) (xy 52.208853 -440.588664) (xy 52.127743 -440.588664) (xy 52.047024 -440.580714)
			(xy 51.967473 -440.564891) (xy 51.889857 -440.541346) (xy 51.814921 -440.510307) (xy 51.743389 -440.472072)
			(xy 51.675949 -440.42701) (xy 51.61325 -440.375555) (xy 51.555897 -440.318202) (xy 51.504442 -440.255503)
			(xy 51.45938 -440.188063) (xy 51.421145 -440.116531) (xy 51.390106 -440.041595) (xy 51.366561 -439.963979)
			(xy 51.350738 -439.884428) (xy 51.342788 -439.803709) (xy 49.493688 -439.803709) (xy 49.485738 -439.884428)
			(xy 49.469915 -439.963979) (xy 49.44637 -440.041595) (xy 49.415331 -440.116531) (xy 49.377096 -440.188063)
			(xy 49.332034 -440.255503) (xy 49.280579 -440.318202) (xy 49.223226 -440.375555) (xy 49.160527 -440.42701)
			(xy 49.093087 -440.472072) (xy 49.021555 -440.510307) (xy 48.946619 -440.541346) (xy 48.869003 -440.564891)
			(xy 48.789452 -440.580714) (xy 48.708733 -440.588664) (xy 48.627623 -440.588664) (xy 48.546904 -440.580714)
			(xy 48.467353 -440.564891) (xy 48.389737 -440.541346) (xy 48.314801 -440.510307) (xy 48.243269 -440.472072)
			(xy 48.175829 -440.42701) (xy 48.11313 -440.375555) (xy 48.055777 -440.318202) (xy 48.004322 -440.255503)
			(xy 47.95926 -440.188063) (xy 47.921025 -440.116531) (xy 47.889986 -440.041595) (xy 47.866441 -439.963979)
			(xy 47.850618 -439.884428) (xy 47.842668 -439.803709) (xy 43.338411 -439.803709) (xy 44.11599 -440.581288)
			(xy 44.147486 -440.590178) (xy 44.173855 -440.598259) (xy 44.224118 -440.620959) (xy 44.270591 -440.650656)
			(xy 44.312305 -440.686734) (xy 44.348392 -440.72844) (xy 44.3781 -440.774905) (xy 44.400811 -440.825163)
			(xy 44.408852 -440.851544) (xy 44.417742 -440.88304) (xy 46.476158 -442.941456) (xy 87.015828 -442.941456)
			(xy 93.2561 -449.181982) (xy 93.2561 -449.923916) (xy 92.678758 -450.501512) (xy 92.198952 -450.981318)
			(xy 92.183631 -450.997334) (xy 92.15822 -451.033643) (xy 92.139491 -451.073809) (xy 92.128011 -451.116614)
			(xy 92.12413 -451.160762) (xy 92.127963 -451.204914) (xy 92.139396 -451.247731) (xy 92.158082 -451.287918)
			(xy 92.183453 -451.324254) (xy 92.214742 -451.35564) (xy 92.251 -451.381124) (xy 92.270834 -451.39102)
			(xy 92.305514 -451.406445) (xy 92.371678 -451.443648) (xy 92.433506 -451.487681) (xy 92.490297 -451.538044)
			(xy 92.541406 -451.594165) (xy 92.586253 -451.655406) (xy 92.624328 -451.721071) (xy 92.655198 -451.790416)
			(xy 92.678513 -451.862652) (xy 92.694009 -451.936959) (xy 92.701509 -452.012493) (xy 92.700928 -452.088397)
			(xy 92.692272 -452.163807) (xy 92.675641 -452.237868) (xy 92.651222 -452.309739) (xy 92.619294 -452.378603)
			(xy 92.580218 -452.443678) (xy 92.534439 -452.504225) (xy 92.508832 -452.532242) (xy 92.49938 -452.54222)
			(xy 92.479815 -452.561528) (xy 92.469716 -452.57085) (xy 92.442815 -452.594768) (xy 92.384999 -452.637657)
			(xy 92.323149 -452.674491) (xy 92.257897 -452.704894) (xy 92.189909 -452.728554) (xy 92.11988 -452.745231)
			(xy 92.048525 -452.754754) (xy 91.976574 -452.757026) (xy 91.940634 -452.755) (xy 91.903489 -452.75195)
			(xy 91.830081 -452.739044) (xy 91.758424 -452.718536) (xy 91.689304 -452.690649) (xy 91.623478 -452.655689)
			(xy 91.561667 -452.614039) (xy 91.504548 -452.566156) (xy 91.452748 -452.512565) (xy 91.406834 -452.453852)
			(xy 91.38666 -452.422514) (xy 91.37773 -452.409116) (xy 91.354379 -452.386962) (xy 91.326223 -452.371362)
			(xy 91.295058 -452.36331) (xy 91.278964 -452.362824) (xy 90.873072 -452.362824) (xy 90.856427 -452.363371)
			(xy 90.824274 -452.371994) (xy 90.795447 -452.388645) (xy 90.771913 -452.412189) (xy 90.755274 -452.441022)
			(xy 90.746664 -452.473179) (xy 90.746072 -452.489824) (xy 90.746492 -452.504536) (xy 90.753234 -452.533177)
			(xy 90.766355 -452.559514) (xy 90.785156 -452.582147) (xy 90.80864 -452.599875) (xy 90.835559 -452.611755)
			(xy 90.849958 -452.614792) (xy 90.887564 -452.622278) (xy 90.961024 -452.644273) (xy 91.031694 -452.674038)
			(xy 91.098754 -452.711227) (xy 91.161428 -452.75541) (xy 91.166733 -452.76008) (xy 93.154506 -452.76008)
			(xy 93.158522 -452.64381) (xy 93.170549 -452.528095) (xy 93.190531 -452.413485) (xy 93.218373 -452.300526)
			(xy 93.253942 -452.189758) (xy 93.297068 -452.081707) (xy 93.347545 -451.976889) (xy 93.405134 -451.875804)
			(xy 93.46956 -451.778932) (xy 93.540515 -451.686736) (xy 93.617662 -451.599655) (xy 93.700633 -451.518104)
			(xy 93.789033 -451.442472) (xy 93.88244 -451.373118) (xy 93.980409 -451.310375) (xy 94.082473 -451.254539)
			(xy 94.188147 -451.205878) (xy 94.296926 -451.164624) (xy 94.408291 -451.130973) (xy 94.521714 -451.105085)
			(xy 94.636651 -451.087084) (xy 94.752557 -451.077055) (xy 94.868879 -451.075047) (xy 94.985062 -451.081069)
			(xy 95.100553 -451.095092) (xy 95.214801 -451.11705) (xy 95.327262 -451.146837) (xy 95.4374 -451.184312)
			(xy 95.54469 -451.229297) (xy 95.648621 -451.281576) (xy 95.748697 -451.340901) (xy 95.844443 -451.406989)
			(xy 95.9354 -451.479525) (xy 96.021136 -451.558164) (xy 96.101243 -451.64253) (xy 96.175339 -451.732222)
			(xy 96.243069 -451.826812) (xy 96.304113 -451.92585) (xy 96.358178 -452.028863) (xy 96.405008 -452.13536)
			(xy 96.444379 -452.244835) (xy 96.476103 -452.356765) (xy 96.500029 -452.470617) (xy 96.516043 -452.585849)
			(xy 96.52407 -452.701911) (xy 96.524572 -452.76008) (xy 96.52407 -452.818249) (xy 96.516043 -452.934311)
			(xy 96.500029 -453.049543) (xy 96.476103 -453.163395) (xy 96.444379 -453.275325) (xy 96.405008 -453.3848)
			(xy 96.358178 -453.491297) (xy 96.304113 -453.59431) (xy 96.243069 -453.693348) (xy 96.175339 -453.787938)
			(xy 96.101243 -453.87763) (xy 96.021136 -453.961996) (xy 95.9354 -454.040635) (xy 95.844443 -454.113171)
			(xy 95.748697 -454.179259) (xy 95.648621 -454.238584) (xy 95.54469 -454.290863) (xy 95.4374 -454.335848)
			(xy 95.327262 -454.373323) (xy 95.214801 -454.40311) (xy 95.100553 -454.425068) (xy 94.985062 -454.439091)
			(xy 94.868879 -454.445113) (xy 94.752557 -454.443105) (xy 94.636651 -454.433076) (xy 94.521714 -454.415075)
			(xy 94.408291 -454.389187) (xy 94.296926 -454.355536) (xy 94.188147 -454.314282) (xy 94.082473 -454.265621)
			(xy 93.980409 -454.209785) (xy 93.88244 -454.147042) (xy 93.789033 -454.077688) (xy 93.700633 -454.002056)
			(xy 93.617662 -453.920505) (xy 93.540515 -453.833424) (xy 93.46956 -453.741228) (xy 93.405134 -453.644356)
			(xy 93.347545 -453.543271) (xy 93.297068 -453.438453) (xy 93.253942 -453.330402) (xy 93.218373 -453.219634)
			(xy 93.190531 -453.106675) (xy 93.170549 -452.992065) (xy 93.158522 -452.87635) (xy 93.154506 -452.76008)
			(xy 91.166733 -452.76008) (xy 91.218988 -452.806076) (xy 91.270767 -452.862635) (xy 91.316166 -452.924434)
			(xy 91.354659 -452.990755) (xy 91.385798 -453.06083) (xy 91.409223 -453.133846) (xy 91.424662 -453.208958)
			(xy 91.431937 -453.285294) (xy 91.430963 -453.36197) (xy 91.421752 -453.438096) (xy 91.40441 -453.512791)
			(xy 91.379138 -453.585189) (xy 91.34623 -453.654451) (xy 91.306066 -453.719773) (xy 91.283028 -453.750426)
			(xy 91.261029 -453.77817) (xy 91.212372 -453.829616) (xy 91.158846 -453.875974) (xy 91.100979 -453.916785)
			(xy 91.039345 -453.951646) (xy 90.974552 -453.980211) (xy 90.907242 -454.002199) (xy 90.838081 -454.017392)
			(xy 90.802968 -454.021952) (xy 90.768938 -454.025541) (xy 90.70052 -454.026959) (xy 90.632283 -454.021796)
			(xy 90.598498 -454.016364) (xy 90.58021 -454.013062) (xy 90.541759 -454.004832) (xy 90.466823 -453.980996)
			(xy 90.394972 -453.949042) (xy 90.327083 -453.90936) (xy 90.295222 -453.886316) (xy 90.268813 -453.866205)
			(xy 90.219457 -453.821808) (xy 90.19667 -453.79767) (xy 90.174558 -453.773053) (xy 90.134486 -453.720391)
			(xy 90.11666 -453.692514) (xy 90.10771 -453.679091) (xy 90.084301 -453.656906) (xy 90.056075 -453.641303)
			(xy 90.024837 -453.633282) (xy 90.00871 -453.632824) (xy 89.83853 -453.632824) (xy 88.653366 -454.817988)
			(xy 85.284564 -454.817988) (xy 84.770468 -454.303892) (xy 84.75433 -454.288363) (xy 84.717658 -454.262662)
			(xy 84.677054 -454.243777) (xy 84.63377 -454.232291) (xy 84.589144 -454.228559) (xy 84.544554 -454.232696)
			(xy 84.501377 -454.244574) (xy 84.460945 -454.263826) (xy 84.424508 -454.289859) (xy 84.393189 -454.321868)
			(xy 84.367958 -454.358864) (xy 84.349591 -454.399706) (xy 84.338658 -454.443132) (xy 84.336636 -454.465436)
			(xy 84.336636 -464.509866) (xy 86.877404 -464.509866) (xy 86.881424 -464.319215) (xy 86.893478 -464.128902)
			(xy 86.913544 -463.939267) (xy 86.941587 -463.750646) (xy 86.977556 -463.563376) (xy 87.021388 -463.377788)
			(xy 87.073005 -463.194213) (xy 87.132315 -463.012977) (xy 87.199213 -462.834402) (xy 87.273579 -462.658807)
			(xy 87.355281 -462.486502) (xy 87.444175 -462.317795) (xy 87.540101 -462.152985) (xy 87.64289 -461.992366)
			(xy 87.752359 -461.836223) (xy 87.868313 -461.684834) (xy 87.990547 -461.538467) (xy 88.118841 -461.397383)
			(xy 88.252969 -461.261834) (xy 88.392693 -461.132059) (xy 88.537763 -461.008289) (xy 88.687921 -460.890746)
			(xy 88.842902 -460.779637) (xy 89.002429 -460.67516) (xy 89.166218 -460.577501) (xy 89.333978 -460.486834)
			(xy 89.505412 -460.40332) (xy 89.680214 -460.327107) (xy 89.858073 -460.258331) (xy 90.038674 -460.197113)
			(xy 90.221694 -460.143564) (xy 90.40681 -460.097778) (xy 90.593691 -460.059836) (xy 90.782006 -460.029807)
			(xy 90.971419 -460.007742) (xy 91.161593 -459.993683) (xy 91.352192 -459.987653) (xy 91.542875 -459.989663)
			(xy 91.733304 -459.99971) (xy 91.92314 -460.017776) (xy 92.112046 -460.043829) (xy 92.299685 -460.077822)
			(xy 92.485725 -460.119695) (xy 92.669834 -460.169374) (xy 92.851685 -460.22677) (xy 93.030955 -460.291781)
			(xy 93.207325 -460.364292) (xy 93.380481 -460.444173) (xy 93.550116 -460.531283) (xy 93.715928 -460.625467)
			(xy 93.877622 -460.726558) (xy 94.03491 -460.834374) (xy 94.187513 -460.948726) (xy 94.335161 -461.069409)
			(xy 94.477589 -461.19621) (xy 94.614545 -461.328901) (xy 94.745786 -461.467249) (xy 94.871078 -461.611006)
			(xy 94.990198 -461.759917) (xy 95.102934 -461.913718) (xy 95.209087 -462.072134) (xy 95.308467 -462.234885)
			(xy 95.400897 -462.40168) (xy 95.486214 -462.572224) (xy 95.564266 -462.746212) (xy 95.634913 -462.923337)
			(xy 95.698031 -463.103282) (xy 95.753507 -463.285728) (xy 95.801242 -463.470351) (xy 95.841152 -463.656821)
			(xy 95.873165 -463.844809) (xy 95.897225 -464.033979) (xy 95.913288 -464.223995) (xy 95.921327 -464.414519)
			(xy 95.92183 -464.509866) (xy 95.921327 -464.605213) (xy 95.913288 -464.795737) (xy 95.897225 -464.985753)
			(xy 95.873165 -465.174923) (xy 95.841152 -465.362911) (xy 95.801242 -465.549381) (xy 95.753507 -465.734004)
			(xy 95.698031 -465.91645) (xy 95.634913 -466.096395) (xy 95.564266 -466.27352) (xy 95.486214 -466.447508)
			(xy 95.400897 -466.618052) (xy 95.308467 -466.784847) (xy 95.209087 -466.947598) (xy 95.102934 -467.106014)
			(xy 94.990198 -467.259815) (xy 94.871078 -467.408726) (xy 94.745786 -467.552483) (xy 94.614545 -467.690831)
			(xy 94.477589 -467.823522) (xy 94.335161 -467.950323) (xy 94.187513 -468.071006) (xy 94.03491 -468.185358)
			(xy 93.877622 -468.293174) (xy 93.715928 -468.394265) (xy 93.550116 -468.488449) (xy 93.380481 -468.575559)
			(xy 93.207325 -468.65544) (xy 93.030955 -468.727951) (xy 92.851685 -468.792962) (xy 92.669834 -468.850358)
			(xy 92.485725 -468.900037) (xy 92.299685 -468.94191) (xy 92.112046 -468.975903) (xy 91.92314 -469.001956)
			(xy 91.733304 -469.020022) (xy 91.542875 -469.030069) (xy 91.352192 -469.032079) (xy 91.161593 -469.026049)
			(xy 90.971419 -469.01199) (xy 90.782006 -468.989925) (xy 90.593691 -468.959896) (xy 90.40681 -468.921954)
			(xy 90.221694 -468.876168) (xy 90.038674 -468.822619) (xy 89.858073 -468.761401) (xy 89.680214 -468.692625)
			(xy 89.505412 -468.616412) (xy 89.333978 -468.532898) (xy 89.166218 -468.442231) (xy 89.002429 -468.344572)
			(xy 88.842902 -468.240095) (xy 88.687921 -468.128986) (xy 88.537763 -468.011443) (xy 88.392693 -467.887673)
			(xy 88.252969 -467.757898) (xy 88.118841 -467.622349) (xy 87.990547 -467.481265) (xy 87.868313 -467.334898)
			(xy 87.752359 -467.183509) (xy 87.64289 -467.027366) (xy 87.540101 -466.866747) (xy 87.444175 -466.701937)
			(xy 87.355281 -466.53323) (xy 87.273579 -466.360925) (xy 87.199213 -466.18533) (xy 87.132315 -466.006755)
			(xy 87.073005 -465.825519) (xy 87.021388 -465.641944) (xy 86.977556 -465.456356) (xy 86.941587 -465.269086)
			(xy 86.913544 -465.080465) (xy 86.893478 -464.89083) (xy 86.881424 -464.700517) (xy 86.877404 -464.509866)
			(xy 84.336636 -464.509866) (xy 84.336636 -465.33562) (xy 84.337159 -465.352261) (xy 84.345833 -465.384396)
			(xy 84.36253 -465.413189) (xy 84.373974 -465.425282) (xy 85.801708 -466.852762) (xy 85.801708 -479.37039)
			(xy 89.11158 -479.37039) (xy 89.115651 -479.314768) (xy 89.127777 -479.260331) (xy 89.1477 -479.20824)
			(xy 89.174996 -479.159605) (xy 89.209082 -479.115462) (xy 89.249231 -479.076753) (xy 89.294589 -479.044302)
			(xy 89.344189 -479.018801) (xy 89.396973 -479.000794) (xy 89.451816 -478.990664) (xy 89.50755 -478.988627)
			(xy 89.562987 -478.994727) (xy 89.616944 -479.008833) (xy 89.668273 -479.030645) (xy 89.715879 -479.059699)
			(xy 89.758747 -479.095374) (xy 89.795964 -479.136911) (xy 89.826737 -479.183424) (xy 89.850409 -479.233921)
			(xy 89.866477 -479.287328) (xy 89.874597 -479.342504) (xy 89.875106 -479.37039) (xy 89.874597 -479.398276)
			(xy 89.866477 -479.453452) (xy 89.850409 -479.506859) (xy 89.826737 -479.557356) (xy 89.795964 -479.603869)
			(xy 89.758747 -479.645406) (xy 89.715879 -479.681081) (xy 89.668273 -479.710135) (xy 89.616944 -479.731947)
			(xy 89.562987 -479.746053) (xy 89.50755 -479.752153) (xy 89.451816 -479.750116) (xy 89.396973 -479.739986)
			(xy 89.344189 -479.721979) (xy 89.294589 -479.696478) (xy 89.249231 -479.664027) (xy 89.209082 -479.625318)
			(xy 89.174996 -479.581175) (xy 89.1477 -479.53254) (xy 89.127777 -479.480449) (xy 89.115651 -479.426012)
			(xy 89.11158 -479.37039) (xy 85.801708 -479.37039) (xy 85.801708 -482.565456) (xy 92.659706 -482.565456)
			(xy 92.663777 -482.509834) (xy 92.675903 -482.455397) (xy 92.695826 -482.403306) (xy 92.723122 -482.354671)
			(xy 92.757208 -482.310528) (xy 92.797357 -482.271819) (xy 92.842715 -482.239368) (xy 92.892315 -482.213867)
			(xy 92.945099 -482.19586) (xy 92.999942 -482.18573) (xy 93.055676 -482.183693) (xy 93.111113 -482.189793)
			(xy 93.16507 -482.203899) (xy 93.216399 -482.225711) (xy 93.264005 -482.254765) (xy 93.306873 -482.29044)
			(xy 93.34409 -482.331977) (xy 93.374863 -482.37849) (xy 93.398535 -482.428987) (xy 93.414603 -482.482394)
			(xy 93.422723 -482.53757) (xy 93.423232 -482.565456) (xy 93.422723 -482.593342) (xy 93.414603 -482.648518)
			(xy 93.398535 -482.701925) (xy 93.374863 -482.752422) (xy 93.34409 -482.798935) (xy 93.306873 -482.840472)
			(xy 93.264005 -482.876147) (xy 93.216399 -482.905201) (xy 93.16507 -482.927013) (xy 93.111113 -482.941119)
			(xy 93.055676 -482.947219) (xy 92.999942 -482.945182) (xy 92.945099 -482.935052) (xy 92.892315 -482.917045)
			(xy 92.842715 -482.891544) (xy 92.797357 -482.859093) (xy 92.757208 -482.820384) (xy 92.723122 -482.776241)
			(xy 92.695826 -482.727606) (xy 92.675903 -482.675515) (xy 92.663777 -482.621078) (xy 92.659706 -482.565456)
			(xy 85.801708 -482.565456) (xy 85.801708 -482.954838) (xy 94.723456 -482.954838) (xy 94.727527 -482.899216)
			(xy 94.739653 -482.844779) (xy 94.759576 -482.792688) (xy 94.786872 -482.744053) (xy 94.820958 -482.69991)
			(xy 94.861107 -482.661201) (xy 94.906465 -482.62875) (xy 94.956065 -482.603249) (xy 95.008849 -482.585242)
			(xy 95.063692 -482.575112) (xy 95.119426 -482.573075) (xy 95.174863 -482.579175) (xy 95.22882 -482.593281)
			(xy 95.280149 -482.615093) (xy 95.327755 -482.644147) (xy 95.370623 -482.679822) (xy 95.40784 -482.721359)
			(xy 95.438613 -482.767872) (xy 95.462285 -482.818369) (xy 95.478353 -482.871776) (xy 95.486473 -482.926952)
			(xy 95.486982 -482.954838) (xy 95.486473 -482.982724) (xy 95.478353 -483.0379) (xy 95.462285 -483.091307)
			(xy 95.438613 -483.141804) (xy 95.40784 -483.188317) (xy 95.370623 -483.229854) (xy 95.327755 -483.265529)
			(xy 95.280149 -483.294583) (xy 95.22882 -483.316395) (xy 95.174863 -483.330501) (xy 95.119426 -483.336601)
			(xy 95.063692 -483.334564) (xy 95.008849 -483.324434) (xy 94.956065 -483.306427) (xy 94.906465 -483.280926)
			(xy 94.861107 -483.248475) (xy 94.820958 -483.209766) (xy 94.786872 -483.165623) (xy 94.759576 -483.116988)
			(xy 94.739653 -483.064897) (xy 94.727527 -483.01046) (xy 94.723456 -482.954838) (xy 85.801708 -482.954838)
			(xy 85.801708 -483.299262) (xy 87.551768 -485.049322) (xy 87.583264 -485.058466) (xy 87.607527 -485.065854)
			(xy 87.653999 -485.086174) (xy 87.697363 -485.11248) (xy 87.717376 -485.128062) (xy 87.739807 -485.146849)
			(xy 87.779246 -485.190069) (xy 87.811641 -485.238791) (xy 87.836239 -485.291879) (xy 87.844884 -485.319832)
			(xy 87.853774 -485.351328) (xy 89.753948 -487.251502) (xy 91.911676 -487.251502) (xy 91.915747 -487.19588)
			(xy 91.927873 -487.141443) (xy 91.947796 -487.089352) (xy 91.975092 -487.040717) (xy 92.009178 -486.996574)
			(xy 92.049327 -486.957865) (xy 92.094685 -486.925414) (xy 92.144285 -486.899913) (xy 92.197069 -486.881906)
			(xy 92.251912 -486.871776) (xy 92.307646 -486.869739) (xy 92.363083 -486.875839) (xy 92.41704 -486.889945)
			(xy 92.468369 -486.911757) (xy 92.515975 -486.940811) (xy 92.558843 -486.976486) (xy 92.565839 -486.984294)
			(xy 95.986344 -486.984294) (xy 95.990415 -486.928672) (xy 96.002541 -486.874235) (xy 96.022464 -486.822144)
			(xy 96.04976 -486.773509) (xy 96.083846 -486.729366) (xy 96.123995 -486.690657) (xy 96.169353 -486.658206)
			(xy 96.218953 -486.632705) (xy 96.271737 -486.614698) (xy 96.32658 -486.604568) (xy 96.382314 -486.602531)
			(xy 96.437751 -486.608631) (xy 96.491708 -486.622737) (xy 96.543037 -486.644549) (xy 96.590643 -486.673603)
			(xy 96.633511 -486.709278) (xy 96.670728 -486.750815) (xy 96.701501 -486.797328) (xy 96.725173 -486.847825)
			(xy 96.741241 -486.901232) (xy 96.749361 -486.956408) (xy 96.74987 -486.984294) (xy 96.749361 -487.01218)
			(xy 96.741241 -487.067356) (xy 96.725173 -487.120763) (xy 96.701501 -487.17126) (xy 96.670728 -487.217773)
			(xy 96.633511 -487.25931) (xy 96.590643 -487.294985) (xy 96.543037 -487.324039) (xy 96.491708 -487.345851)
			(xy 96.437751 -487.359957) (xy 96.382314 -487.366057) (xy 96.32658 -487.36402) (xy 96.271737 -487.35389)
			(xy 96.218953 -487.335883) (xy 96.169353 -487.310382) (xy 96.123995 -487.277931) (xy 96.083846 -487.239222)
			(xy 96.04976 -487.195079) (xy 96.022464 -487.146444) (xy 96.002541 -487.094353) (xy 95.990415 -487.039916)
			(xy 95.986344 -486.984294) (xy 92.565839 -486.984294) (xy 92.59606 -487.018023) (xy 92.626833 -487.064536)
			(xy 92.650505 -487.115033) (xy 92.666573 -487.16844) (xy 92.674693 -487.223616) (xy 92.675202 -487.251502)
			(xy 92.674693 -487.279388) (xy 92.666573 -487.334564) (xy 92.650505 -487.387971) (xy 92.626833 -487.438468)
			(xy 92.59606 -487.484981) (xy 92.593604 -487.487722) (xy 94.810832 -487.487722) (xy 94.814903 -487.4321)
			(xy 94.827029 -487.377663) (xy 94.846952 -487.325572) (xy 94.874248 -487.276937) (xy 94.908334 -487.232794)
			(xy 94.948483 -487.194085) (xy 94.993841 -487.161634) (xy 95.043441 -487.136133) (xy 95.096225 -487.118126)
			(xy 95.151068 -487.107996) (xy 95.206802 -487.105959) (xy 95.262239 -487.112059) (xy 95.316196 -487.126165)
			(xy 95.367525 -487.147977) (xy 95.415131 -487.177031) (xy 95.457999 -487.212706) (xy 95.495216 -487.254243)
			(xy 95.525989 -487.300756) (xy 95.549661 -487.351253) (xy 95.565729 -487.40466) (xy 95.573849 -487.459836)
			(xy 95.574358 -487.487722) (xy 95.573849 -487.515608) (xy 95.565729 -487.570784) (xy 95.549661 -487.624191)
			(xy 95.525989 -487.674688) (xy 95.495216 -487.721201) (xy 95.457999 -487.762738) (xy 95.415131 -487.798413)
			(xy 95.367525 -487.827467) (xy 95.316196 -487.849279) (xy 95.262239 -487.863385) (xy 95.206802 -487.869485)
			(xy 95.151068 -487.867448) (xy 95.096225 -487.857318) (xy 95.043441 -487.839311) (xy 94.993841 -487.81381)
			(xy 94.948483 -487.781359) (xy 94.908334 -487.74265) (xy 94.874248 -487.698507) (xy 94.846952 -487.649872)
			(xy 94.827029 -487.597781) (xy 94.814903 -487.543344) (xy 94.810832 -487.487722) (xy 92.593604 -487.487722)
			(xy 92.558843 -487.526518) (xy 92.515975 -487.562193) (xy 92.468369 -487.591247) (xy 92.41704 -487.613059)
			(xy 92.363083 -487.627165) (xy 92.307646 -487.633265) (xy 92.251912 -487.631228) (xy 92.197069 -487.621098)
			(xy 92.144285 -487.603091) (xy 92.094685 -487.57759) (xy 92.049327 -487.545139) (xy 92.009178 -487.50643)
			(xy 91.975092 -487.462287) (xy 91.947796 -487.413652) (xy 91.927873 -487.361561) (xy 91.915747 -487.307124)
			(xy 91.911676 -487.251502) (xy 89.753948 -487.251502) (xy 90.26017 -487.757724) (xy 90.275886 -487.772806)
			(xy 90.311483 -487.797903) (xy 90.350838 -487.816562) (xy 90.392799 -487.828238) (xy 90.436135 -487.83259)
			(xy 90.47958 -487.829488) (xy 90.521859 -487.819025) (xy 90.561735 -487.801506) (xy 90.59804 -487.777445)
			(xy 90.629711 -487.747546) (xy 90.655821 -487.712685) (xy 90.666062 -487.693462) (xy 90.677864 -487.668923)
			(xy 90.707391 -487.623175) (xy 90.743122 -487.582089) (xy 90.784331 -487.5465) (xy 90.830181 -487.517131)
			(xy 90.87974 -487.494578) (xy 90.932002 -487.4793) (xy 90.985905 -487.471606) (xy 91.040355 -487.471653)
			(xy 91.094244 -487.47944) (xy 91.14648 -487.494809) (xy 91.196 -487.517448) (xy 91.241799 -487.546896)
			(xy 91.282946 -487.582557) (xy 91.318606 -487.623704) (xy 91.348054 -487.669503) (xy 91.370692 -487.719024)
			(xy 91.386061 -487.771259) (xy 91.393847 -487.825149) (xy 91.393894 -487.879599) (xy 91.3862 -487.933502)
			(xy 91.37092 -487.985764) (xy 91.348367 -488.035323) (xy 91.318997 -488.081172) (xy 91.283408 -488.122381)
			(xy 91.267828 -488.13593) (xy 93.533974 -488.13593) (xy 93.538045 -488.080308) (xy 93.550171 -488.025871)
			(xy 93.570094 -487.97378) (xy 93.59739 -487.925145) (xy 93.631476 -487.881002) (xy 93.671625 -487.842293)
			(xy 93.716983 -487.809842) (xy 93.766583 -487.784341) (xy 93.819367 -487.766334) (xy 93.87421 -487.756204)
			(xy 93.929944 -487.754167) (xy 93.985381 -487.760267) (xy 94.039338 -487.774373) (xy 94.090667 -487.796185)
			(xy 94.138273 -487.825239) (xy 94.181141 -487.860914) (xy 94.218358 -487.902451) (xy 94.249131 -487.948964)
			(xy 94.272803 -487.999461) (xy 94.288871 -488.052868) (xy 94.296991 -488.108044) (xy 94.2975 -488.13593)
			(xy 94.296991 -488.163816) (xy 94.288871 -488.218992) (xy 94.272803 -488.272399) (xy 94.249131 -488.322896)
			(xy 94.218358 -488.369409) (xy 94.181141 -488.410946) (xy 94.138273 -488.446621) (xy 94.090667 -488.475675)
			(xy 94.039338 -488.497487) (xy 93.985381 -488.511593) (xy 93.929944 -488.517693) (xy 93.87421 -488.515656)
			(xy 93.819367 -488.505526) (xy 93.766583 -488.487519) (xy 93.716983 -488.462018) (xy 93.671625 -488.429567)
			(xy 93.631476 -488.390858) (xy 93.59739 -488.346715) (xy 93.570094 -488.29808) (xy 93.550171 -488.245989)
			(xy 93.538045 -488.191552) (xy 93.533974 -488.13593) (xy 91.267828 -488.13593) (xy 91.242322 -488.158111)
			(xy 91.196573 -488.187638) (xy 91.17203 -488.19943) (xy 91.15283 -488.209714) (xy 91.117964 -488.235813)
			(xy 91.088059 -488.267475) (xy 91.063993 -488.303774) (xy 91.04647 -488.343646) (xy 91.036004 -488.385922)
			(xy 91.032902 -488.429363) (xy 91.037254 -488.472697) (xy 91.048933 -488.514655) (xy 91.067596 -488.554005)
			(xy 91.070827 -488.558586) (xy 91.924376 -488.558586) (xy 91.928447 -488.502964) (xy 91.940573 -488.448527)
			(xy 91.960496 -488.396436) (xy 91.987792 -488.347801) (xy 92.021878 -488.303658) (xy 92.062027 -488.264949)
			(xy 92.107385 -488.232498) (xy 92.156985 -488.206997) (xy 92.209769 -488.18899) (xy 92.264612 -488.17886)
			(xy 92.320346 -488.176823) (xy 92.375783 -488.182923) (xy 92.42974 -488.197029) (xy 92.481069 -488.218841)
			(xy 92.528675 -488.247895) (xy 92.571543 -488.28357) (xy 92.60876 -488.325107) (xy 92.639533 -488.37162)
			(xy 92.663205 -488.422117) (xy 92.679273 -488.475524) (xy 92.687393 -488.5307) (xy 92.687902 -488.558586)
			(xy 92.687393 -488.586472) (xy 92.679273 -488.641648) (xy 92.663205 -488.695055) (xy 92.639533 -488.745552)
			(xy 92.60876 -488.792065) (xy 92.571543 -488.833602) (xy 92.528675 -488.869277) (xy 92.481069 -488.898331)
			(xy 92.42974 -488.920143) (xy 92.375783 -488.934249) (xy 92.320346 -488.940349) (xy 92.264612 -488.938312)
			(xy 92.209769 -488.928182) (xy 92.156985 -488.910175) (xy 92.107385 -488.884674) (xy 92.062027 -488.852223)
			(xy 92.021878 -488.813514) (xy 91.987792 -488.769371) (xy 91.960496 -488.720736) (xy 91.940573 -488.668645)
			(xy 91.928447 -488.614208) (xy 91.924376 -488.558586) (xy 91.070827 -488.558586) (xy 91.092698 -488.589596)
			(xy 91.107768 -488.605322) (xy 91.972384 -489.469938) (xy 93.012768 -490.510576) (xy 93.012768 -492.874554)
			(xy 93.265752 -493.127538) (xy 93.265752 -495.811302) (xy 93.268019 -495.833107) (xy 93.279073 -495.875526)
			(xy 93.297235 -495.915422) (xy 93.321965 -495.951615) (xy 93.352533 -495.983034) (xy 93.388034 -496.008748)
			(xy 93.427417 -496.027997) (xy 93.469516 -496.040211) (xy 93.513086 -496.045029) (xy 93.556836 -496.042307)
			(xy 93.599473 -496.032127) (xy 93.639734 -496.01479) (xy 93.676428 -495.990808) (xy 93.692726 -495.976148)
			(xy 93.735559 -495.937009) (xy 93.825783 -495.86404) (xy 93.920815 -495.797452) (xy 94.020203 -495.737562)
			(xy 94.123477 -495.684653) (xy 94.230147 -495.638976) (xy 94.339708 -495.600747) (xy 94.45164 -495.570149)
			(xy 94.565411 -495.547326) (xy 94.680484 -495.532385) (xy 94.796312 -495.525399) (xy 94.912346 -495.5264)
			(xy 95.028036 -495.535384) (xy 95.142834 -495.552307) (xy 95.256195 -495.57709) (xy 95.367582 -495.609614)
			(xy 95.476467 -495.649727) (xy 95.582333 -495.697238) (xy 95.684679 -495.751921) (xy 95.78302 -495.813517)
			(xy 95.876888 -495.881734) (xy 95.96584 -495.956249) (xy 96.049454 -496.036709) (xy 96.127332 -496.122732)
			(xy 96.199106 -496.21391) (xy 96.264436 -496.30981) (xy 96.323011 -496.409979) (xy 96.374555 -496.513942)
			(xy 96.418822 -496.621205) (xy 96.455603 -496.73126) (xy 96.484724 -496.843585) (xy 96.506046 -496.957647)
			(xy 96.519468 -497.072907) (xy 96.524928 -497.188817) (xy 96.522398 -497.304828) (xy 96.51189 -497.42039)
			(xy 96.493456 -497.534955) (xy 96.467181 -497.647979) (xy 96.433191 -497.758928) (xy 96.391647 -497.867275)
			(xy 96.342746 -497.972506) (xy 96.286719 -498.074122) (xy 96.223832 -498.171642) (xy 96.154383 -498.264604)
			(xy 96.078703 -498.352566) (xy 95.997148 -498.435112) (xy 95.910107 -498.51185) (xy 95.817991 -498.582416)
			(xy 95.721237 -498.646476) (xy 95.620305 -498.703726) (xy 95.515672 -498.753896) (xy 95.407835 -498.796745)
			(xy 95.297305 -498.832073) (xy 95.184606 -498.859711) (xy 95.070273 -498.879528) (xy 94.954846 -498.891431)
			(xy 94.838874 -498.895362) (xy 94.722907 -498.891303) (xy 94.607493 -498.879274) (xy 94.493182 -498.859331)
			(xy 94.380513 -498.83157) (xy 94.270022 -498.79612) (xy 94.162232 -498.753152) (xy 94.057654 -498.702868)
			(xy 93.956785 -498.645507) (xy 93.860102 -498.58134) (xy 93.768064 -498.510673) (xy 93.681107 -498.433839)
			(xy 93.599643 -498.351204) (xy 93.524059 -498.263159) (xy 93.454713 -498.170121) (xy 93.391933 -498.072532)
			(xy 93.336018 -497.970854) (xy 93.287232 -497.865569) (xy 93.245807 -497.757177) (xy 93.228414 -497.701824)
			(xy 93.221621 -497.681096) (xy 93.201961 -497.642163) (xy 93.175941 -497.60716) (xy 93.144325 -497.577115)
			(xy 93.108043 -497.55291) (xy 93.068159 -497.535258) (xy 93.025847 -497.524677) (xy 92.982349 -497.521477)
			(xy 92.938944 -497.525753) (xy 92.896907 -497.537379) (xy 92.857473 -497.556013) (xy 92.821801 -497.581109)
			(xy 92.806012 -497.59616) (xy 92.19565 -498.206522) (xy 92.086684 -498.315234) (xy 91.221306 -499.180612)
			(xy 86.606126 -499.180612) (xy 86.268052 -498.842792) (xy 85.918802 -498.493542) (xy 85.908417 -498.483677)
			(xy 85.884171 -498.468437) (xy 85.857141 -498.458978) (xy 85.828683 -498.455774) (xy 85.814408 -498.456966)
			(xy 85.79993 -498.458744) (xy 85.793326 -498.460268) (xy 85.756608 -498.467906) (xy 85.682082 -498.476335)
			(xy 85.607083 -498.476882) (xy 85.532442 -498.469539) (xy 85.458986 -498.454389) (xy 85.387531 -498.431599)
			(xy 85.318868 -498.401423) (xy 85.253759 -498.364194) (xy 85.192925 -498.320325) (xy 85.137041 -498.270304)
			(xy 85.086727 -498.214683) (xy 85.042539 -498.15408) (xy 85.004969 -498.089168) (xy 84.974432 -498.020664)
			(xy 84.951268 -497.94933) (xy 84.935732 -497.875955) (xy 84.927998 -497.801354) (xy 84.92815 -497.726352)
			(xy 84.936188 -497.651783) (xy 84.952022 -497.578472) (xy 84.975477 -497.507232) (xy 85.006292 -497.438854)
			(xy 85.044126 -497.374094) (xy 85.08856 -497.313672) (xy 85.1391 -497.258257) (xy 85.195187 -497.208463)
			(xy 85.256199 -497.164842) (xy 85.321459 -497.127878) (xy 85.355684 -497.112544) (xy 85.376099 -497.103121)
			(xy 85.413511 -497.078186) (xy 85.445951 -497.047056) (xy 85.472407 -497.010704) (xy 85.492054 -496.970264)
			(xy 85.504279 -496.926998) (xy 85.508699 -496.882256) (xy 85.505178 -496.837434) (xy 85.493825 -496.793931)
			(xy 85.474994 -496.753105) (xy 85.449273 -496.716229) (xy 85.433662 -496.700048) (xy 84.933282 -496.199668)
			(xy 84.111592 -495.377724) (xy 84.111592 -489.617258) (xy 84.09559 -489.588556) (xy 84.082676 -489.564216)
			(xy 84.063214 -489.512667) (xy 84.051372 -489.458855) (xy 84.047398 -489.403898) (xy 84.051373 -489.348942)
			(xy 84.063215 -489.295129) (xy 84.082677 -489.243581) (xy 84.09559 -489.21924) (xy 84.111592 -489.190538)
			(xy 84.111592 -487.226102) (xy 84.111092 -487.209419) (xy 84.102435 -487.177195) (xy 84.085714 -487.148321)
			(xy 84.074254 -487.136186) (xy 84.016342 -487.078528) (xy 83.991704 -487.05389) (xy 83.991704 -467.551008)
			(xy 82.837528 -466.396832) (xy 82.837528 -466.336634) (xy 82.697828 -466.19668) (xy 82.697828 -449.930266)
			(xy 80.668114 -447.900552) (xy 42.490136 -447.900552) (xy 42.480738 -447.891408) (xy 42.44086 -447.891408)
			(xy 38.409118 -443.859666) (xy 28.382214 -443.859666) (xy 23.188168 -438.66562) (xy 23.188168 -426.145706)
			(xy 23.187674 -426.129052) (xy 23.179053 -426.09688) (xy 23.162398 -426.068036) (xy 23.138844 -426.044486)
			(xy 23.109996 -426.027837) (xy 23.077822 -426.019223) (xy 23.061168 -426.018706) (xy 22.369018 -426.018706)
			(xy 12.453874 -435.93385) (xy 12.439396 -436.01132) (xy 12.455398 -436.047134) (xy 12.474005 -436.090467)
			(xy 12.504634 -436.179668) (xy 12.527552 -436.271154) (xy 12.542592 -436.36426) (xy 12.549645 -436.458309)
			(xy 12.54866 -436.552617) (xy 12.539643 -436.646498) (xy 12.522661 -436.73927) (xy 12.497837 -436.830257)
			(xy 12.465352 -436.918799) (xy 12.425441 -437.004251) (xy 12.378395 -437.085993) (xy 12.324556 -437.163428)
			(xy 12.264315 -437.235996) (xy 12.198111 -437.303167) (xy 12.126425 -437.364454) (xy 12.049778 -437.41941)
			(xy 11.968728 -437.467637) (xy 11.883863 -437.508783) (xy 11.795802 -437.542549) (xy 11.705184 -437.56869)
			(xy 11.612668 -437.587015) (xy 11.518928 -437.597392) (xy 11.424644 -437.599745) (xy 11.330503 -437.594057)
			(xy 11.237188 -437.580368) (xy 11.14538 -437.55878) (xy 11.055744 -437.529448) (xy 10.968933 -437.492586)
			(xy 10.885578 -437.448462) (xy 10.806285 -437.397397) (xy 10.731631 -437.339762) (xy 10.662159 -437.275977)
			(xy 10.598374 -437.206505) (xy 10.54074 -437.131851) (xy 10.489675 -437.052558) (xy 10.445552 -436.969203)
			(xy 10.40869 -436.882391) (xy 10.379359 -436.792755) (xy 10.357771 -436.700946) (xy 10.344083 -436.607632)
			(xy 10.338395 -436.51349) (xy 10.340748 -436.419207) (xy 10.351126 -436.325466) (xy 10.369452 -436.232951)
			(xy 10.395593 -436.142333) (xy 10.42936 -436.054272) (xy 10.470506 -435.969408) (xy 10.518733 -435.888358)
			(xy 10.57369 -435.811711) (xy 10.634977 -435.740025) (xy 10.702148 -435.673822) (xy 10.774716 -435.613581)
			(xy 10.852152 -435.559743) (xy 10.933893 -435.512697) (xy 11.019346 -435.472786) (xy 11.107888 -435.440301)
			(xy 11.198875 -435.415478) (xy 11.291647 -435.398496) (xy 11.385528 -435.38948) (xy 11.479836 -435.388495)
			(xy 11.573885 -435.395549) (xy 11.666991 -435.410589) (xy 11.758477 -435.433508) (xy 11.847678 -435.464137)
			(xy 11.89101 -435.482746) (xy 11.926824 -435.498748) (xy 12.004294 -435.48427) (xy 22.81682 -424.671744)
			(xy 22.81682 -380.926848) (xy 12.1666 -370.276628) (xy 12.1666 -342.652096) (xy 12.164324 -342.630281)
			(xy 12.153251 -342.587846) (xy 12.135069 -342.547936) (xy 12.110317 -342.511732) (xy 12.079727 -342.480306)
			(xy 12.044203 -342.454587) (xy 12.004797 -342.435336) (xy 11.962676 -342.423123) (xy 11.919084 -342.41831)
			(xy 11.875313 -342.421038) (xy 11.832656 -342.431227) (xy 11.792377 -342.448576) (xy 11.755667 -342.472571)
			(xy 11.739372 -342.48725) (xy 11.57859 -342.648032) (xy 8.846312 -342.648032) (xy 8.751824 -342.74252)
			(xy 8.736348 -342.758661) (xy 8.710753 -342.795323) (xy 8.691969 -342.835899) (xy 8.680578 -342.879137)
			(xy 8.67693 -342.9237) (xy 8.681138 -342.968215) (xy 8.693072 -343.011305) (xy 8.712365 -343.051642)
			(xy 8.738419 -343.087979) (xy 8.770431 -343.119196) (xy 8.788654 -343.132156) (xy 8.81854 -343.151578)
			(xy 8.874214 -343.196086) (xy 8.924558 -343.246544) (xy 8.968941 -343.302318) (xy 9.006805 -343.362707)
			(xy 9.037675 -343.426954) (xy 9.061162 -343.494251) (xy 9.076973 -343.563753) (xy 9.084908 -343.634588)
			(xy 9.084868 -343.705866) (xy 9.076853 -343.776692) (xy 9.060964 -343.846176) (xy 9.037401 -343.913447)
			(xy 9.006459 -343.977659) (xy 8.968527 -344.038006) (xy 8.924082 -344.093729) (xy 8.873681 -344.144131)
			(xy 8.817957 -344.188576) (xy 8.757611 -344.226508) (xy 8.693399 -344.25745) (xy 8.626128 -344.281014)
			(xy 8.556644 -344.296903) (xy 8.485818 -344.304918) (xy 8.41454 -344.304958) (xy 8.343705 -344.297023)
			(xy 8.274203 -344.281213) (xy 8.206905 -344.257725) (xy 8.142659 -344.226856) (xy 8.082269 -344.188992)
			(xy 8.026495 -344.144609) (xy 7.976037 -344.094265) (xy 7.931529 -344.038592) (xy 7.9121 -344.00871)
			(xy 7.899145 -343.990483) (xy 7.867929 -343.958469) (xy 7.831591 -343.932413) (xy 7.791254 -343.91312)
			(xy 7.748162 -343.901185) (xy 7.703646 -343.896978) (xy 7.659081 -343.900627) (xy 7.615843 -343.91202)
			(xy 7.575267 -343.930805) (xy 7.538605 -343.956403) (xy 7.522464 -343.97188) (xy 7.342124 -344.15222)
			(xy 7.299198 -344.15222) (xy 7.275774 -344.152756) (xy 7.229718 -344.161343) (xy 7.186017 -344.178226)
			(xy 7.146151 -344.202832) (xy 7.111469 -344.234329) (xy 7.083148 -344.271648) (xy 7.062147 -344.313526)
			(xy 7.049177 -344.358544) (xy 7.044678 -344.405176) (xy 7.048802 -344.451843) (xy 7.054596 -344.474546)
			(xy 7.064966 -344.508198) (xy 7.079068 -344.577193) (xy 7.085457 -344.647324) (xy 7.084054 -344.717732)
			(xy 7.074875 -344.787553) (xy 7.058034 -344.855931) (xy 7.033738 -344.922028) (xy 7.002283 -344.985034)
			(xy 6.964056 -345.044177) (xy 6.919524 -345.098731) (xy 6.869235 -345.148028) (xy 6.813804 -345.191463)
			(xy 6.753912 -345.228504) (xy 6.690291 -345.258697) (xy 6.623723 -345.281672) (xy 6.555023 -345.297146)
			(xy 6.485033 -345.304931) (xy 6.414611 -345.304931) (xy 6.344621 -345.297146) (xy 6.275921 -345.281672)
			(xy 6.209353 -345.258697) (xy 6.145732 -345.228504) (xy 6.08584 -345.191463) (xy 6.030409 -345.148028)
			(xy 5.98012 -345.098731) (xy 5.935588 -345.044177) (xy 5.897361 -344.985034) (xy 5.865906 -344.922028)
			(xy 5.84161 -344.855931) (xy 5.824769 -344.787553) (xy 5.81559 -344.717732) (xy 5.814187 -344.647324)
			(xy 5.820576 -344.577193) (xy 5.834678 -344.508198) (xy 5.845048 -344.474546) (xy 5.850831 -344.451842)
			(xy 5.854949 -344.405178) (xy 5.850446 -344.35855) (xy 5.837474 -344.313536) (xy 5.816473 -344.271662)
			(xy 5.788155 -344.234345) (xy 5.753477 -344.202849) (xy 5.713615 -344.178242) (xy 5.669919 -344.161356)
			(xy 5.623869 -344.152763) (xy 5.600446 -344.15222) (xy 4.79933 -344.15222) (xy 4.775903 -344.152754)
			(xy 4.729843 -344.161336) (xy 4.686137 -344.178216) (xy 4.646265 -344.202822) (xy 4.611579 -344.234319)
			(xy 4.583254 -344.27164) (xy 4.562249 -344.313521) (xy 4.549278 -344.358542) (xy 4.544778 -344.405179)
			(xy 4.548903 -344.45185) (xy 4.554728 -344.474546) (xy 4.564986 -344.507865) (xy 4.579019 -344.576158)
			(xy 4.585502 -344.645575) (xy 4.584358 -344.715285) (xy 4.575602 -344.784452) (xy 4.567936 -344.818462)
			(xy 4.559108 -344.853101) (xy 4.534704 -344.920292) (xy 4.502915 -344.984321) (xy 4.464142 -345.044378)
			(xy 4.418875 -345.099705) (xy 4.367685 -345.149603) (xy 4.311219 -345.193442) (xy 4.250191 -345.230668)
			(xy 4.185371 -345.260811) (xy 4.15163 -345.272614) (xy 4.117705 -345.283428) (xy 4.048072 -345.298319)
			(xy 4.012692 -345.302332) (xy 3.978556 -345.305257) (xy 3.910042 -345.304642) (xy 3.841991 -345.296662)
			(xy 3.775193 -345.281411) (xy 3.710423 -345.259064) (xy 3.648432 -345.229882) (xy 3.589938 -345.194202)
			(xy 3.535621 -345.152439) (xy 3.510534 -345.129104) (xy 3.484522 -345.103506) (xy 3.437921 -345.047337)
			(xy 3.398061 -344.986201) (xy 3.365465 -344.920902) (xy 3.340562 -344.852299) (xy 3.323682 -344.781295)
			(xy 3.315045 -344.708825) (xy 3.314765 -344.635842) (xy 3.318256 -344.599514) (xy 3.322701 -344.564021)
			(xy 3.33855 -344.494265) (xy 3.362122 -344.426726) (xy 3.377184 -344.394282) (xy 3.3897 -344.369066)
			(xy 3.418575 -344.320737) (xy 3.434842 -344.297762) (xy 3.446018 -344.282268) (xy 3.459734 -344.241628)
			(xy 3.464844 -344.224718) (xy 3.466546 -344.189449) (xy 3.458506 -344.155065) (xy 3.441342 -344.124207)
			(xy 3.429254 -344.111326) (xy 3.305556 -343.987628) (xy 2.567686 -343.987628) (xy 2.466848 -344.040206)
			(xy 2.44602 -344.067384) (xy 2.423611 -344.094577) (xy 2.373723 -344.144344) (xy 2.318633 -344.188284)
			(xy 2.259018 -344.225856) (xy 2.195611 -344.256599) (xy 2.162556 -344.268806) (xy 2.130548 -344.279692)
			(xy 2.064791 -344.295418) (xy 1.997736 -344.304073) (xy 1.93014 -344.305561) (xy 1.862769 -344.299865)
			(xy 1.796384 -344.287049) (xy 1.731734 -344.267258) (xy 1.66955 -344.240715) (xy 1.639824 -344.22461)
			(xy 1.620355 -344.215128) (xy 1.579026 -344.202203) (xy 1.536104 -344.196472) (xy 1.492832 -344.198099)
			(xy 1.450463 -344.207039) (xy 1.410221 -344.223031) (xy 1.373274 -344.245614) (xy 1.340689 -344.274134)
			(xy 1.313411 -344.307764) (xy 1.292228 -344.345532) (xy 1.277755 -344.386344) (xy 1.270409 -344.429019)
			(xy 1.27 -344.45067) (xy 1.27 -344.889074) (xy 1.270438 -344.910724) (xy 1.277779 -344.953398) (xy 1.292249 -344.994209)
			(xy 1.313428 -345.031976) (xy 1.340704 -345.065606) (xy 1.373285 -345.094125) (xy 1.410231 -345.116708)
			(xy 1.450469 -345.132701) (xy 1.492837 -345.14164) (xy 1.536107 -345.143267) (xy 1.579026 -345.137535)
			(xy 1.620352 -345.124609) (xy 1.639824 -345.115134) (xy 1.671264 -345.098114) (xy 1.737191 -345.070449)
			(xy 1.805806 -345.050357) (xy 1.876243 -345.038093) (xy 1.947611 -345.033811) (xy 2.019008 -345.037566)
			(xy 2.089533 -345.049309) (xy 2.158295 -345.068893) (xy 2.224425 -345.096071) (xy 2.287086 -345.130498)
			(xy 2.345488 -345.17174) (xy 2.398893 -345.219276) (xy 2.446626 -345.272504) (xy 2.488083 -345.330754)
			(xy 2.522742 -345.393288) (xy 2.550163 -345.459317) (xy 2.570001 -345.528005) (xy 2.582005 -345.598487)
			(xy 2.586023 -345.66987) (xy 2.584016 -345.705531) (xy 7.81481 -345.705531) (xy 7.81481 -345.634209)
			(xy 7.822796 -345.563335) (xy 7.838666 -345.4938) (xy 7.862223 -345.42648) (xy 7.893168 -345.362221)
			(xy 7.931114 -345.30183) (xy 7.975583 -345.246068) (xy 8.026016 -345.195635) (xy 8.081778 -345.151166)
			(xy 8.142169 -345.11322) (xy 8.206428 -345.082275) (xy 8.273748 -345.058718) (xy 8.343283 -345.042848)
			(xy 8.414157 -345.034862) (xy 8.485479 -345.034862) (xy 8.556353 -345.042848) (xy 8.625888 -345.058718)
			(xy 8.693208 -345.082275) (xy 8.757467 -345.11322) (xy 8.817858 -345.151166) (xy 8.87362 -345.195635)
			(xy 8.924053 -345.246068) (xy 8.968522 -345.30183) (xy 9.006468 -345.362221) (xy 9.037413 -345.42648)
			(xy 9.06097 -345.4938) (xy 9.07684 -345.563335) (xy 9.084826 -345.634209) (xy 9.085326 -345.66987)
			(xy 9.084826 -345.705531) (xy 9.07684 -345.776405) (xy 9.06097 -345.84594) (xy 9.037413 -345.91326)
			(xy 9.006468 -345.977519) (xy 8.968522 -346.03791) (xy 8.924053 -346.093672) (xy 8.87362 -346.144105)
			(xy 8.817858 -346.188574) (xy 8.757467 -346.22652) (xy 8.693208 -346.257465) (xy 8.625888 -346.281022)
			(xy 8.556353 -346.296892) (xy 8.485479 -346.304878) (xy 8.414157 -346.304878) (xy 8.343283 -346.296892)
			(xy 8.273748 -346.281022) (xy 8.206428 -346.257465) (xy 8.142169 -346.22652) (xy 8.081778 -346.188574)
			(xy 8.026016 -346.144105) (xy 7.975583 -346.093672) (xy 7.931114 -346.03791) (xy 7.893168 -345.977519)
			(xy 7.862223 -345.91326) (xy 7.838666 -345.84594) (xy 7.822796 -345.776405) (xy 7.81481 -345.705531)
			(xy 2.584016 -345.705531) (xy 2.582005 -345.741253) (xy 2.570001 -345.811735) (xy 2.550163 -345.880423)
			(xy 2.522742 -345.946452) (xy 2.488083 -346.008986) (xy 2.446626 -346.067236) (xy 2.398893 -346.120464)
			(xy 2.345488 -346.168) (xy 2.287086 -346.209242) (xy 2.224425 -346.243669) (xy 2.158295 -346.270847)
			(xy 2.089533 -346.290431) (xy 2.019008 -346.302174) (xy 1.947611 -346.305929) (xy 1.876243 -346.301647)
			(xy 1.805806 -346.289383) (xy 1.737191 -346.269291) (xy 1.671264 -346.241626) (xy 1.639824 -346.224606)
			(xy 1.620355 -346.215124) (xy 1.579026 -346.202199) (xy 1.536104 -346.196468) (xy 1.492832 -346.198096)
			(xy 1.450462 -346.207035) (xy 1.410221 -346.223028) (xy 1.373273 -346.245611) (xy 1.340688 -346.27413)
			(xy 1.313409 -346.30776) (xy 1.292226 -346.345528) (xy 1.277752 -346.38634) (xy 1.270406 -346.429015)
			(xy 1.27 -346.450666) (xy 1.27 -346.705529) (xy 3.314946 -346.705529) (xy 3.314946 -346.634207) (xy 3.322932 -346.563333)
			(xy 3.338802 -346.493798) (xy 3.362359 -346.426478) (xy 3.393304 -346.362219) (xy 3.43125 -346.301828)
			(xy 3.475719 -346.246066) (xy 3.526152 -346.195633) (xy 3.581914 -346.151164) (xy 3.642305 -346.113218)
			(xy 3.706564 -346.082273) (xy 3.773884 -346.058716) (xy 3.843419 -346.042846) (xy 3.914293 -346.03486)
			(xy 3.985615 -346.03486) (xy 4.056489 -346.042846) (xy 4.126024 -346.058716) (xy 4.193344 -346.082273)
			(xy 4.257603 -346.113218) (xy 4.317994 -346.151164) (xy 4.373756 -346.195633) (xy 4.424189 -346.246066)
			(xy 4.468658 -346.301828) (xy 4.506604 -346.362219) (xy 4.537549 -346.426478) (xy 4.561106 -346.493798)
			(xy 4.576976 -346.563333) (xy 4.584962 -346.634207) (xy 4.585462 -346.669868) (xy 4.584962 -346.705529)
			(xy 5.814814 -346.705529) (xy 5.814814 -346.634207) (xy 5.8228 -346.563333) (xy 5.83867 -346.493798)
			(xy 5.862227 -346.426478) (xy 5.893172 -346.362219) (xy 5.931118 -346.301828) (xy 5.975587 -346.246066)
			(xy 6.02602 -346.195633) (xy 6.081782 -346.151164) (xy 6.142173 -346.113218) (xy 6.206432 -346.082273)
			(xy 6.273752 -346.058716) (xy 6.343287 -346.042846) (xy 6.414161 -346.03486) (xy 6.485483 -346.03486)
			(xy 6.556357 -346.042846) (xy 6.625892 -346.058716) (xy 6.693212 -346.082273) (xy 6.757471 -346.113218)
			(xy 6.817862 -346.151164) (xy 6.873624 -346.195633) (xy 6.924057 -346.246066) (xy 6.968526 -346.301828)
			(xy 7.006472 -346.362219) (xy 7.037417 -346.426478) (xy 7.060974 -346.493798) (xy 7.076844 -346.563333)
			(xy 7.08483 -346.634207) (xy 7.08533 -346.669868) (xy 7.08483 -346.705529) (xy 7.076844 -346.776403)
			(xy 7.060974 -346.845938) (xy 7.037417 -346.913258) (xy 7.006472 -346.977517) (xy 6.968526 -347.037908)
			(xy 6.924057 -347.09367) (xy 6.873624 -347.144103) (xy 6.817862 -347.188572) (xy 6.757471 -347.226518)
			(xy 6.693212 -347.257463) (xy 6.625892 -347.28102) (xy 6.556357 -347.29689) (xy 6.485483 -347.304876)
			(xy 6.414161 -347.304876) (xy 6.343287 -347.29689) (xy 6.273752 -347.28102) (xy 6.206432 -347.257463)
			(xy 6.142173 -347.226518) (xy 6.081782 -347.188572) (xy 6.02602 -347.144103) (xy 5.975587 -347.09367)
			(xy 5.931118 -347.037908) (xy 5.893172 -346.977517) (xy 5.862227 -346.913258) (xy 5.83867 -346.845938)
			(xy 5.8228 -346.776403) (xy 5.814814 -346.705529) (xy 4.584962 -346.705529) (xy 4.576976 -346.776403)
			(xy 4.561106 -346.845938) (xy 4.537549 -346.913258) (xy 4.506604 -346.977517) (xy 4.468658 -347.037908)
			(xy 4.424189 -347.09367) (xy 4.373756 -347.144103) (xy 4.317994 -347.188572) (xy 4.257603 -347.226518)
			(xy 4.193344 -347.257463) (xy 4.126024 -347.28102) (xy 4.056489 -347.29689) (xy 3.985615 -347.304876)
			(xy 3.914293 -347.304876) (xy 3.843419 -347.29689) (xy 3.773884 -347.28102) (xy 3.706564 -347.257463)
			(xy 3.642305 -347.226518) (xy 3.581914 -347.188572) (xy 3.526152 -347.144103) (xy 3.475719 -347.09367)
			(xy 3.43125 -347.037908) (xy 3.393304 -346.977517) (xy 3.362359 -346.913258) (xy 3.338802 -346.845938)
			(xy 3.322932 -346.776403) (xy 3.314946 -346.705529) (xy 1.27 -346.705529) (xy 1.27 -346.88907) (xy 1.270438 -346.91072)
			(xy 1.277779 -346.953394) (xy 1.292248 -346.994206) (xy 1.313427 -347.031974) (xy 1.340702 -347.065605)
			(xy 1.373284 -347.094125) (xy 1.41023 -347.116708) (xy 1.450469 -347.1327) (xy 1.492837 -347.14164)
			(xy 1.536107 -347.143267) (xy 1.579027 -347.137535) (xy 1.620354 -347.124609) (xy 1.639824 -347.11513)
			(xy 1.671264 -347.09811) (xy 1.737191 -347.070445) (xy 1.805806 -347.050354) (xy 1.876242 -347.03809)
			(xy 1.94761 -347.033808) (xy 2.019007 -347.037563) (xy 2.089532 -347.049306) (xy 2.158294 -347.068891)
			(xy 2.224423 -347.096068) (xy 2.287084 -347.130495) (xy 2.345486 -347.171737) (xy 2.398891 -347.219273)
			(xy 2.446623 -347.272501) (xy 2.488081 -347.330751) (xy 2.522739 -347.393285) (xy 2.55016 -347.459313)
			(xy 2.569998 -347.528002) (xy 2.582002 -347.598483) (xy 2.58602 -347.669866) (xy 2.584013 -347.705527)
			(xy 7.81481 -347.705527) (xy 7.81481 -347.634205) (xy 7.822796 -347.563331) (xy 7.838666 -347.493796)
			(xy 7.862223 -347.426476) (xy 7.893168 -347.362217) (xy 7.931114 -347.301826) (xy 7.975583 -347.246064)
			(xy 8.026016 -347.195631) (xy 8.081778 -347.151162) (xy 8.142169 -347.113216) (xy 8.206428 -347.082271)
			(xy 8.273748 -347.058714) (xy 8.343283 -347.042844) (xy 8.414157 -347.034858) (xy 8.485479 -347.034858)
			(xy 8.556353 -347.042844) (xy 8.625888 -347.058714) (xy 8.693208 -347.082271) (xy 8.757467 -347.113216)
			(xy 8.817858 -347.151162) (xy 8.87362 -347.195631) (xy 8.924053 -347.246064) (xy 8.968522 -347.301826)
			(xy 9.006468 -347.362217) (xy 9.037413 -347.426476) (xy 9.06097 -347.493796) (xy 9.07684 -347.563331)
			(xy 9.084826 -347.634205) (xy 9.085326 -347.669866) (xy 9.084826 -347.705527) (xy 9.07684 -347.776401)
			(xy 9.06097 -347.845936) (xy 9.037413 -347.913256) (xy 9.006468 -347.977515) (xy 8.968522 -348.037906)
			(xy 8.924053 -348.093668) (xy 8.87362 -348.144101) (xy 8.817858 -348.18857) (xy 8.757467 -348.226516)
			(xy 8.693208 -348.257461) (xy 8.625888 -348.281018) (xy 8.556353 -348.296888) (xy 8.485479 -348.304874)
			(xy 8.414157 -348.304874) (xy 8.343283 -348.296888) (xy 8.273748 -348.281018) (xy 8.206428 -348.257461)
			(xy 8.142169 -348.226516) (xy 8.081778 -348.18857) (xy 8.026016 -348.144101) (xy 7.975583 -348.093668)
			(xy 7.931114 -348.037906) (xy 7.893168 -347.977515) (xy 7.862223 -347.913256) (xy 7.838666 -347.845936)
			(xy 7.822796 -347.776401) (xy 7.81481 -347.705527) (xy 2.584013 -347.705527) (xy 2.582002 -347.741249)
			(xy 2.569998 -347.81173) (xy 2.55016 -347.880419) (xy 2.522739 -347.946447) (xy 2.488081 -348.008981)
			(xy 2.446623 -348.067231) (xy 2.398891 -348.120459) (xy 2.345486 -348.167995) (xy 2.287084 -348.209237)
			(xy 2.224423 -348.243664) (xy 2.158294 -348.270841) (xy 2.089532 -348.290426) (xy 2.019007 -348.302169)
			(xy 1.94761 -348.305924) (xy 1.876242 -348.301642) (xy 1.805806 -348.289378) (xy 1.737191 -348.269287)
			(xy 1.671264 -348.241622) (xy 1.639824 -348.224602) (xy 1.620354 -348.21512) (xy 1.579025 -348.202196)
			(xy 1.536103 -348.196465) (xy 1.492831 -348.198092) (xy 1.450461 -348.207032) (xy 1.41022 -348.223024)
			(xy 1.373272 -348.245607) (xy 1.340687 -348.274126) (xy 1.313408 -348.307756) (xy 1.292224 -348.345524)
			(xy 1.277749 -348.386336) (xy 1.270402 -348.429011) (xy 1.27 -348.450662) (xy 1.27 -348.705525) (xy 3.314946 -348.705525)
			(xy 3.314946 -348.634203) (xy 3.322932 -348.563329) (xy 3.338802 -348.493794) (xy 3.362359 -348.426474)
			(xy 3.393304 -348.362215) (xy 3.43125 -348.301824) (xy 3.475719 -348.246062) (xy 3.526152 -348.195629)
			(xy 3.581914 -348.15116) (xy 3.642305 -348.113214) (xy 3.706564 -348.082269) (xy 3.773884 -348.058712)
			(xy 3.843419 -348.042842) (xy 3.914293 -348.034856) (xy 3.985615 -348.034856) (xy 4.056489 -348.042842)
			(xy 4.126024 -348.058712) (xy 4.193344 -348.082269) (xy 4.257603 -348.113214) (xy 4.317994 -348.15116)
			(xy 4.373756 -348.195629) (xy 4.424189 -348.246062) (xy 4.468658 -348.301824) (xy 4.506604 -348.362215)
			(xy 4.537549 -348.426474) (xy 4.561106 -348.493794) (xy 4.576976 -348.563329) (xy 4.584962 -348.634203)
			(xy 4.585462 -348.669864) (xy 4.584962 -348.705525) (xy 5.814814 -348.705525) (xy 5.814814 -348.634203)
			(xy 5.8228 -348.563329) (xy 5.83867 -348.493794) (xy 5.862227 -348.426474) (xy 5.893172 -348.362215)
			(xy 5.931118 -348.301824) (xy 5.975587 -348.246062) (xy 6.02602 -348.195629) (xy 6.081782 -348.15116)
			(xy 6.142173 -348.113214) (xy 6.206432 -348.082269) (xy 6.273752 -348.058712) (xy 6.343287 -348.042842)
			(xy 6.414161 -348.034856) (xy 6.485483 -348.034856) (xy 6.556357 -348.042842) (xy 6.625892 -348.058712)
			(xy 6.693212 -348.082269) (xy 6.757471 -348.113214) (xy 6.817862 -348.15116) (xy 6.873624 -348.195629)
			(xy 6.924057 -348.246062) (xy 6.968526 -348.301824) (xy 7.006472 -348.362215) (xy 7.037417 -348.426474)
			(xy 7.060974 -348.493794) (xy 7.076844 -348.563329) (xy 7.08483 -348.634203) (xy 7.08533 -348.669864)
			(xy 7.08483 -348.705525) (xy 7.076844 -348.776399) (xy 7.060974 -348.845934) (xy 7.037417 -348.913254)
			(xy 7.006472 -348.977513) (xy 6.968526 -349.037904) (xy 6.924057 -349.093666) (xy 6.873624 -349.144099)
			(xy 6.817862 -349.188568) (xy 6.757471 -349.226514) (xy 6.693212 -349.257459) (xy 6.625892 -349.281016)
			(xy 6.556357 -349.296886) (xy 6.485483 -349.304872) (xy 6.414161 -349.304872) (xy 6.343287 -349.296886)
			(xy 6.273752 -349.281016) (xy 6.206432 -349.257459) (xy 6.142173 -349.226514) (xy 6.081782 -349.188568)
			(xy 6.02602 -349.144099) (xy 5.975587 -349.093666) (xy 5.931118 -349.037904) (xy 5.893172 -348.977513)
			(xy 5.862227 -348.913254) (xy 5.83867 -348.845934) (xy 5.8228 -348.776399) (xy 5.814814 -348.705525)
			(xy 4.584962 -348.705525) (xy 4.576976 -348.776399) (xy 4.561106 -348.845934) (xy 4.537549 -348.913254)
			(xy 4.506604 -348.977513) (xy 4.468658 -349.037904) (xy 4.424189 -349.093666) (xy 4.373756 -349.144099)
			(xy 4.317994 -349.188568) (xy 4.257603 -349.226514) (xy 4.193344 -349.257459) (xy 4.126024 -349.281016)
			(xy 4.056489 -349.296886) (xy 3.985615 -349.304872) (xy 3.914293 -349.304872) (xy 3.843419 -349.296886)
			(xy 3.773884 -349.281016) (xy 3.706564 -349.257459) (xy 3.642305 -349.226514) (xy 3.581914 -349.188568)
			(xy 3.526152 -349.144099) (xy 3.475719 -349.093666) (xy 3.43125 -349.037904) (xy 3.393304 -348.977513)
			(xy 3.362359 -348.913254) (xy 3.338802 -348.845934) (xy 3.322932 -348.776399) (xy 3.314946 -348.705525)
			(xy 1.27 -348.705525) (xy 1.27 -348.889066) (xy 1.270438 -348.910716) (xy 1.27778 -348.953389) (xy 1.29225 -348.9942)
			(xy 1.313429 -349.031967) (xy 1.340704 -349.065597) (xy 1.373286 -349.094116) (xy 1.410231 -349.116698)
			(xy 1.45047 -349.132691) (xy 1.492837 -349.14163) (xy 1.536106 -349.143257) (xy 1.579026 -349.137525)
			(xy 1.620352 -349.1246) (xy 1.639824 -349.115126) (xy 1.671264 -349.098106) (xy 1.737191 -349.070441)
			(xy 1.805806 -349.050349) (xy 1.876242 -349.038085) (xy 1.94761 -349.033803) (xy 2.019007 -349.037557)
			(xy 2.089532 -349.049301) (xy 2.158294 -349.068885) (xy 2.224423 -349.096062) (xy 2.287084 -349.130489)
			(xy 2.345487 -349.171731) (xy 2.398891 -349.219266) (xy 2.446624 -349.272495) (xy 2.488081 -349.330744)
			(xy 2.52274 -349.393278) (xy 2.550161 -349.459306) (xy 2.569999 -349.527995) (xy 2.582003 -349.598476)
			(xy 2.586021 -349.669859) (xy 2.584014 -349.705523) (xy 7.81481 -349.705523) (xy 7.81481 -349.634201)
			(xy 7.822796 -349.563327) (xy 7.838666 -349.493792) (xy 7.862223 -349.426472) (xy 7.893168 -349.362213)
			(xy 7.931114 -349.301822) (xy 7.975583 -349.24606) (xy 8.026016 -349.195627) (xy 8.081778 -349.151158)
			(xy 8.142169 -349.113212) (xy 8.206428 -349.082267) (xy 8.273748 -349.05871) (xy 8.343283 -349.04284)
			(xy 8.414157 -349.034854) (xy 8.485479 -349.034854) (xy 8.556353 -349.04284) (xy 8.625888 -349.05871)
			(xy 8.693208 -349.082267) (xy 8.757467 -349.113212) (xy 8.817858 -349.151158) (xy 8.87362 -349.195627)
			(xy 8.924053 -349.24606) (xy 8.968522 -349.301822) (xy 9.006468 -349.362213) (xy 9.037413 -349.426472)
			(xy 9.06097 -349.493792) (xy 9.07684 -349.563327) (xy 9.084826 -349.634201) (xy 9.085326 -349.669862)
			(xy 9.084826 -349.705523) (xy 9.07684 -349.776397) (xy 9.06097 -349.845932) (xy 9.037413 -349.913252)
			(xy 9.006468 -349.977511) (xy 8.968522 -350.037902) (xy 8.924053 -350.093664) (xy 8.87362 -350.144097)
			(xy 8.817858 -350.188566) (xy 8.757467 -350.226512) (xy 8.693208 -350.257457) (xy 8.625888 -350.281014)
			(xy 8.556353 -350.296884) (xy 8.485479 -350.30487) (xy 8.414157 -350.30487) (xy 8.343283 -350.296884)
			(xy 8.273748 -350.281014) (xy 8.206428 -350.257457) (xy 8.142169 -350.226512) (xy 8.081778 -350.188566)
			(xy 8.026016 -350.144097) (xy 7.975583 -350.093664) (xy 7.931114 -350.037902) (xy 7.893168 -349.977511)
			(xy 7.862223 -349.913252) (xy 7.838666 -349.845932) (xy 7.822796 -349.776397) (xy 7.81481 -349.705523)
			(xy 2.584014 -349.705523) (xy 2.582003 -349.741242) (xy 2.569999 -349.811723) (xy 2.550162 -349.880412)
			(xy 2.52274 -349.94644) (xy 2.488082 -350.008974) (xy 2.446625 -350.067224) (xy 2.398893 -350.120453)
			(xy 2.345488 -350.167988) (xy 2.287086 -350.20923) (xy 2.224425 -350.243657) (xy 2.158295 -350.270835)
			(xy 2.089534 -350.290419) (xy 2.019009 -350.302162) (xy 1.947612 -350.305917) (xy 1.876244 -350.301635)
			(xy 1.805808 -350.289371) (xy 1.737193 -350.26928) (xy 1.671266 -350.241615) (xy 1.639824 -350.224598)
			(xy 1.620354 -350.215116) (xy 1.579025 -350.202192) (xy 1.536103 -350.196461) (xy 1.492831 -350.198089)
			(xy 1.450461 -350.207028) (xy 1.410219 -350.223021) (xy 1.373271 -350.245603) (xy 1.340685 -350.274122)
			(xy 1.313406 -350.307752) (xy 1.292222 -350.34552) (xy 1.277747 -350.386332) (xy 1.270399 -350.429007)
			(xy 1.27 -350.450658) (xy 1.27 -350.705521) (xy 3.314946 -350.705521) (xy 3.314946 -350.634199) (xy 3.322932 -350.563325)
			(xy 3.338802 -350.49379) (xy 3.362359 -350.42647) (xy 3.393304 -350.362211) (xy 3.43125 -350.30182)
			(xy 3.475719 -350.246058) (xy 3.526152 -350.195625) (xy 3.581914 -350.151156) (xy 3.642305 -350.11321)
			(xy 3.706564 -350.082265) (xy 3.773884 -350.058708) (xy 3.843419 -350.042838) (xy 3.914293 -350.034852)
			(xy 3.985615 -350.034852) (xy 4.056489 -350.042838) (xy 4.126024 -350.058708) (xy 4.193344 -350.082265)
			(xy 4.257603 -350.11321) (xy 4.317994 -350.151156) (xy 4.373756 -350.195625) (xy 4.424189 -350.246058)
			(xy 4.468658 -350.30182) (xy 4.506604 -350.362211) (xy 4.537549 -350.42647) (xy 4.561106 -350.49379)
			(xy 4.576976 -350.563325) (xy 4.584962 -350.634199) (xy 4.585462 -350.66986) (xy 4.584962 -350.705521)
			(xy 5.814814 -350.705521) (xy 5.814814 -350.634199) (xy 5.8228 -350.563325) (xy 5.83867 -350.49379)
			(xy 5.862227 -350.42647) (xy 5.893172 -350.362211) (xy 5.931118 -350.30182) (xy 5.975587 -350.246058)
			(xy 6.02602 -350.195625) (xy 6.081782 -350.151156) (xy 6.142173 -350.11321) (xy 6.206432 -350.082265)
			(xy 6.273752 -350.058708) (xy 6.343287 -350.042838) (xy 6.414161 -350.034852) (xy 6.485483 -350.034852)
			(xy 6.556357 -350.042838) (xy 6.625892 -350.058708) (xy 6.693212 -350.082265) (xy 6.757471 -350.11321)
			(xy 6.817862 -350.151156) (xy 6.873624 -350.195625) (xy 6.924057 -350.246058) (xy 6.968526 -350.30182)
			(xy 7.006472 -350.362211) (xy 7.037417 -350.42647) (xy 7.060974 -350.49379) (xy 7.076844 -350.563325)
			(xy 7.08483 -350.634199) (xy 7.08533 -350.66986) (xy 7.08483 -350.705521) (xy 7.076844 -350.776395)
			(xy 7.060974 -350.84593) (xy 7.037417 -350.91325) (xy 7.006472 -350.977509) (xy 6.968526 -351.0379)
			(xy 6.924057 -351.093662) (xy 6.873624 -351.144095) (xy 6.817862 -351.188564) (xy 6.757471 -351.22651)
			(xy 6.693212 -351.257455) (xy 6.625892 -351.281012) (xy 6.556357 -351.296882) (xy 6.485483 -351.304868)
			(xy 6.414161 -351.304868) (xy 6.343287 -351.296882) (xy 6.273752 -351.281012) (xy 6.206432 -351.257455)
			(xy 6.142173 -351.22651) (xy 6.081782 -351.188564) (xy 6.02602 -351.144095) (xy 5.975587 -351.093662)
			(xy 5.931118 -351.0379) (xy 5.893172 -350.977509) (xy 5.862227 -350.91325) (xy 5.83867 -350.84593)
			(xy 5.8228 -350.776395) (xy 5.814814 -350.705521) (xy 4.584962 -350.705521) (xy 4.576976 -350.776395)
			(xy 4.561106 -350.84593) (xy 4.537549 -350.91325) (xy 4.506604 -350.977509) (xy 4.468658 -351.0379)
			(xy 4.424189 -351.093662) (xy 4.373756 -351.144095) (xy 4.317994 -351.188564) (xy 4.257603 -351.22651)
			(xy 4.193344 -351.257455) (xy 4.126024 -351.281012) (xy 4.056489 -351.296882) (xy 3.985615 -351.304868)
			(xy 3.914293 -351.304868) (xy 3.843419 -351.296882) (xy 3.773884 -351.281012) (xy 3.706564 -351.257455)
			(xy 3.642305 -351.22651) (xy 3.581914 -351.188564) (xy 3.526152 -351.144095) (xy 3.475719 -351.093662)
			(xy 3.43125 -351.0379) (xy 3.393304 -350.977509) (xy 3.362359 -350.91325) (xy 3.338802 -350.84593)
			(xy 3.322932 -350.776395) (xy 3.314946 -350.705521) (xy 1.27 -350.705521) (xy 1.27 -350.889062) (xy 1.270438 -350.910712)
			(xy 1.277779 -350.953386) (xy 1.292249 -350.994198) (xy 1.313428 -351.031965) (xy 1.340703 -351.065596)
			(xy 1.373285 -351.094115) (xy 1.41023 -351.116698) (xy 1.450469 -351.132691) (xy 1.492837 -351.14163)
			(xy 1.536107 -351.143257) (xy 1.579027 -351.137525) (xy 1.620353 -351.124599) (xy 1.639824 -351.115122)
			(xy 1.671264 -351.098102) (xy 1.737191 -351.070437) (xy 1.805807 -351.050345) (xy 1.876243 -351.038081)
			(xy 1.947612 -351.033799) (xy 2.019009 -351.037554) (xy 2.089535 -351.049298) (xy 2.158297 -351.068882)
			(xy 2.224426 -351.09606) (xy 2.287088 -351.130487) (xy 2.34549 -351.171729) (xy 2.398895 -351.219265)
			(xy 2.446628 -351.272494) (xy 2.488085 -351.330744) (xy 2.522744 -351.393278) (xy 2.550165 -351.459307)
			(xy 2.570003 -351.527996) (xy 2.582007 -351.598478) (xy 2.586025 -351.669861) (xy 2.584018 -351.705519)
			(xy 7.81481 -351.705519) (xy 7.81481 -351.634197) (xy 7.822796 -351.563323) (xy 7.838666 -351.493788)
			(xy 7.862223 -351.426468) (xy 7.893168 -351.362209) (xy 7.931114 -351.301818) (xy 7.975583 -351.246056)
			(xy 8.026016 -351.195623) (xy 8.081778 -351.151154) (xy 8.142169 -351.113208) (xy 8.206428 -351.082263)
			(xy 8.273748 -351.058706) (xy 8.343283 -351.042836) (xy 8.414157 -351.03485) (xy 8.485479 -351.03485)
			(xy 8.556353 -351.042836) (xy 8.625888 -351.058706) (xy 8.693208 -351.082263) (xy 8.757467 -351.113208)
			(xy 8.817858 -351.151154) (xy 8.87362 -351.195623) (xy 8.924053 -351.246056) (xy 8.968522 -351.301818)
			(xy 9.006468 -351.362209) (xy 9.037413 -351.426468) (xy 9.06097 -351.493788) (xy 9.07684 -351.563323)
			(xy 9.084826 -351.634197) (xy 9.085326 -351.669858) (xy 9.084826 -351.705519) (xy 9.07684 -351.776393)
			(xy 9.06097 -351.845928) (xy 9.037413 -351.913248) (xy 9.006468 -351.977507) (xy 8.968522 -352.037898)
			(xy 8.924053 -352.09366) (xy 8.87362 -352.144093) (xy 8.817858 -352.188562) (xy 8.757467 -352.226508)
			(xy 8.693208 -352.257453) (xy 8.625888 -352.28101) (xy 8.556353 -352.29688) (xy 8.485479 -352.304866)
			(xy 8.414157 -352.304866) (xy 8.343283 -352.29688) (xy 8.273748 -352.28101) (xy 8.206428 -352.257453)
			(xy 8.142169 -352.226508) (xy 8.081778 -352.188562) (xy 8.026016 -352.144093) (xy 7.975583 -352.09366)
			(xy 7.931114 -352.037898) (xy 7.893168 -351.977507) (xy 7.862223 -351.913248) (xy 7.838666 -351.845928)
			(xy 7.822796 -351.776393) (xy 7.81481 -351.705519) (xy 2.584018 -351.705519) (xy 2.582007 -351.741244)
			(xy 2.570002 -351.811726) (xy 2.550164 -351.880415) (xy 2.522743 -351.946444) (xy 2.488084 -352.008978)
			(xy 2.446627 -352.067227) (xy 2.398894 -352.120456) (xy 2.345489 -352.167992) (xy 2.287086 -352.209234)
			(xy 2.224424 -352.243661) (xy 2.158295 -352.270839) (xy 2.089533 -352.290423) (xy 2.019007 -352.302166)
			(xy 1.94761 -352.305921) (xy 1.876242 -352.301639) (xy 1.805805 -352.289374) (xy 1.73719 -352.269282)
			(xy 1.671263 -352.241617) (xy 1.639824 -352.224594) (xy 1.620357 -352.215109) (xy 1.579032 -352.202181)
			(xy 1.536114 -352.196447) (xy 1.492844 -352.198073) (xy 1.450477 -352.207013) (xy 1.410239 -352.223006)
			(xy 1.373296 -352.245591) (xy 1.340717 -352.274113) (xy 1.313445 -352.307746) (xy 1.292272 -352.345516)
			(xy 1.277809 -352.386329) (xy 1.270477 -352.429004) (xy 1.27 -352.450654) (xy 1.27 -352.705517) (xy 3.314946 -352.705517)
			(xy 3.314946 -352.634195) (xy 3.322932 -352.563321) (xy 3.338802 -352.493786) (xy 3.362359 -352.426466)
			(xy 3.393304 -352.362207) (xy 3.43125 -352.301816) (xy 3.475719 -352.246054) (xy 3.526152 -352.195621)
			(xy 3.581914 -352.151152) (xy 3.642305 -352.113206) (xy 3.706564 -352.082261) (xy 3.773884 -352.058704)
			(xy 3.843419 -352.042834) (xy 3.914293 -352.034848) (xy 3.985615 -352.034848) (xy 4.056489 -352.042834)
			(xy 4.126024 -352.058704) (xy 4.193344 -352.082261) (xy 4.257603 -352.113206) (xy 4.317994 -352.151152)
			(xy 4.373756 -352.195621) (xy 4.424189 -352.246054) (xy 4.468658 -352.301816) (xy 4.506604 -352.362207)
			(xy 4.537549 -352.426466) (xy 4.561106 -352.493786) (xy 4.576976 -352.563321) (xy 4.584962 -352.634195)
			(xy 4.585462 -352.669856) (xy 4.584962 -352.705517) (xy 5.814814 -352.705517) (xy 5.814814 -352.634195)
			(xy 5.8228 -352.563321) (xy 5.83867 -352.493786) (xy 5.862227 -352.426466) (xy 5.893172 -352.362207)
			(xy 5.931118 -352.301816) (xy 5.975587 -352.246054) (xy 6.02602 -352.195621) (xy 6.081782 -352.151152)
			(xy 6.142173 -352.113206) (xy 6.206432 -352.082261) (xy 6.273752 -352.058704) (xy 6.343287 -352.042834)
			(xy 6.414161 -352.034848) (xy 6.485483 -352.034848) (xy 6.556357 -352.042834) (xy 6.625892 -352.058704)
			(xy 6.693212 -352.082261) (xy 6.757471 -352.113206) (xy 6.817862 -352.151152) (xy 6.873624 -352.195621)
			(xy 6.924057 -352.246054) (xy 6.968526 -352.301816) (xy 7.006472 -352.362207) (xy 7.037417 -352.426466)
			(xy 7.060974 -352.493786) (xy 7.076844 -352.563321) (xy 7.08483 -352.634195) (xy 7.08533 -352.669856)
			(xy 7.08483 -352.705517) (xy 7.076844 -352.776391) (xy 7.060974 -352.845926) (xy 7.037417 -352.913246)
			(xy 7.006472 -352.977505) (xy 6.968526 -353.037896) (xy 6.924057 -353.093658) (xy 6.873624 -353.144091)
			(xy 6.817862 -353.18856) (xy 6.757471 -353.226506) (xy 6.693212 -353.257451) (xy 6.625892 -353.281008)
			(xy 6.556357 -353.296878) (xy 6.485483 -353.304864) (xy 6.414161 -353.304864) (xy 6.343287 -353.296878)
			(xy 6.273752 -353.281008) (xy 6.206432 -353.257451) (xy 6.142173 -353.226506) (xy 6.081782 -353.18856)
			(xy 6.02602 -353.144091) (xy 5.975587 -353.093658) (xy 5.931118 -353.037896) (xy 5.893172 -352.977505)
			(xy 5.862227 -352.913246) (xy 5.83867 -352.845926) (xy 5.8228 -352.776391) (xy 5.814814 -352.705517)
			(xy 4.584962 -352.705517) (xy 4.576976 -352.776391) (xy 4.561106 -352.845926) (xy 4.537549 -352.913246)
			(xy 4.506604 -352.977505) (xy 4.468658 -353.037896) (xy 4.424189 -353.093658) (xy 4.373756 -353.144091)
			(xy 4.317994 -353.18856) (xy 4.257603 -353.226506) (xy 4.193344 -353.257451) (xy 4.126024 -353.281008)
			(xy 4.056489 -353.296878) (xy 3.985615 -353.304864) (xy 3.914293 -353.304864) (xy 3.843419 -353.296878)
			(xy 3.773884 -353.281008) (xy 3.706564 -353.257451) (xy 3.642305 -353.226506) (xy 3.581914 -353.18856)
			(xy 3.526152 -353.144091) (xy 3.475719 -353.093658) (xy 3.43125 -353.037896) (xy 3.393304 -352.977505)
			(xy 3.362359 -352.913246) (xy 3.338802 -352.845926) (xy 3.322932 -352.776391) (xy 3.314946 -352.705517)
			(xy 1.27 -352.705517) (xy 1.27 -384.79984) (xy 11.345672 -384.79984) (xy 11.346163 -384.696662) (xy 11.354255 -384.490463)
			(xy 11.370436 -384.284742) (xy 11.394682 -384.079814) (xy 11.426955 -383.875996) (xy 11.467204 -383.673603)
			(xy 11.515369 -383.472946) (xy 11.571375 -383.274334) (xy 11.635136 -383.078075) (xy 11.706552 -382.88447)
			(xy 11.785515 -382.693818) (xy 11.871902 -382.506413) (xy 11.96558 -382.322545) (xy 12.066404 -382.142496)
			(xy 12.17422 -381.966544) (xy 12.288861 -381.794961) (xy 12.410149 -381.628012) (xy 12.537899 -381.465952)
			(xy 12.671913 -381.309034) (xy 12.811985 -381.157498) (xy 12.957898 -381.011578) (xy 13.109427 -380.871499)
			(xy 13.266339 -380.737478) (xy 13.428392 -380.60972) (xy 13.595336 -380.488424) (xy 13.766914 -380.373775)
			(xy 13.94286 -380.265951) (xy 14.122904 -380.165117) (xy 14.306768 -380.071431) (xy 14.494169 -379.985035)
			(xy 14.684817 -379.906063) (xy 14.878418 -379.834637) (xy 15.074675 -379.770868) (xy 15.273284 -379.714853)
			(xy 15.473939 -379.666678) (xy 15.67633 -379.626419) (xy 15.880146 -379.594136) (xy 16.085073 -379.569881)
			(xy 16.290794 -379.55369) (xy 16.496992 -379.545588) (xy 16.60017 -379.545088) (xy 16.703348 -379.545592)
			(xy 16.909546 -379.553694) (xy 17.115267 -379.569885) (xy 17.320193 -379.59414) (xy 17.524009 -379.626422)
			(xy 17.726401 -379.666682) (xy 17.927055 -379.714856) (xy 18.125664 -379.770872) (xy 18.32192 -379.834641)
			(xy 18.515522 -379.906067) (xy 18.70617 -379.985039) (xy 18.89357 -380.071434) (xy 19.077434 -380.165121)
			(xy 19.257478 -380.265954) (xy 19.433424 -380.373778) (xy 19.605002 -380.488427) (xy 19.771945 -380.609723)
			(xy 19.933998 -380.737481) (xy 20.09091 -380.871502) (xy 20.24244 -381.011581) (xy 20.388352 -381.157501)
			(xy 20.528424 -381.309037) (xy 20.662438 -381.465955) (xy 20.790187 -381.628014) (xy 20.911476 -381.794964)
			(xy 21.026117 -381.966546) (xy 21.133932 -382.142498) (xy 21.234757 -382.322547) (xy 21.328435 -382.506415)
			(xy 21.414822 -382.693819) (xy 21.493784 -382.884471) (xy 21.565201 -383.078076) (xy 21.628961 -383.274335)
			(xy 21.684967 -383.472947) (xy 21.733132 -383.673604) (xy 21.773381 -383.875997) (xy 21.805654 -384.079815)
			(xy 21.8299 -384.284742) (xy 21.846081 -384.490464) (xy 21.854173 -384.696662) (xy 21.854668 -384.79984)
			(xy 21.854174 -384.901741) (xy 21.846271 -385.105391) (xy 21.830478 -385.30858) (xy 21.806818 -385.511005)
			(xy 21.775327 -385.71236) (xy 21.736052 -385.912342) (xy 21.689051 -386.110651) (xy 21.634397 -386.306989)
			(xy 21.572171 -386.501059) (xy 21.502466 -386.692571) (xy 21.425388 -386.881236) (xy 21.341053 -387.06677)
			(xy 21.249586 -387.248895) (xy 21.151127 -387.427336) (xy 21.045822 -387.601825) (xy 20.933831 -387.7721)
			(xy 20.815321 -387.937904) (xy 20.690471 -388.098988) (xy 20.55947 -388.25511) (xy 20.422513 -388.406034)
			(xy 20.279807 -388.551535) (xy 20.131566 -388.691393) (xy 19.978014 -388.825397) (xy 19.819381 -388.953347)
			(xy 19.655906 -389.07505) (xy 19.487835 -389.190322) (xy 19.315421 -389.29899) (xy 19.138923 -389.400892)
			(xy 18.958606 -389.495872) (xy 18.774742 -389.58379) (xy 18.587607 -389.664512) (xy 18.397483 -389.737917)
			(xy 18.204656 -389.803895) (xy 18.009415 -389.862346) (xy 17.812055 -389.913183) (xy 17.612871 -389.956329)
			(xy 17.412165 -389.991719) (xy 17.210237 -390.0193) (xy 17.007392 -390.03903) (xy 16.803934 -390.05088)
			(xy 16.60017 -390.054832) (xy 16.396406 -390.05088) (xy 16.192948 -390.03903) (xy 15.990103 -390.0193)
			(xy 15.788175 -389.991719) (xy 15.587469 -389.956329) (xy 15.388285 -389.913183) (xy 15.190925 -389.862346)
			(xy 14.995684 -389.803895) (xy 14.802857 -389.737917) (xy 14.612733 -389.664512) (xy 14.425598 -389.58379)
			(xy 14.241734 -389.495872) (xy 14.061417 -389.400892) (xy 13.884919 -389.29899) (xy 13.712505 -389.190322)
			(xy 13.544434 -389.07505) (xy 13.380959 -388.953347) (xy 13.222326 -388.825397) (xy 13.068774 -388.691393)
			(xy 12.920533 -388.551535) (xy 12.777827 -388.406034) (xy 12.64087 -388.25511) (xy 12.509869 -388.098988)
			(xy 12.385019 -387.937904) (xy 12.266509 -387.7721) (xy 12.154518 -387.601825) (xy 12.049213 -387.427336)
			(xy 11.950754 -387.248895) (xy 11.859287 -387.06677) (xy 11.774952 -386.881236) (xy 11.697874 -386.692571)
			(xy 11.628169 -386.501059) (xy 11.565943 -386.306989) (xy 11.511289 -386.110651) (xy 11.464288 -385.912342)
			(xy 11.425013 -385.71236) (xy 11.393522 -385.511005) (xy 11.369862 -385.30858) (xy 11.354069 -385.105391)
			(xy 11.346166 -384.901741) (xy 11.345672 -384.79984) (xy 1.27 -384.79984) (xy 1.27 -396.83182) (xy 2.549396 -396.83182)
			(xy 2.553467 -396.776198) (xy 2.565593 -396.721761) (xy 2.585516 -396.66967) (xy 2.612812 -396.621035)
			(xy 2.646898 -396.576892) (xy 2.687047 -396.538183) (xy 2.732405 -396.505732) (xy 2.782005 -396.480231)
			(xy 2.834789 -396.462224) (xy 2.889632 -396.452094) (xy 2.945366 -396.450057) (xy 3.000803 -396.456157)
			(xy 3.05476 -396.470263) (xy 3.106089 -396.492075) (xy 3.153695 -396.521129) (xy 3.196563 -396.556804)
			(xy 3.23378 -396.598341) (xy 3.264553 -396.644854) (xy 3.288225 -396.695351) (xy 3.304293 -396.748758)
			(xy 3.312413 -396.803934) (xy 3.312922 -396.83182) (xy 3.312413 -396.859706) (xy 3.304293 -396.914882)
			(xy 3.288225 -396.968289) (xy 3.264553 -397.018786) (xy 3.23378 -397.065299) (xy 3.196563 -397.106836)
			(xy 3.153695 -397.142511) (xy 3.106089 -397.171565) (xy 3.05476 -397.193377) (xy 3.000803 -397.207483)
			(xy 2.945366 -397.213583) (xy 2.889632 -397.211546) (xy 2.834789 -397.201416) (xy 2.782005 -397.183409)
			(xy 2.732405 -397.157908) (xy 2.687047 -397.125457) (xy 2.646898 -397.086748) (xy 2.612812 -397.042605)
			(xy 2.585516 -396.99397) (xy 2.565593 -396.941879) (xy 2.553467 -396.887442) (xy 2.549396 -396.83182)
			(xy 1.27 -396.83182) (xy 1.27 -397.307396) (xy 10.22629 -397.307396) (xy 10.22629 -397.204604) (xy 10.234355 -397.10213)
			(xy 10.250435 -397.000605) (xy 10.274431 -396.900654) (xy 10.306196 -396.802894) (xy 10.345532 -396.707927)
			(xy 10.392198 -396.61634) (xy 10.445906 -396.528696) (xy 10.506325 -396.445536) (xy 10.573083 -396.367373)
			(xy 10.645767 -396.294689) (xy 10.72393 -396.227931) (xy 10.80709 -396.167512) (xy 10.894734 -396.113804)
			(xy 10.986321 -396.067138) (xy 11.081288 -396.027802) (xy 11.179048 -395.996037) (xy 11.278999 -395.972041)
			(xy 11.380524 -395.955961) (xy 11.482998 -395.947896) (xy 11.58579 -395.947896) (xy 11.688264 -395.955961)
			(xy 11.789789 -395.972041) (xy 11.88974 -395.996037) (xy 11.9875 -396.027802) (xy 12.082467 -396.067138)
			(xy 12.174054 -396.113804) (xy 12.261698 -396.167512) (xy 12.344858 -396.227931) (xy 12.423021 -396.294689)
			(xy 12.495705 -396.367373) (xy 12.562463 -396.445536) (xy 12.622882 -396.528696) (xy 12.67659 -396.61634)
			(xy 12.723256 -396.707927) (xy 12.762592 -396.802894) (xy 12.794357 -396.900654) (xy 12.818353 -397.000605)
			(xy 12.834433 -397.10213) (xy 12.842498 -397.204604) (xy 12.843002 -397.256) (xy 12.842498 -397.307396)
			(xy 12.834433 -397.40987) (xy 12.818353 -397.511395) (xy 12.794357 -397.611346) (xy 12.762592 -397.709106)
			(xy 12.723256 -397.804073) (xy 12.67659 -397.89566) (xy 12.622882 -397.983304) (xy 12.562463 -398.066464)
			(xy 12.495705 -398.144627) (xy 12.423021 -398.217311) (xy 12.344858 -398.284069) (xy 12.261698 -398.344488)
			(xy 12.174054 -398.398196) (xy 12.082467 -398.444862) (xy 11.9875 -398.484198) (xy 11.88974 -398.515963)
			(xy 11.789789 -398.539959) (xy 11.688264 -398.556039) (xy 11.58579 -398.564104) (xy 11.482998 -398.564104)
			(xy 11.380524 -398.556039) (xy 11.278999 -398.539959) (xy 11.179048 -398.515963) (xy 11.081288 -398.484198)
			(xy 10.986321 -398.444862) (xy 10.894734 -398.398196) (xy 10.80709 -398.344488) (xy 10.72393 -398.284069)
			(xy 10.645767 -398.217311) (xy 10.573083 -398.144627) (xy 10.506325 -398.066464) (xy 10.445906 -397.983304)
			(xy 10.392198 -397.89566) (xy 10.345532 -397.804073) (xy 10.306196 -397.709106) (xy 10.274431 -397.611346)
			(xy 10.250435 -397.511395) (xy 10.234355 -397.40987) (xy 10.22629 -397.307396) (xy 1.27 -397.307396)
			(xy 1.27 -398.870987) (xy 2.787139 -398.870987) (xy 2.787139 -398.791121) (xy 2.795219 -398.711666)
			(xy 2.811296 -398.633436) (xy 2.835205 -398.557234) (xy 2.8667 -398.483841) (xy 2.905459 -398.414011)
			(xy 2.951083 -398.348461) (xy 3.003105 -398.287862) (xy 3.06099 -398.232838) (xy 3.124146 -398.183952)
			(xy 3.191923 -398.141706) (xy 3.263626 -398.106534) (xy 3.33852 -398.078797) (xy 3.415835 -398.058778)
			(xy 3.494779 -398.046685) (xy 3.574542 -398.04264) (xy 3.654305 -398.046685) (xy 3.733249 -398.058778)
			(xy 3.810564 -398.078797) (xy 3.885458 -398.106534) (xy 3.957161 -398.141706) (xy 4.024938 -398.183952)
			(xy 4.088094 -398.232838) (xy 4.145979 -398.287862) (xy 4.198001 -398.348461) (xy 4.243625 -398.414011)
			(xy 4.282384 -398.483841) (xy 4.313879 -398.557234) (xy 4.337788 -398.633436) (xy 4.353865 -398.711666)
			(xy 4.361945 -398.791121) (xy 4.36245 -398.831054) (xy 4.361945 -398.870987) (xy 4.353865 -398.950442)
			(xy 4.337788 -399.028672) (xy 4.313879 -399.104874) (xy 4.282384 -399.178267) (xy 4.243625 -399.248097)
			(xy 4.198001 -399.313647) (xy 4.145979 -399.374246) (xy 4.088094 -399.42927) (xy 4.024938 -399.478156)
			(xy 4.023449 -399.479084) (xy 5.677649 -399.479084) (xy 5.677649 -399.352948) (xy 5.685569 -399.22706)
			(xy 5.701379 -399.101918) (xy 5.725014 -398.978015) (xy 5.756383 -398.855842) (xy 5.795361 -398.735879)
			(xy 5.841795 -398.6186) (xy 5.895502 -398.504468) (xy 5.956269 -398.393933) (xy 6.023856 -398.287433)
			(xy 6.097997 -398.185386) (xy 6.1784 -398.088196) (xy 6.264746 -397.996246) (xy 6.356696 -397.9099)
			(xy 6.453886 -397.829497) (xy 6.555933 -397.755356) (xy 6.662433 -397.687769) (xy 6.772968 -397.627002)
			(xy 6.8871 -397.573295) (xy 7.004379 -397.526861) (xy 7.124342 -397.487883) (xy 7.246515 -397.456514)
			(xy 7.370418 -397.432879) (xy 7.49556 -397.417069) (xy 7.621448 -397.409149) (xy 7.747584 -397.409149)
			(xy 7.873472 -397.417069) (xy 7.998614 -397.432879) (xy 8.122517 -397.456514) (xy 8.24469 -397.487883)
			(xy 8.364653 -397.526861) (xy 8.481932 -397.573295) (xy 8.596064 -397.627002) (xy 8.706599 -397.687769)
			(xy 8.813099 -397.755356) (xy 8.915146 -397.829497) (xy 9.012336 -397.9099) (xy 9.104286 -397.996246)
			(xy 9.190632 -398.088196) (xy 9.271035 -398.185386) (xy 9.345176 -398.287433) (xy 9.412763 -398.393933)
			(xy 9.47353 -398.504468) (xy 9.527237 -398.6186) (xy 9.573671 -398.735879) (xy 9.612649 -398.855842)
			(xy 9.644018 -398.978015) (xy 9.667653 -399.101918) (xy 9.683463 -399.22706) (xy 9.691383 -399.352948)
			(xy 9.691878 -399.416016) (xy 9.691383 -399.479084) (xy 9.683463 -399.604972) (xy 9.667653 -399.730114)
			(xy 9.644018 -399.854017) (xy 9.612649 -399.97619) (xy 9.573671 -400.096153) (xy 9.527237 -400.213432)
			(xy 9.47353 -400.327564) (xy 9.412763 -400.438099) (xy 9.345176 -400.544599) (xy 9.271035 -400.646646)
			(xy 9.205429 -400.725949) (xy 15.787113 -400.725949) (xy 15.787113 -400.646083) (xy 15.795193 -400.566628)
			(xy 15.81127 -400.488398) (xy 15.835179 -400.412196) (xy 15.866674 -400.338803) (xy 15.905433 -400.268973)
			(xy 15.951057 -400.203423) (xy 16.003079 -400.142824) (xy 16.060964 -400.0878) (xy 16.12412 -400.038914)
			(xy 16.191897 -399.996668) (xy 16.2636 -399.961496) (xy 16.338494 -399.933759) (xy 16.415809 -399.91374)
			(xy 16.494753 -399.901647) (xy 16.574516 -399.897602) (xy 16.654279 -399.901647) (xy 16.733223 -399.91374)
			(xy 16.810538 -399.933759) (xy 16.885432 -399.961496) (xy 16.957135 -399.996668) (xy 17.024912 -400.038914)
			(xy 17.088068 -400.0878) (xy 17.145953 -400.142824) (xy 17.197975 -400.203423) (xy 17.243599 -400.268973)
			(xy 17.282358 -400.338803) (xy 17.313853 -400.412196) (xy 17.337762 -400.488398) (xy 17.353839 -400.566628)
			(xy 17.361919 -400.646083) (xy 17.362424 -400.686016) (xy 17.361919 -400.725949) (xy 17.353839 -400.805404)
			(xy 17.337762 -400.883634) (xy 17.313853 -400.959836) (xy 17.282358 -401.033229) (xy 17.243599 -401.103059)
			(xy 17.197975 -401.168609) (xy 17.145953 -401.229208) (xy 17.088068 -401.284232) (xy 17.024912 -401.333118)
			(xy 16.957135 -401.375364) (xy 16.885432 -401.410536) (xy 16.810538 -401.438273) (xy 16.733223 -401.458292)
			(xy 16.654279 -401.470385) (xy 16.574516 -401.474431) (xy 16.494753 -401.470385) (xy 16.415809 -401.458292)
			(xy 16.338494 -401.438273) (xy 16.2636 -401.410536) (xy 16.191897 -401.375364) (xy 16.12412 -401.333118)
			(xy 16.060964 -401.284232) (xy 16.003079 -401.229208) (xy 15.951057 -401.168609) (xy 15.905433 -401.103059)
			(xy 15.866674 -401.033229) (xy 15.835179 -400.959836) (xy 15.81127 -400.883634) (xy 15.795193 -400.805404)
			(xy 15.787113 -400.725949) (xy 9.205429 -400.725949) (xy 9.190632 -400.743836) (xy 9.104286 -400.835786)
			(xy 9.012336 -400.922132) (xy 8.915146 -401.002535) (xy 8.813099 -401.076676) (xy 8.706599 -401.144263)
			(xy 8.596064 -401.20503) (xy 8.481932 -401.258737) (xy 8.364653 -401.305171) (xy 8.24469 -401.344149)
			(xy 8.122517 -401.375518) (xy 7.998614 -401.399153) (xy 7.873472 -401.414963) (xy 7.747584 -401.422883)
			(xy 7.621448 -401.422883) (xy 7.49556 -401.414963) (xy 7.370418 -401.399153) (xy 7.246515 -401.375518)
			(xy 7.124342 -401.344149) (xy 7.004379 -401.305171) (xy 6.8871 -401.258737) (xy 6.772968 -401.20503)
			(xy 6.662433 -401.144263) (xy 6.555933 -401.076676) (xy 6.453886 -401.002535) (xy 6.356696 -400.922132)
			(xy 6.264746 -400.835786) (xy 6.1784 -400.743836) (xy 6.097997 -400.646646) (xy 6.023856 -400.544599)
			(xy 5.956269 -400.438099) (xy 5.895502 -400.327564) (xy 5.841795 -400.213432) (xy 5.795361 -400.096153)
			(xy 5.756383 -399.97619) (xy 5.725014 -399.854017) (xy 5.701379 -399.730114) (xy 5.685569 -399.604972)
			(xy 5.677649 -399.479084) (xy 4.023449 -399.479084) (xy 3.957161 -399.520402) (xy 3.885458 -399.555574)
			(xy 3.810564 -399.583311) (xy 3.733249 -399.60333) (xy 3.654305 -399.615423) (xy 3.574542 -399.619469)
			(xy 3.494779 -399.615423) (xy 3.415835 -399.60333) (xy 3.33852 -399.583311) (xy 3.263626 -399.555574)
			(xy 3.191923 -399.520402) (xy 3.124146 -399.478156) (xy 3.06099 -399.42927) (xy 3.003105 -399.374246)
			(xy 2.951083 -399.313647) (xy 2.905459 -399.248097) (xy 2.8667 -399.178267) (xy 2.835205 -399.104874)
			(xy 2.811296 -399.028672) (xy 2.795219 -398.950442) (xy 2.787139 -398.870987) (xy 1.27 -398.870987)
			(xy 1.27 -401.360949) (xy 2.787139 -401.360949) (xy 2.787139 -401.281083) (xy 2.795219 -401.201628)
			(xy 2.811296 -401.123398) (xy 2.835205 -401.047196) (xy 2.8667 -400.973803) (xy 2.905459 -400.903973)
			(xy 2.951083 -400.838423) (xy 3.003105 -400.777824) (xy 3.06099 -400.7228) (xy 3.124146 -400.673914)
			(xy 3.191923 -400.631668) (xy 3.263626 -400.596496) (xy 3.33852 -400.568759) (xy 3.415835 -400.54874)
			(xy 3.494779 -400.536647) (xy 3.574542 -400.532602) (xy 3.654305 -400.536647) (xy 3.733249 -400.54874)
			(xy 3.810564 -400.568759) (xy 3.885458 -400.596496) (xy 3.957161 -400.631668) (xy 4.024938 -400.673914)
			(xy 4.088094 -400.7228) (xy 4.145979 -400.777824) (xy 4.198001 -400.838423) (xy 4.243625 -400.903973)
			(xy 4.282384 -400.973803) (xy 4.313879 -401.047196) (xy 4.337788 -401.123398) (xy 4.353865 -401.201628)
			(xy 4.361945 -401.281083) (xy 4.36245 -401.321016) (xy 4.361945 -401.360949) (xy 4.353865 -401.440404)
			(xy 4.337788 -401.518634) (xy 4.313879 -401.594836) (xy 4.282384 -401.668229) (xy 4.243625 -401.738059)
			(xy 4.198001 -401.803609) (xy 4.145979 -401.864208) (xy 4.088094 -401.919232) (xy 4.024938 -401.968118)
			(xy 3.980288 -401.995949) (xy 13.247113 -401.995949) (xy 13.247113 -401.916083) (xy 13.255193 -401.836628)
			(xy 13.27127 -401.758398) (xy 13.295179 -401.682196) (xy 13.326674 -401.608803) (xy 13.365433 -401.538973)
			(xy 13.411057 -401.473423) (xy 13.463079 -401.412824) (xy 13.520964 -401.3578) (xy 13.58412 -401.308914)
			(xy 13.651897 -401.266668) (xy 13.7236 -401.231496) (xy 13.798494 -401.203759) (xy 13.875809 -401.18374)
			(xy 13.954753 -401.171647) (xy 14.034516 -401.167602) (xy 14.114279 -401.171647) (xy 14.193223 -401.18374)
			(xy 14.270538 -401.203759) (xy 14.345432 -401.231496) (xy 14.417135 -401.266668) (xy 14.484912 -401.308914)
			(xy 14.548068 -401.3578) (xy 14.605953 -401.412824) (xy 14.657975 -401.473423) (xy 14.703599 -401.538973)
			(xy 14.742358 -401.608803) (xy 14.773853 -401.682196) (xy 14.797762 -401.758398) (xy 14.813839 -401.836628)
			(xy 14.821919 -401.916083) (xy 14.822424 -401.956016) (xy 14.821919 -401.995949) (xy 14.813839 -402.075404)
			(xy 14.797762 -402.153634) (xy 14.773853 -402.229836) (xy 14.742358 -402.303229) (xy 14.703599 -402.373059)
			(xy 14.657975 -402.438609) (xy 14.605953 -402.499208) (xy 14.548068 -402.554232) (xy 14.484912 -402.603118)
			(xy 14.417135 -402.645364) (xy 14.345432 -402.680536) (xy 14.270538 -402.708273) (xy 14.193223 -402.728292)
			(xy 14.114279 -402.740385) (xy 14.034516 -402.744431) (xy 13.954753 -402.740385) (xy 13.875809 -402.728292)
			(xy 13.798494 -402.708273) (xy 13.7236 -402.680536) (xy 13.651897 -402.645364) (xy 13.58412 -402.603118)
			(xy 13.520964 -402.554232) (xy 13.463079 -402.499208) (xy 13.411057 -402.438609) (xy 13.365433 -402.373059)
			(xy 13.326674 -402.303229) (xy 13.295179 -402.229836) (xy 13.27127 -402.153634) (xy 13.255193 -402.075404)
			(xy 13.247113 -401.995949) (xy 3.980288 -401.995949) (xy 3.957161 -402.010364) (xy 3.885458 -402.045536)
			(xy 3.810564 -402.073273) (xy 3.733249 -402.093292) (xy 3.654305 -402.105385) (xy 3.574542 -402.109431)
			(xy 3.494779 -402.105385) (xy 3.415835 -402.093292) (xy 3.33852 -402.073273) (xy 3.263626 -402.045536)
			(xy 3.191923 -402.010364) (xy 3.124146 -401.968118) (xy 3.06099 -401.919232) (xy 3.003105 -401.864208)
			(xy 2.951083 -401.803609) (xy 2.905459 -401.738059) (xy 2.8667 -401.668229) (xy 2.835205 -401.594836)
			(xy 2.811296 -401.518634) (xy 2.795219 -401.440404) (xy 2.787139 -401.360949) (xy 1.27 -401.360949)
			(xy 1.27 -403.265949) (xy 15.787113 -403.265949) (xy 15.787113 -403.186083) (xy 15.795193 -403.106628)
			(xy 15.81127 -403.028398) (xy 15.835179 -402.952196) (xy 15.866674 -402.878803) (xy 15.905433 -402.808973)
			(xy 15.951057 -402.743423) (xy 16.003079 -402.682824) (xy 16.060964 -402.6278) (xy 16.12412 -402.578914)
			(xy 16.191897 -402.536668) (xy 16.2636 -402.501496) (xy 16.338494 -402.473759) (xy 16.415809 -402.45374)
			(xy 16.494753 -402.441647) (xy 16.574516 -402.437602) (xy 16.654279 -402.441647) (xy 16.733223 -402.45374)
			(xy 16.810538 -402.473759) (xy 16.885432 -402.501496) (xy 16.957135 -402.536668) (xy 17.024912 -402.578914)
			(xy 17.088068 -402.6278) (xy 17.145953 -402.682824) (xy 17.197975 -402.743423) (xy 17.243599 -402.808973)
			(xy 17.282358 -402.878803) (xy 17.313853 -402.952196) (xy 17.337762 -403.028398) (xy 17.353839 -403.106628)
			(xy 17.361919 -403.186083) (xy 17.362424 -403.226016) (xy 17.361919 -403.265949) (xy 17.353839 -403.345404)
			(xy 17.337762 -403.423634) (xy 17.313853 -403.499836) (xy 17.282358 -403.573229) (xy 17.243599 -403.643059)
			(xy 17.197975 -403.708609) (xy 17.145953 -403.769208) (xy 17.088068 -403.824232) (xy 17.024912 -403.873118)
			(xy 16.957135 -403.915364) (xy 16.885432 -403.950536) (xy 16.810538 -403.978273) (xy 16.733223 -403.998292)
			(xy 16.654279 -404.010385) (xy 16.574516 -404.014431) (xy 16.494753 -404.010385) (xy 16.415809 -403.998292)
			(xy 16.338494 -403.978273) (xy 16.2636 -403.950536) (xy 16.191897 -403.915364) (xy 16.12412 -403.873118)
			(xy 16.060964 -403.824232) (xy 16.003079 -403.769208) (xy 15.951057 -403.708609) (xy 15.905433 -403.643059)
			(xy 15.866674 -403.573229) (xy 15.835179 -403.499836) (xy 15.81127 -403.423634) (xy 15.795193 -403.345404)
			(xy 15.787113 -403.265949) (xy 1.27 -403.265949) (xy 1.27 -404.535949) (xy 13.247113 -404.535949)
			(xy 13.247113 -404.456083) (xy 13.255193 -404.376628) (xy 13.27127 -404.298398) (xy 13.295179 -404.222196)
			(xy 13.326674 -404.148803) (xy 13.365433 -404.078973) (xy 13.411057 -404.013423) (xy 13.463079 -403.952824)
			(xy 13.520964 -403.8978) (xy 13.58412 -403.848914) (xy 13.651897 -403.806668) (xy 13.7236 -403.771496)
			(xy 13.798494 -403.743759) (xy 13.875809 -403.72374) (xy 13.954753 -403.711647) (xy 14.034516 -403.707602)
			(xy 14.114279 -403.711647) (xy 14.193223 -403.72374) (xy 14.270538 -403.743759) (xy 14.345432 -403.771496)
			(xy 14.417135 -403.806668) (xy 14.484912 -403.848914) (xy 14.548068 -403.8978) (xy 14.605953 -403.952824)
			(xy 14.657975 -404.013423) (xy 14.703599 -404.078973) (xy 14.742358 -404.148803) (xy 14.773853 -404.222196)
			(xy 14.797762 -404.298398) (xy 14.813839 -404.376628) (xy 14.821919 -404.456083) (xy 14.822424 -404.496016)
			(xy 14.821919 -404.535949) (xy 14.813839 -404.615404) (xy 14.797762 -404.693634) (xy 14.773853 -404.769836)
			(xy 14.742358 -404.843229) (xy 14.703599 -404.913059) (xy 14.657975 -404.978609) (xy 14.605953 -405.039208)
			(xy 14.548068 -405.094232) (xy 14.484912 -405.143118) (xy 14.417135 -405.185364) (xy 14.345432 -405.220536)
			(xy 14.270538 -405.248273) (xy 14.193223 -405.268292) (xy 14.114279 -405.280385) (xy 14.034516 -405.284431)
			(xy 13.954753 -405.280385) (xy 13.875809 -405.268292) (xy 13.798494 -405.248273) (xy 13.7236 -405.220536)
			(xy 13.651897 -405.185364) (xy 13.58412 -405.143118) (xy 13.520964 -405.094232) (xy 13.463079 -405.039208)
			(xy 13.411057 -404.978609) (xy 13.365433 -404.913059) (xy 13.326674 -404.843229) (xy 13.295179 -404.769836)
			(xy 13.27127 -404.693634) (xy 13.255193 -404.615404) (xy 13.247113 -404.535949) (xy 1.27 -404.535949)
			(xy 1.27 -405.805949) (xy 15.787113 -405.805949) (xy 15.787113 -405.726083) (xy 15.795193 -405.646628)
			(xy 15.81127 -405.568398) (xy 15.835179 -405.492196) (xy 15.866674 -405.418803) (xy 15.905433 -405.348973)
			(xy 15.951057 -405.283423) (xy 16.003079 -405.222824) (xy 16.060964 -405.1678) (xy 16.12412 -405.118914)
			(xy 16.191897 -405.076668) (xy 16.2636 -405.041496) (xy 16.338494 -405.013759) (xy 16.415809 -404.99374)
			(xy 16.494753 -404.981647) (xy 16.574516 -404.977602) (xy 16.654279 -404.981647) (xy 16.733223 -404.99374)
			(xy 16.810538 -405.013759) (xy 16.885432 -405.041496) (xy 16.957135 -405.076668) (xy 17.024912 -405.118914)
			(xy 17.088068 -405.1678) (xy 17.145953 -405.222824) (xy 17.197975 -405.283423) (xy 17.243599 -405.348973)
			(xy 17.282358 -405.418803) (xy 17.313853 -405.492196) (xy 17.337762 -405.568398) (xy 17.353839 -405.646628)
			(xy 17.361919 -405.726083) (xy 17.362424 -405.766016) (xy 17.361919 -405.805949) (xy 17.353839 -405.885404)
			(xy 17.337762 -405.963634) (xy 17.313853 -406.039836) (xy 17.282358 -406.113229) (xy 17.243599 -406.183059)
			(xy 17.197975 -406.248609) (xy 17.145953 -406.309208) (xy 17.088068 -406.364232) (xy 17.024912 -406.413118)
			(xy 16.957135 -406.455364) (xy 16.885432 -406.490536) (xy 16.810538 -406.518273) (xy 16.733223 -406.538292)
			(xy 16.654279 -406.550385) (xy 16.574516 -406.554431) (xy 16.494753 -406.550385) (xy 16.415809 -406.538292)
			(xy 16.338494 -406.518273) (xy 16.2636 -406.490536) (xy 16.191897 -406.455364) (xy 16.12412 -406.413118)
			(xy 16.060964 -406.364232) (xy 16.003079 -406.309208) (xy 15.951057 -406.248609) (xy 15.905433 -406.183059)
			(xy 15.866674 -406.113229) (xy 15.835179 -406.039836) (xy 15.81127 -405.963634) (xy 15.795193 -405.885404)
			(xy 15.787113 -405.805949) (xy 1.27 -405.805949) (xy 1.27 -407.075949) (xy 13.247113 -407.075949)
			(xy 13.247113 -406.996083) (xy 13.255193 -406.916628) (xy 13.27127 -406.838398) (xy 13.295179 -406.762196)
			(xy 13.326674 -406.688803) (xy 13.365433 -406.618973) (xy 13.411057 -406.553423) (xy 13.463079 -406.492824)
			(xy 13.520964 -406.4378) (xy 13.58412 -406.388914) (xy 13.651897 -406.346668) (xy 13.7236 -406.311496)
			(xy 13.798494 -406.283759) (xy 13.875809 -406.26374) (xy 13.954753 -406.251647) (xy 14.034516 -406.247602)
			(xy 14.114279 -406.251647) (xy 14.193223 -406.26374) (xy 14.270538 -406.283759) (xy 14.345432 -406.311496)
			(xy 14.417135 -406.346668) (xy 14.484912 -406.388914) (xy 14.548068 -406.4378) (xy 14.605953 -406.492824)
			(xy 14.657975 -406.553423) (xy 14.703599 -406.618973) (xy 14.742358 -406.688803) (xy 14.773853 -406.762196)
			(xy 14.797762 -406.838398) (xy 14.813839 -406.916628) (xy 14.821919 -406.996083) (xy 14.822424 -407.036016)
			(xy 14.821919 -407.075949) (xy 14.813839 -407.155404) (xy 14.797762 -407.233634) (xy 14.773853 -407.309836)
			(xy 14.742358 -407.383229) (xy 14.703599 -407.453059) (xy 14.657975 -407.518609) (xy 14.605953 -407.579208)
			(xy 14.548068 -407.634232) (xy 14.484912 -407.683118) (xy 14.417135 -407.725364) (xy 14.345432 -407.760536)
			(xy 14.270538 -407.788273) (xy 14.193223 -407.808292) (xy 14.114279 -407.820385) (xy 14.034516 -407.824431)
			(xy 13.954753 -407.820385) (xy 13.875809 -407.808292) (xy 13.798494 -407.788273) (xy 13.7236 -407.760536)
			(xy 13.651897 -407.725364) (xy 13.58412 -407.683118) (xy 13.520964 -407.634232) (xy 13.463079 -407.579208)
			(xy 13.411057 -407.518609) (xy 13.365433 -407.453059) (xy 13.326674 -407.383229) (xy 13.295179 -407.309836)
			(xy 13.27127 -407.233634) (xy 13.255193 -407.155404) (xy 13.247113 -407.075949) (xy 1.27 -407.075949)
			(xy 1.27 -408.980949) (xy 2.787139 -408.980949) (xy 2.787139 -408.901083) (xy 2.795219 -408.821628)
			(xy 2.811296 -408.743398) (xy 2.835205 -408.667196) (xy 2.8667 -408.593803) (xy 2.905459 -408.523973)
			(xy 2.951083 -408.458423) (xy 3.003105 -408.397824) (xy 3.06099 -408.3428) (xy 3.124146 -408.293914)
			(xy 3.191923 -408.251668) (xy 3.263626 -408.216496) (xy 3.33852 -408.188759) (xy 3.415835 -408.16874)
			(xy 3.494779 -408.156647) (xy 3.574542 -408.152602) (xy 3.654305 -408.156647) (xy 3.733249 -408.16874)
			(xy 3.810564 -408.188759) (xy 3.885458 -408.216496) (xy 3.957161 -408.251668) (xy 4.024938 -408.293914)
			(xy 4.088094 -408.3428) (xy 4.091407 -408.345949) (xy 15.787113 -408.345949) (xy 15.787113 -408.266083)
			(xy 15.795193 -408.186628) (xy 15.81127 -408.108398) (xy 15.835179 -408.032196) (xy 15.866674 -407.958803)
			(xy 15.905433 -407.888973) (xy 15.951057 -407.823423) (xy 16.003079 -407.762824) (xy 16.060964 -407.7078)
			(xy 16.12412 -407.658914) (xy 16.191897 -407.616668) (xy 16.2636 -407.581496) (xy 16.338494 -407.553759)
			(xy 16.415809 -407.53374) (xy 16.494753 -407.521647) (xy 16.574516 -407.517602) (xy 16.654279 -407.521647)
			(xy 16.733223 -407.53374) (xy 16.810538 -407.553759) (xy 16.885432 -407.581496) (xy 16.957135 -407.616668)
			(xy 17.024912 -407.658914) (xy 17.088068 -407.7078) (xy 17.145953 -407.762824) (xy 17.197975 -407.823423)
			(xy 17.243599 -407.888973) (xy 17.282358 -407.958803) (xy 17.313853 -408.032196) (xy 17.337762 -408.108398)
			(xy 17.353839 -408.186628) (xy 17.361919 -408.266083) (xy 17.362424 -408.306016) (xy 17.361919 -408.345949)
			(xy 17.353839 -408.425404) (xy 17.337762 -408.503634) (xy 17.313853 -408.579836) (xy 17.282358 -408.653229)
			(xy 17.243599 -408.723059) (xy 17.197975 -408.788609) (xy 17.145953 -408.849208) (xy 17.088068 -408.904232)
			(xy 17.024912 -408.953118) (xy 16.957135 -408.995364) (xy 16.885432 -409.030536) (xy 16.810538 -409.058273)
			(xy 16.733223 -409.078292) (xy 16.654279 -409.090385) (xy 16.574516 -409.094431) (xy 16.494753 -409.090385)
			(xy 16.415809 -409.078292) (xy 16.338494 -409.058273) (xy 16.2636 -409.030536) (xy 16.191897 -408.995364)
			(xy 16.12412 -408.953118) (xy 16.060964 -408.904232) (xy 16.003079 -408.849208) (xy 15.951057 -408.788609)
			(xy 15.905433 -408.723059) (xy 15.866674 -408.653229) (xy 15.835179 -408.579836) (xy 15.81127 -408.503634)
			(xy 15.795193 -408.425404) (xy 15.787113 -408.345949) (xy 4.091407 -408.345949) (xy 4.145979 -408.397824)
			(xy 4.198001 -408.458423) (xy 4.243625 -408.523973) (xy 4.282384 -408.593803) (xy 4.313879 -408.667196)
			(xy 4.337788 -408.743398) (xy 4.353865 -408.821628) (xy 4.361945 -408.901083) (xy 4.36245 -408.941016)
			(xy 4.361945 -408.980949) (xy 4.353865 -409.060404) (xy 4.337788 -409.138634) (xy 4.313879 -409.214836)
			(xy 4.282384 -409.288229) (xy 4.243625 -409.358059) (xy 4.198001 -409.423609) (xy 4.145979 -409.484208)
			(xy 4.088094 -409.539232) (xy 4.024938 -409.588118) (xy 3.957161 -409.630364) (xy 3.885458 -409.665536)
			(xy 3.810564 -409.693273) (xy 3.733249 -409.713292) (xy 3.654305 -409.725385) (xy 3.574542 -409.729431)
			(xy 3.494779 -409.725385) (xy 3.415835 -409.713292) (xy 3.33852 -409.693273) (xy 3.263626 -409.665536)
			(xy 3.191923 -409.630364) (xy 3.124146 -409.588118) (xy 3.06099 -409.539232) (xy 3.003105 -409.484208)
			(xy 2.951083 -409.423609) (xy 2.905459 -409.358059) (xy 2.8667 -409.288229) (xy 2.835205 -409.214836)
			(xy 2.811296 -409.138634) (xy 2.795219 -409.060404) (xy 2.787139 -408.980949) (xy 1.27 -408.980949)
			(xy 1.27 -411.470911) (xy 2.787139 -411.470911) (xy 2.787139 -411.391045) (xy 2.795219 -411.31159)
			(xy 2.811296 -411.23336) (xy 2.835205 -411.157158) (xy 2.8667 -411.083765) (xy 2.905459 -411.013935)
			(xy 2.951083 -410.948385) (xy 3.003105 -410.887786) (xy 3.06099 -410.832762) (xy 3.124146 -410.783876)
			(xy 3.191923 -410.74163) (xy 3.263626 -410.706458) (xy 3.33852 -410.678721) (xy 3.415835 -410.658702)
			(xy 3.494779 -410.646609) (xy 3.574542 -410.642564) (xy 3.654305 -410.646609) (xy 3.733249 -410.658702)
			(xy 3.810564 -410.678721) (xy 3.885458 -410.706458) (xy 3.957161 -410.74163) (xy 4.024938 -410.783876)
			(xy 4.088094 -410.832762) (xy 4.145979 -410.887786) (xy 4.164263 -410.909084) (xy 5.677649 -410.909084)
			(xy 5.677649 -410.782948) (xy 5.685569 -410.65706) (xy 5.701379 -410.531918) (xy 5.725014 -410.408015)
			(xy 5.756383 -410.285842) (xy 5.795361 -410.165879) (xy 5.841795 -410.0486) (xy 5.895502 -409.934468)
			(xy 5.956269 -409.823933) (xy 6.023856 -409.717433) (xy 6.097997 -409.615386) (xy 6.1784 -409.518196)
			(xy 6.264746 -409.426246) (xy 6.356696 -409.3399) (xy 6.453886 -409.259497) (xy 6.555933 -409.185356)
			(xy 6.662433 -409.117769) (xy 6.772968 -409.057002) (xy 6.8871 -409.003295) (xy 7.004379 -408.956861)
			(xy 7.124342 -408.917883) (xy 7.246515 -408.886514) (xy 7.370418 -408.862879) (xy 7.49556 -408.847069)
			(xy 7.621448 -408.839149) (xy 7.747584 -408.839149) (xy 7.873472 -408.847069) (xy 7.998614 -408.862879)
			(xy 8.122517 -408.886514) (xy 8.24469 -408.917883) (xy 8.364653 -408.956861) (xy 8.481932 -409.003295)
			(xy 8.596064 -409.057002) (xy 8.706599 -409.117769) (xy 8.813099 -409.185356) (xy 8.915146 -409.259497)
			(xy 9.012336 -409.3399) (xy 9.104286 -409.426246) (xy 9.190632 -409.518196) (xy 9.271035 -409.615386)
			(xy 9.271444 -409.615949) (xy 13.247113 -409.615949) (xy 13.247113 -409.536083) (xy 13.255193 -409.456628)
			(xy 13.27127 -409.378398) (xy 13.295179 -409.302196) (xy 13.326674 -409.228803) (xy 13.365433 -409.158973)
			(xy 13.411057 -409.093423) (xy 13.463079 -409.032824) (xy 13.520964 -408.9778) (xy 13.58412 -408.928914)
			(xy 13.651897 -408.886668) (xy 13.7236 -408.851496) (xy 13.798494 -408.823759) (xy 13.875809 -408.80374)
			(xy 13.954753 -408.791647) (xy 14.034516 -408.787602) (xy 14.114279 -408.791647) (xy 14.193223 -408.80374)
			(xy 14.270538 -408.823759) (xy 14.345432 -408.851496) (xy 14.417135 -408.886668) (xy 14.484912 -408.928914)
			(xy 14.548068 -408.9778) (xy 14.605953 -409.032824) (xy 14.657975 -409.093423) (xy 14.703599 -409.158973)
			(xy 14.742358 -409.228803) (xy 14.773853 -409.302196) (xy 14.797762 -409.378398) (xy 14.813839 -409.456628)
			(xy 14.821919 -409.536083) (xy 14.822424 -409.576016) (xy 14.821919 -409.615949) (xy 14.813839 -409.695404)
			(xy 14.797762 -409.773634) (xy 14.773853 -409.849836) (xy 14.742358 -409.923229) (xy 14.703599 -409.993059)
			(xy 14.657975 -410.058609) (xy 14.605953 -410.119208) (xy 14.548068 -410.174232) (xy 14.484912 -410.223118)
			(xy 14.417135 -410.265364) (xy 14.345432 -410.300536) (xy 14.270538 -410.328273) (xy 14.193223 -410.348292)
			(xy 14.114279 -410.360385) (xy 14.034516 -410.364431) (xy 13.954753 -410.360385) (xy 13.875809 -410.348292)
			(xy 13.798494 -410.328273) (xy 13.7236 -410.300536) (xy 13.651897 -410.265364) (xy 13.58412 -410.223118)
			(xy 13.520964 -410.174232) (xy 13.463079 -410.119208) (xy 13.411057 -410.058609) (xy 13.365433 -409.993059)
			(xy 13.326674 -409.923229) (xy 13.295179 -409.849836) (xy 13.27127 -409.773634) (xy 13.255193 -409.695404)
			(xy 13.247113 -409.615949) (xy 9.271444 -409.615949) (xy 9.345176 -409.717433) (xy 9.412763 -409.823933)
			(xy 9.47353 -409.934468) (xy 9.527237 -410.0486) (xy 9.573671 -410.165879) (xy 9.612649 -410.285842)
			(xy 9.644018 -410.408015) (xy 9.667653 -410.531918) (xy 9.683463 -410.65706) (xy 9.691383 -410.782948)
			(xy 9.691878 -410.846016) (xy 9.691383 -410.909084) (xy 9.683463 -411.034972) (xy 9.667653 -411.160114)
			(xy 9.644018 -411.284017) (xy 9.612649 -411.40619) (xy 9.573671 -411.526153) (xy 9.527237 -411.643432)
			(xy 9.47353 -411.757564) (xy 9.412763 -411.868099) (xy 9.345176 -411.974599) (xy 9.271035 -412.076646)
			(xy 9.190632 -412.173836) (xy 9.104286 -412.265786) (xy 9.012336 -412.352132) (xy 8.915146 -412.432535)
			(xy 8.813099 -412.506676) (xy 8.706599 -412.574263) (xy 8.596064 -412.63503) (xy 8.481932 -412.688737)
			(xy 8.364653 -412.735171) (xy 8.24469 -412.774149) (xy 8.122517 -412.805518) (xy 7.998614 -412.829153)
			(xy 7.873472 -412.844963) (xy 7.747584 -412.852883) (xy 7.621448 -412.852883) (xy 7.49556 -412.844963)
			(xy 7.370418 -412.829153) (xy 7.246515 -412.805518) (xy 7.124342 -412.774149) (xy 7.004379 -412.735171)
			(xy 6.8871 -412.688737) (xy 6.772968 -412.63503) (xy 6.662433 -412.574263) (xy 6.555933 -412.506676)
			(xy 6.453886 -412.432535) (xy 6.356696 -412.352132) (xy 6.264746 -412.265786) (xy 6.1784 -412.173836)
			(xy 6.097997 -412.076646) (xy 6.023856 -411.974599) (xy 5.956269 -411.868099) (xy 5.895502 -411.757564)
			(xy 5.841795 -411.643432) (xy 5.795361 -411.526153) (xy 5.756383 -411.40619) (xy 5.725014 -411.284017)
			(xy 5.701379 -411.160114) (xy 5.685569 -411.034972) (xy 5.677649 -410.909084) (xy 4.164263 -410.909084)
			(xy 4.198001 -410.948385) (xy 4.243625 -411.013935) (xy 4.282384 -411.083765) (xy 4.313879 -411.157158)
			(xy 4.337788 -411.23336) (xy 4.353865 -411.31159) (xy 4.361945 -411.391045) (xy 4.36245 -411.430978)
			(xy 4.361945 -411.470911) (xy 4.353865 -411.550366) (xy 4.337788 -411.628596) (xy 4.313879 -411.704798)
			(xy 4.282384 -411.778191) (xy 4.243625 -411.848021) (xy 4.198001 -411.913571) (xy 4.145979 -411.97417)
			(xy 4.088094 -412.029194) (xy 4.024938 -412.07808) (xy 3.957161 -412.120326) (xy 3.885458 -412.155498)
			(xy 3.810564 -412.183235) (xy 3.733249 -412.203254) (xy 3.654305 -412.215347) (xy 3.574542 -412.219393)
			(xy 3.494779 -412.215347) (xy 3.415835 -412.203254) (xy 3.33852 -412.183235) (xy 3.263626 -412.155498)
			(xy 3.191923 -412.120326) (xy 3.124146 -412.07808) (xy 3.06099 -412.029194) (xy 3.003105 -411.97417)
			(xy 2.951083 -411.913571) (xy 2.905459 -411.848021) (xy 2.8667 -411.778191) (xy 2.835205 -411.704798)
			(xy 2.811296 -411.628596) (xy 2.795219 -411.550366) (xy 2.787139 -411.470911) (xy 1.27 -411.470911)
			(xy 1.27 -413.057428) (xy 10.22629 -413.057428) (xy 10.22629 -412.954636) (xy 10.234355 -412.852162)
			(xy 10.250435 -412.750637) (xy 10.274431 -412.650686) (xy 10.306196 -412.552926) (xy 10.345532 -412.457959)
			(xy 10.392198 -412.366372) (xy 10.445906 -412.278728) (xy 10.506325 -412.195568) (xy 10.573083 -412.117405)
			(xy 10.645767 -412.044721) (xy 10.72393 -411.977963) (xy 10.80709 -411.917544) (xy 10.894734 -411.863836)
			(xy 10.986321 -411.81717) (xy 11.081288 -411.777834) (xy 11.179048 -411.746069) (xy 11.278999 -411.722073)
			(xy 11.380524 -411.705993) (xy 11.482998 -411.697928) (xy 11.58579 -411.697928) (xy 11.688264 -411.705993)
			(xy 11.789789 -411.722073) (xy 11.88974 -411.746069) (xy 11.9875 -411.777834) (xy 12.082467 -411.81717)
			(xy 12.174054 -411.863836) (xy 12.261698 -411.917544) (xy 12.344858 -411.977963) (xy 12.423021 -412.044721)
			(xy 12.495705 -412.117405) (xy 12.562463 -412.195568) (xy 12.622882 -412.278728) (xy 12.67659 -412.366372)
			(xy 12.723256 -412.457959) (xy 12.762592 -412.552926) (xy 12.794357 -412.650686) (xy 12.818353 -412.750637)
			(xy 12.834433 -412.852162) (xy 12.842498 -412.954636) (xy 12.843002 -413.006032) (xy 12.842498 -413.057428)
			(xy 12.834433 -413.159902) (xy 12.818353 -413.261427) (xy 12.794357 -413.361378) (xy 12.762592 -413.459138)
			(xy 12.723256 -413.554105) (xy 12.67659 -413.645692) (xy 12.622882 -413.733336) (xy 12.562463 -413.816496)
			(xy 12.495705 -413.894659) (xy 12.423021 -413.967343) (xy 12.344858 -414.034101) (xy 12.261698 -414.09452)
			(xy 12.174054 -414.148228) (xy 12.082467 -414.194894) (xy 11.9875 -414.23423) (xy 11.88974 -414.265995)
			(xy 11.789789 -414.289991) (xy 11.688264 -414.306071) (xy 11.58579 -414.314136) (xy 11.482998 -414.314136)
			(xy 11.380524 -414.306071) (xy 11.278999 -414.289991) (xy 11.179048 -414.265995) (xy 11.081288 -414.23423)
			(xy 10.986321 -414.194894) (xy 10.894734 -414.148228) (xy 10.80709 -414.09452) (xy 10.72393 -414.034101)
			(xy 10.645767 -413.967343) (xy 10.573083 -413.894659) (xy 10.506325 -413.816496) (xy 10.445906 -413.733336)
			(xy 10.392198 -413.645692) (xy 10.345532 -413.554105) (xy 10.306196 -413.459138) (xy 10.274431 -413.361378)
			(xy 10.250435 -413.261427) (xy 10.234355 -413.159902) (xy 10.22629 -413.057428) (xy 1.27 -413.057428)
			(xy 1.27 -416.16249) (xy 2.450844 -416.16249) (xy 2.454915 -416.106868) (xy 2.467041 -416.052431)
			(xy 2.486964 -416.00034) (xy 2.51426 -415.951705) (xy 2.548346 -415.907562) (xy 2.588495 -415.868853)
			(xy 2.633853 -415.836402) (xy 2.683453 -415.810901) (xy 2.736237 -415.792894) (xy 2.79108 -415.782764)
			(xy 2.846814 -415.780727) (xy 2.902251 -415.786827) (xy 2.956208 -415.800933) (xy 3.007537 -415.822745)
			(xy 3.055143 -415.851799) (xy 3.098011 -415.887474) (xy 3.135228 -415.929011) (xy 3.166001 -415.975524)
			(xy 3.189673 -416.026021) (xy 3.197871 -416.05327) (xy 3.82219 -416.05327) (xy 3.826261 -415.997648)
			(xy 3.838387 -415.943211) (xy 3.85831 -415.89112) (xy 3.885606 -415.842485) (xy 3.919692 -415.798342)
			(xy 3.959841 -415.759633) (xy 4.005199 -415.727182) (xy 4.054799 -415.701681) (xy 4.107583 -415.683674)
			(xy 4.162426 -415.673544) (xy 4.21816 -415.671507) (xy 4.273597 -415.677607) (xy 4.327554 -415.691713)
			(xy 4.378883 -415.713525) (xy 4.426489 -415.742579) (xy 4.469357 -415.778254) (xy 4.506574 -415.819791)
			(xy 4.537347 -415.866304) (xy 4.561019 -415.916801) (xy 4.577087 -415.970208) (xy 4.585207 -416.025384)
			(xy 4.585716 -416.05327) (xy 4.585207 -416.081156) (xy 4.577087 -416.136332) (xy 4.561019 -416.189739)
			(xy 4.537347 -416.240236) (xy 4.506574 -416.286749) (xy 4.469357 -416.328286) (xy 4.426489 -416.363961)
			(xy 4.378883 -416.393015) (xy 4.327554 -416.414827) (xy 4.273597 -416.428933) (xy 4.21816 -416.435033)
			(xy 4.162426 -416.432996) (xy 4.107583 -416.422866) (xy 4.054799 -416.404859) (xy 4.005199 -416.379358)
			(xy 3.959841 -416.346907) (xy 3.919692 -416.308198) (xy 3.885606 -416.264055) (xy 3.85831 -416.21542)
			(xy 3.838387 -416.163329) (xy 3.826261 -416.108892) (xy 3.82219 -416.05327) (xy 3.197871 -416.05327)
			(xy 3.205741 -416.079428) (xy 3.213861 -416.134604) (xy 3.21437 -416.16249) (xy 3.213861 -416.190376)
			(xy 3.205741 -416.245552) (xy 3.189673 -416.298959) (xy 3.166001 -416.349456) (xy 3.135228 -416.395969)
			(xy 3.098011 -416.437506) (xy 3.055143 -416.473181) (xy 3.007537 -416.502235) (xy 2.956208 -416.524047)
			(xy 2.902251 -416.538153) (xy 2.846814 -416.544253) (xy 2.79108 -416.542216) (xy 2.736237 -416.532086)
			(xy 2.683453 -416.514079) (xy 2.633853 -416.488578) (xy 2.588495 -416.456127) (xy 2.548346 -416.417418)
			(xy 2.51426 -416.373275) (xy 2.486964 -416.32464) (xy 2.467041 -416.272549) (xy 2.454915 -416.218112)
			(xy 2.450844 -416.16249) (xy 1.27 -416.16249) (xy 1.27 -423.940932) (xy 4.839198 -423.940932) (xy 4.839198 -423.84706)
			(xy 4.847159 -423.753526) (xy 4.863023 -423.661004) (xy 4.886677 -423.570161) (xy 4.917949 -423.481652)
			(xy 4.956615 -423.396113) (xy 5.002396 -423.314161) (xy 5.054962 -423.236387) (xy 5.113935 -423.163352)
			(xy 5.178888 -423.09558) (xy 5.249355 -423.033561) (xy 5.324828 -422.977742) (xy 5.404763 -422.928524)
			(xy 5.488584 -422.886262) (xy 5.575687 -422.851262) (xy 5.665444 -422.823774) (xy 5.757209 -422.803997)
			(xy 5.850321 -422.792074) (xy 5.944108 -422.78809) (xy 6.037895 -422.792074) (xy 6.131007 -422.803997)
			(xy 6.222772 -422.823774) (xy 6.312529 -422.851262) (xy 6.399632 -422.886262) (xy 6.483453 -422.928524)
			(xy 6.563388 -422.977742) (xy 6.638861 -423.033561) (xy 6.709328 -423.09558) (xy 6.774281 -423.163352)
			(xy 6.833254 -423.236387) (xy 6.88582 -423.314161) (xy 6.931601 -423.396113) (xy 6.970267 -423.481652)
			(xy 7.001539 -423.570161) (xy 7.025193 -423.661004) (xy 7.041057 -423.753526) (xy 7.049018 -423.84706)
			(xy 7.049516 -423.893996) (xy 7.049018 -423.940932) (xy 10.339314 -423.940932) (xy 10.339314 -423.84706)
			(xy 10.347275 -423.753526) (xy 10.363139 -423.661004) (xy 10.386793 -423.570161) (xy 10.418065 -423.481652)
			(xy 10.456731 -423.396113) (xy 10.502512 -423.314161) (xy 10.555078 -423.236387) (xy 10.614051 -423.163352)
			(xy 10.679004 -423.09558) (xy 10.749471 -423.033561) (xy 10.824944 -422.977742) (xy 10.904879 -422.928524)
			(xy 10.9887 -422.886262) (xy 11.075803 -422.851262) (xy 11.16556 -422.823774) (xy 11.257325 -422.803997)
			(xy 11.350437 -422.792074) (xy 11.444224 -422.78809) (xy 11.538011 -422.792074) (xy 11.631123 -422.803997)
			(xy 11.722888 -422.823774) (xy 11.812645 -422.851262) (xy 11.899748 -422.886262) (xy 11.983569 -422.928524)
			(xy 12.063504 -422.977742) (xy 12.138977 -423.033561) (xy 12.209444 -423.09558) (xy 12.274397 -423.163352)
			(xy 12.33337 -423.236387) (xy 12.385936 -423.314161) (xy 12.431717 -423.396113) (xy 12.470383 -423.481652)
			(xy 12.501655 -423.570161) (xy 12.525309 -423.661004) (xy 12.541173 -423.753526) (xy 12.549134 -423.84706)
			(xy 12.549632 -423.893996) (xy 12.549134 -423.940932) (xy 12.541173 -424.034466) (xy 12.525309 -424.126988)
			(xy 12.501655 -424.217831) (xy 12.470383 -424.30634) (xy 12.431717 -424.391879) (xy 12.385936 -424.473831)
			(xy 12.33337 -424.551605) (xy 12.274397 -424.62464) (xy 12.209444 -424.692412) (xy 12.138977 -424.754431)
			(xy 12.063504 -424.81025) (xy 11.983569 -424.859468) (xy 11.899748 -424.90173) (xy 11.812645 -424.93673)
			(xy 11.722888 -424.964218) (xy 11.631123 -424.983995) (xy 11.538011 -424.995918) (xy 11.444224 -424.999903)
			(xy 11.350437 -424.995918) (xy 11.257325 -424.983995) (xy 11.16556 -424.964218) (xy 11.075803 -424.93673)
			(xy 10.9887 -424.90173) (xy 10.904879 -424.859468) (xy 10.824944 -424.81025) (xy 10.749471 -424.754431)
			(xy 10.679004 -424.692412) (xy 10.614051 -424.62464) (xy 10.555078 -424.551605) (xy 10.502512 -424.473831)
			(xy 10.456731 -424.391879) (xy 10.418065 -424.30634) (xy 10.386793 -424.217831) (xy 10.363139 -424.126988)
			(xy 10.347275 -424.034466) (xy 10.339314 -423.940932) (xy 7.049018 -423.940932) (xy 7.041057 -424.034466)
			(xy 7.025193 -424.126988) (xy 7.001539 -424.217831) (xy 6.970267 -424.30634) (xy 6.931601 -424.391879)
			(xy 6.88582 -424.473831) (xy 6.833254 -424.551605) (xy 6.774281 -424.62464) (xy 6.709328 -424.692412)
			(xy 6.638861 -424.754431) (xy 6.563388 -424.81025) (xy 6.483453 -424.859468) (xy 6.399632 -424.90173)
			(xy 6.312529 -424.93673) (xy 6.222772 -424.964218) (xy 6.131007 -424.983995) (xy 6.037895 -424.995918)
			(xy 5.944108 -424.999903) (xy 5.850321 -424.995918) (xy 5.757209 -424.983995) (xy 5.665444 -424.964218)
			(xy 5.575687 -424.93673) (xy 5.488584 -424.90173) (xy 5.404763 -424.859468) (xy 5.324828 -424.81025)
			(xy 5.249355 -424.754431) (xy 5.178888 -424.692412) (xy 5.113935 -424.62464) (xy 5.054962 -424.551605)
			(xy 5.002396 -424.473831) (xy 4.956615 -424.391879) (xy 4.917949 -424.30634) (xy 4.886677 -424.217831)
			(xy 4.863023 -424.126988) (xy 4.847159 -424.034466) (xy 4.839198 -423.940932) (xy 1.27 -423.940932)
			(xy 1.27 -428.141076) (xy 4.839198 -428.141076) (xy 4.839198 -428.047204) (xy 4.847159 -427.95367)
			(xy 4.863023 -427.861148) (xy 4.886677 -427.770305) (xy 4.917949 -427.681796) (xy 4.956615 -427.596257)
			(xy 5.002396 -427.514305) (xy 5.054962 -427.436531) (xy 5.113935 -427.363496) (xy 5.178888 -427.295724)
			(xy 5.249355 -427.233705) (xy 5.324828 -427.177886) (xy 5.404763 -427.128668) (xy 5.488584 -427.086406)
			(xy 5.575687 -427.051406) (xy 5.665444 -427.023918) (xy 5.757209 -427.004141) (xy 5.850321 -426.992218)
			(xy 5.944108 -426.988234) (xy 6.037895 -426.992218) (xy 6.131007 -427.004141) (xy 6.222772 -427.023918)
			(xy 6.312529 -427.051406) (xy 6.399632 -427.086406) (xy 6.483453 -427.128668) (xy 6.563388 -427.177886)
			(xy 6.638861 -427.233705) (xy 6.709328 -427.295724) (xy 6.774281 -427.363496) (xy 6.833254 -427.436531)
			(xy 6.88582 -427.514305) (xy 6.931601 -427.596257) (xy 6.970267 -427.681796) (xy 7.001539 -427.770305)
			(xy 7.025193 -427.861148) (xy 7.041057 -427.95367) (xy 7.049018 -428.047204) (xy 7.049516 -428.09414)
			(xy 7.049018 -428.141076) (xy 7.041057 -428.23461) (xy 7.025193 -428.327132) (xy 7.001539 -428.417975)
			(xy 6.970267 -428.506484) (xy 6.931601 -428.592023) (xy 6.88582 -428.673975) (xy 6.833254 -428.751749)
			(xy 6.774281 -428.824784) (xy 6.709328 -428.892556) (xy 6.638861 -428.954575) (xy 6.563388 -429.010394)
			(xy 6.483453 -429.059612) (xy 6.399632 -429.101874) (xy 6.312529 -429.136874) (xy 6.222772 -429.164362)
			(xy 6.131007 -429.184139) (xy 6.037895 -429.196062) (xy 5.944108 -429.200047) (xy 5.850321 -429.196062)
			(xy 5.757209 -429.184139) (xy 5.665444 -429.164362) (xy 5.575687 -429.136874) (xy 5.488584 -429.101874)
			(xy 5.404763 -429.059612) (xy 5.324828 -429.010394) (xy 5.249355 -428.954575) (xy 5.178888 -428.892556)
			(xy 5.113935 -428.824784) (xy 5.054962 -428.751749) (xy 5.002396 -428.673975) (xy 4.956615 -428.592023)
			(xy 4.917949 -428.506484) (xy 4.886677 -428.417975) (xy 4.863023 -428.327132) (xy 4.847159 -428.23461)
			(xy 4.839198 -428.141076) (xy 1.27 -428.141076) (xy 1.27 -432.340966) (xy 4.839198 -432.340966) (xy 4.839198 -432.247094)
			(xy 4.847159 -432.15356) (xy 4.863023 -432.061038) (xy 4.886677 -431.970195) (xy 4.917949 -431.881686)
			(xy 4.956615 -431.796147) (xy 5.002396 -431.714195) (xy 5.054962 -431.636421) (xy 5.113935 -431.563386)
			(xy 5.178888 -431.495614) (xy 5.249355 -431.433595) (xy 5.324828 -431.377776) (xy 5.404763 -431.328558)
			(xy 5.488584 -431.286296) (xy 5.575687 -431.251296) (xy 5.665444 -431.223808) (xy 5.757209 -431.204031)
			(xy 5.850321 -431.192108) (xy 5.944108 -431.188124) (xy 6.037895 -431.192108) (xy 6.131007 -431.204031)
			(xy 6.222772 -431.223808) (xy 6.312529 -431.251296) (xy 6.399632 -431.286296) (xy 6.483453 -431.328558)
			(xy 6.563388 -431.377776) (xy 6.638861 -431.433595) (xy 6.709328 -431.495614) (xy 6.774281 -431.563386)
			(xy 6.833254 -431.636421) (xy 6.88582 -431.714195) (xy 6.931601 -431.796147) (xy 6.970267 -431.881686)
			(xy 7.001539 -431.970195) (xy 7.025193 -432.061038) (xy 7.041057 -432.15356) (xy 7.049018 -432.247094)
			(xy 7.049516 -432.29403) (xy 7.049018 -432.340966) (xy 7.041057 -432.4345) (xy 7.025193 -432.527022)
			(xy 7.001539 -432.617865) (xy 6.970267 -432.706374) (xy 6.931601 -432.791913) (xy 6.88582 -432.873865)
			(xy 6.833254 -432.951639) (xy 6.774281 -433.024674) (xy 6.709328 -433.092446) (xy 6.638861 -433.154465)
			(xy 6.563388 -433.210284) (xy 6.483453 -433.259502) (xy 6.399632 -433.301764) (xy 6.312529 -433.336764)
			(xy 6.222772 -433.364252) (xy 6.131007 -433.384029) (xy 6.037895 -433.395952) (xy 5.944108 -433.399937)
			(xy 5.850321 -433.395952) (xy 5.757209 -433.384029) (xy 5.665444 -433.364252) (xy 5.575687 -433.336764)
			(xy 5.488584 -433.301764) (xy 5.404763 -433.259502) (xy 5.324828 -433.210284) (xy 5.249355 -433.154465)
			(xy 5.178888 -433.092446) (xy 5.113935 -433.024674) (xy 5.054962 -432.951639) (xy 5.002396 -432.873865)
			(xy 4.956615 -432.791913) (xy 4.917949 -432.706374) (xy 4.886677 -432.617865) (xy 4.863023 -432.527022)
			(xy 4.847159 -432.4345) (xy 4.839198 -432.340966) (xy 1.27 -432.340966) (xy 1.27 -436.540856) (xy 4.839198 -436.540856)
			(xy 4.839198 -436.446984) (xy 4.847159 -436.35345) (xy 4.863023 -436.260928) (xy 4.886677 -436.170085)
			(xy 4.917949 -436.081576) (xy 4.956615 -435.996037) (xy 5.002396 -435.914085) (xy 5.054962 -435.836311)
			(xy 5.113935 -435.763276) (xy 5.178888 -435.695504) (xy 5.249355 -435.633485) (xy 5.324828 -435.577666)
			(xy 5.404763 -435.528448) (xy 5.488584 -435.486186) (xy 5.575687 -435.451186) (xy 5.665444 -435.423698)
			(xy 5.757209 -435.403921) (xy 5.850321 -435.391998) (xy 5.944108 -435.388014) (xy 6.037895 -435.391998)
			(xy 6.131007 -435.403921) (xy 6.222772 -435.423698) (xy 6.312529 -435.451186) (xy 6.399632 -435.486186)
			(xy 6.483453 -435.528448) (xy 6.563388 -435.577666) (xy 6.638861 -435.633485) (xy 6.709328 -435.695504)
			(xy 6.774281 -435.763276) (xy 6.833254 -435.836311) (xy 6.88582 -435.914085) (xy 6.931601 -435.996037)
			(xy 6.970267 -436.081576) (xy 7.001539 -436.170085) (xy 7.025193 -436.260928) (xy 7.041057 -436.35345)
			(xy 7.049018 -436.446984) (xy 7.049516 -436.49392) (xy 7.049018 -436.540856) (xy 7.041057 -436.63439)
			(xy 7.025193 -436.726912) (xy 7.001539 -436.817755) (xy 6.970267 -436.906264) (xy 6.931601 -436.991803)
			(xy 6.88582 -437.073755) (xy 6.833254 -437.151529) (xy 6.774281 -437.224564) (xy 6.709328 -437.292336)
			(xy 6.638861 -437.354355) (xy 6.563388 -437.410174) (xy 6.483453 -437.459392) (xy 6.399632 -437.501654)
			(xy 6.312529 -437.536654) (xy 6.222772 -437.564142) (xy 6.131007 -437.583919) (xy 6.037895 -437.595842)
			(xy 5.944108 -437.599827) (xy 5.850321 -437.595842) (xy 5.757209 -437.583919) (xy 5.665444 -437.564142)
			(xy 5.575687 -437.536654) (xy 5.488584 -437.501654) (xy 5.404763 -437.459392) (xy 5.324828 -437.410174)
			(xy 5.249355 -437.354355) (xy 5.178888 -437.292336) (xy 5.113935 -437.224564) (xy 5.054962 -437.151529)
			(xy 5.002396 -437.073755) (xy 4.956615 -436.991803) (xy 4.917949 -436.906264) (xy 4.886677 -436.817755)
			(xy 4.863023 -436.726912) (xy 4.847159 -436.63439) (xy 4.839198 -436.540856) (xy 1.27 -436.540856)
			(xy 1.27 -440.741) (xy 4.839198 -440.741) (xy 4.839198 -440.647128) (xy 4.847159 -440.553594) (xy 4.863023 -440.461072)
			(xy 4.886677 -440.370229) (xy 4.917949 -440.28172) (xy 4.956615 -440.196181) (xy 5.002396 -440.114229)
			(xy 5.054962 -440.036455) (xy 5.113935 -439.96342) (xy 5.178888 -439.895648) (xy 5.249355 -439.833629)
			(xy 5.324828 -439.77781) (xy 5.404763 -439.728592) (xy 5.488584 -439.68633) (xy 5.575687 -439.65133)
			(xy 5.665444 -439.623842) (xy 5.757209 -439.604065) (xy 5.850321 -439.592142) (xy 5.944108 -439.588158)
			(xy 6.037895 -439.592142) (xy 6.131007 -439.604065) (xy 6.222772 -439.623842) (xy 6.312529 -439.65133)
			(xy 6.399632 -439.68633) (xy 6.483453 -439.728592) (xy 6.563388 -439.77781) (xy 6.638861 -439.833629)
			(xy 6.709328 -439.895648) (xy 6.774281 -439.96342) (xy 6.833254 -440.036455) (xy 6.88582 -440.114229)
			(xy 6.931601 -440.196181) (xy 6.970267 -440.28172) (xy 7.001539 -440.370229) (xy 7.025193 -440.461072)
			(xy 7.041057 -440.553594) (xy 7.049018 -440.647128) (xy 7.049516 -440.694064) (xy 7.049018 -440.741)
			(xy 7.041057 -440.834534) (xy 7.025193 -440.927056) (xy 7.001539 -441.017899) (xy 6.970267 -441.106408)
			(xy 6.931601 -441.191947) (xy 6.88582 -441.273899) (xy 6.833254 -441.351673) (xy 6.774281 -441.424708)
			(xy 6.709328 -441.49248) (xy 6.638861 -441.554499) (xy 6.563388 -441.610318) (xy 6.483453 -441.659536)
			(xy 6.399632 -441.701798) (xy 6.312529 -441.736798) (xy 6.222772 -441.764286) (xy 6.131007 -441.784063)
			(xy 6.037895 -441.795986) (xy 5.944108 -441.799971) (xy 5.850321 -441.795986) (xy 5.757209 -441.784063)
			(xy 5.665444 -441.764286) (xy 5.575687 -441.736798) (xy 5.488584 -441.701798) (xy 5.404763 -441.659536)
			(xy 5.324828 -441.610318) (xy 5.249355 -441.554499) (xy 5.178888 -441.49248) (xy 5.113935 -441.424708)
			(xy 5.054962 -441.351673) (xy 5.002396 -441.273899) (xy 4.956615 -441.191947) (xy 4.917949 -441.106408)
			(xy 4.886677 -441.017899) (xy 4.863023 -440.927056) (xy 4.847159 -440.834534) (xy 4.839198 -440.741)
			(xy 1.27 -440.741) (xy 1.27 -444.94089) (xy 4.839198 -444.94089) (xy 4.839198 -444.847018) (xy 4.847159 -444.753484)
			(xy 4.863023 -444.660962) (xy 4.886677 -444.570119) (xy 4.917949 -444.48161) (xy 4.956615 -444.396071)
			(xy 5.002396 -444.314119) (xy 5.054962 -444.236345) (xy 5.113935 -444.16331) (xy 5.178888 -444.095538)
			(xy 5.249355 -444.033519) (xy 5.324828 -443.9777) (xy 5.404763 -443.928482) (xy 5.488584 -443.88622)
			(xy 5.575687 -443.85122) (xy 5.665444 -443.823732) (xy 5.757209 -443.803955) (xy 5.850321 -443.792032)
			(xy 5.944108 -443.788048) (xy 6.037895 -443.792032) (xy 6.131007 -443.803955) (xy 6.222772 -443.823732)
			(xy 6.312529 -443.85122) (xy 6.399632 -443.88622) (xy 6.483453 -443.928482) (xy 6.563388 -443.9777)
			(xy 6.638861 -444.033519) (xy 6.657198 -444.049658) (xy 23.435816 -444.049658) (xy 23.439887 -443.994036)
			(xy 23.452013 -443.939599) (xy 23.471936 -443.887508) (xy 23.499232 -443.838873) (xy 23.533318 -443.79473)
			(xy 23.573467 -443.756021) (xy 23.618825 -443.72357) (xy 23.668425 -443.698069) (xy 23.721209 -443.680062)
			(xy 23.776052 -443.669932) (xy 23.831786 -443.667895) (xy 23.887223 -443.673995) (xy 23.94118 -443.688101)
			(xy 23.992509 -443.709913) (xy 24.040115 -443.738967) (xy 24.082983 -443.774642) (xy 24.1202 -443.816179)
			(xy 24.150973 -443.862692) (xy 24.174645 -443.913189) (xy 24.190713 -443.966596) (xy 24.198833 -444.021772)
			(xy 24.199342 -444.049658) (xy 24.198833 -444.077544) (xy 24.190713 -444.13272) (xy 24.174645 -444.186127)
			(xy 24.150973 -444.236624) (xy 24.1202 -444.283137) (xy 24.082983 -444.324674) (xy 24.040115 -444.360349)
			(xy 23.992509 -444.389403) (xy 23.94118 -444.411215) (xy 23.887223 -444.425321) (xy 23.831786 -444.431421)
			(xy 23.776052 -444.429384) (xy 23.721209 -444.419254) (xy 23.668425 -444.401247) (xy 23.618825 -444.375746)
			(xy 23.573467 -444.343295) (xy 23.533318 -444.304586) (xy 23.499232 -444.260443) (xy 23.471936 -444.211808)
			(xy 23.452013 -444.159717) (xy 23.439887 -444.10528) (xy 23.435816 -444.049658) (xy 6.657198 -444.049658)
			(xy 6.709328 -444.095538) (xy 6.774281 -444.16331) (xy 6.833254 -444.236345) (xy 6.88582 -444.314119)
			(xy 6.931601 -444.396071) (xy 6.970267 -444.48161) (xy 7.001539 -444.570119) (xy 7.025193 -444.660962)
			(xy 7.041057 -444.753484) (xy 7.049018 -444.847018) (xy 7.049516 -444.893954) (xy 7.049018 -444.94089)
			(xy 7.041057 -445.034424) (xy 7.025193 -445.126946) (xy 7.001539 -445.217789) (xy 6.970267 -445.306298)
			(xy 6.931601 -445.391837) (xy 6.88582 -445.473789) (xy 6.833254 -445.551563) (xy 6.774281 -445.624598)
			(xy 6.709328 -445.69237) (xy 6.638861 -445.754389) (xy 6.563388 -445.810208) (xy 6.558149 -445.813434)
			(xy 13.574774 -445.813434) (xy 13.578845 -445.757812) (xy 13.590971 -445.703375) (xy 13.610894 -445.651284)
			(xy 13.63819 -445.602649) (xy 13.672276 -445.558506) (xy 13.712425 -445.519797) (xy 13.757783 -445.487346)
			(xy 13.807383 -445.461845) (xy 13.860167 -445.443838) (xy 13.91501 -445.433708) (xy 13.970744 -445.431671)
			(xy 14.026181 -445.437771) (xy 14.080138 -445.451877) (xy 14.131467 -445.473689) (xy 14.179073 -445.502743)
			(xy 14.221941 -445.538418) (xy 14.259158 -445.579955) (xy 14.289931 -445.626468) (xy 14.313603 -445.676965)
			(xy 14.329671 -445.730372) (xy 14.337791 -445.785548) (xy 14.3383 -445.813434) (xy 14.337791 -445.84132)
			(xy 14.329671 -445.896496) (xy 14.313603 -445.949903) (xy 14.289931 -446.0004) (xy 14.259158 -446.046913)
			(xy 14.221941 -446.08845) (xy 14.179073 -446.124125) (xy 14.131467 -446.153179) (xy 14.080138 -446.174991)
			(xy 14.026181 -446.189097) (xy 13.970744 -446.195197) (xy 13.91501 -446.19316) (xy 13.860167 -446.18303)
			(xy 13.807383 -446.165023) (xy 13.757783 -446.139522) (xy 13.712425 -446.107071) (xy 13.672276 -446.068362)
			(xy 13.63819 -446.024219) (xy 13.610894 -445.975584) (xy 13.590971 -445.923493) (xy 13.578845 -445.869056)
			(xy 13.574774 -445.813434) (xy 6.558149 -445.813434) (xy 6.483453 -445.859426) (xy 6.399632 -445.901688)
			(xy 6.312529 -445.936688) (xy 6.222772 -445.964176) (xy 6.131007 -445.983953) (xy 6.037895 -445.995876)
			(xy 5.944108 -445.999861) (xy 5.850321 -445.995876) (xy 5.757209 -445.983953) (xy 5.665444 -445.964176)
			(xy 5.575687 -445.936688) (xy 5.488584 -445.901688) (xy 5.404763 -445.859426) (xy 5.324828 -445.810208)
			(xy 5.249355 -445.754389) (xy 5.178888 -445.69237) (xy 5.113935 -445.624598) (xy 5.054962 -445.551563)
			(xy 5.002396 -445.473789) (xy 4.956615 -445.391837) (xy 4.917949 -445.306298) (xy 4.886677 -445.217789)
			(xy 4.863023 -445.126946) (xy 4.847159 -445.034424) (xy 4.839198 -444.94089) (xy 1.27 -444.94089)
			(xy 1.27 -446.633362) (xy 29.519874 -446.633362) (xy 29.519874 -446.546462) (xy 29.527892 -446.459933)
			(xy 29.54386 -446.374513) (xy 29.567641 -446.290931) (xy 29.599033 -446.209899) (xy 29.637767 -446.13211)
			(xy 29.683514 -446.058226) (xy 29.735883 -445.988879) (xy 29.794427 -445.924659) (xy 29.858647 -445.866115)
			(xy 29.927994 -445.813746) (xy 30.001878 -445.767999) (xy 30.079667 -445.729265) (xy 30.160699 -445.697873)
			(xy 30.244281 -445.674092) (xy 30.329701 -445.658124) (xy 30.41623 -445.650106) (xy 30.50313 -445.650106)
			(xy 30.589659 -445.658124) (xy 30.675079 -445.674092) (xy 30.758661 -445.697873) (xy 30.839693 -445.729265)
			(xy 30.917482 -445.767999) (xy 30.991366 -445.813746) (xy 31.060713 -445.866115) (xy 31.124933 -445.924659)
			(xy 31.183477 -445.988879) (xy 31.235846 -446.058226) (xy 31.281593 -446.13211) (xy 31.320327 -446.209899)
			(xy 31.351719 -446.290931) (xy 31.3755 -446.374513) (xy 31.391468 -446.459933) (xy 31.399486 -446.546462)
			(xy 31.399988 -446.589912) (xy 31.399486 -446.633362) (xy 34.599874 -446.633362) (xy 34.599874 -446.546462)
			(xy 34.607892 -446.459933) (xy 34.62386 -446.374513) (xy 34.647641 -446.290931) (xy 34.679033 -446.209899)
			(xy 34.717767 -446.13211) (xy 34.763514 -446.058226) (xy 34.815883 -445.988879) (xy 34.874427 -445.924659)
			(xy 34.938647 -445.866115) (xy 35.007994 -445.813746) (xy 35.081878 -445.767999) (xy 35.159667 -445.729265)
			(xy 35.240699 -445.697873) (xy 35.324281 -445.674092) (xy 35.409701 -445.658124) (xy 35.49623 -445.650106)
			(xy 35.58313 -445.650106) (xy 35.669659 -445.658124) (xy 35.755079 -445.674092) (xy 35.838661 -445.697873)
			(xy 35.919693 -445.729265) (xy 35.997482 -445.767999) (xy 36.071366 -445.813746) (xy 36.140713 -445.866115)
			(xy 36.204933 -445.924659) (xy 36.263477 -445.988879) (xy 36.315846 -446.058226) (xy 36.361593 -446.13211)
			(xy 36.400327 -446.209899) (xy 36.431719 -446.290931) (xy 36.4555 -446.374513) (xy 36.471468 -446.459933)
			(xy 36.479486 -446.546462) (xy 36.479988 -446.589912) (xy 36.479486 -446.633362) (xy 36.471468 -446.719891)
			(xy 36.4555 -446.805311) (xy 36.431719 -446.888893) (xy 36.400327 -446.969925) (xy 36.361593 -447.047714)
			(xy 36.315846 -447.121598) (xy 36.263477 -447.190945) (xy 36.204933 -447.255165) (xy 36.140713 -447.313709)
			(xy 36.071366 -447.366078) (xy 35.997482 -447.411825) (xy 35.919693 -447.450559) (xy 35.838661 -447.481951)
			(xy 35.755079 -447.505732) (xy 35.669659 -447.5217) (xy 35.58313 -447.529718) (xy 35.49623 -447.529718)
			(xy 35.409701 -447.5217) (xy 35.324281 -447.505732) (xy 35.240699 -447.481951) (xy 35.159667 -447.450559)
			(xy 35.081878 -447.411825) (xy 35.007994 -447.366078) (xy 34.938647 -447.313709) (xy 34.874427 -447.255165)
			(xy 34.815883 -447.190945) (xy 34.763514 -447.121598) (xy 34.717767 -447.047714) (xy 34.679033 -446.969925)
			(xy 34.647641 -446.888893) (xy 34.62386 -446.805311) (xy 34.607892 -446.719891) (xy 34.599874 -446.633362)
			(xy 31.399486 -446.633362) (xy 31.391468 -446.719891) (xy 31.3755 -446.805311) (xy 31.351719 -446.888893)
			(xy 31.320327 -446.969925) (xy 31.281593 -447.047714) (xy 31.235846 -447.121598) (xy 31.183477 -447.190945)
			(xy 31.124933 -447.255165) (xy 31.060713 -447.313709) (xy 30.991366 -447.366078) (xy 30.917482 -447.411825)
			(xy 30.839693 -447.450559) (xy 30.758661 -447.481951) (xy 30.675079 -447.505732) (xy 30.589659 -447.5217)
			(xy 30.50313 -447.529718) (xy 30.41623 -447.529718) (xy 30.329701 -447.5217) (xy 30.244281 -447.505732)
			(xy 30.160699 -447.481951) (xy 30.079667 -447.450559) (xy 30.001878 -447.411825) (xy 29.927994 -447.366078)
			(xy 29.858647 -447.313709) (xy 29.794427 -447.255165) (xy 29.735883 -447.190945) (xy 29.683514 -447.121598)
			(xy 29.637767 -447.047714) (xy 29.599033 -446.969925) (xy 29.567641 -446.888893) (xy 29.54386 -446.805311)
			(xy 29.527892 -446.719891) (xy 29.519874 -446.633362) (xy 1.27 -446.633362) (xy 1.27 -447.250058)
			(xy 24.781254 -447.250058) (xy 24.785325 -447.194436) (xy 24.797451 -447.139999) (xy 24.817374 -447.087908)
			(xy 24.84467 -447.039273) (xy 24.878756 -446.99513) (xy 24.918905 -446.956421) (xy 24.964263 -446.92397)
			(xy 25.013863 -446.898469) (xy 25.066647 -446.880462) (xy 25.12149 -446.870332) (xy 25.177224 -446.868295)
			(xy 25.232661 -446.874395) (xy 25.286618 -446.888501) (xy 25.337947 -446.910313) (xy 25.385553 -446.939367)
			(xy 25.428421 -446.975042) (xy 25.465638 -447.016579) (xy 25.496411 -447.063092) (xy 25.520083 -447.113589)
			(xy 25.536151 -447.166996) (xy 25.544271 -447.222172) (xy 25.54478 -447.250058) (xy 25.544271 -447.277944)
			(xy 25.536151 -447.33312) (xy 25.520083 -447.386527) (xy 25.496411 -447.437024) (xy 25.465638 -447.483537)
			(xy 25.428421 -447.525074) (xy 25.385553 -447.560749) (xy 25.337947 -447.589803) (xy 25.286618 -447.611615)
			(xy 25.232661 -447.625721) (xy 25.177224 -447.631821) (xy 25.12149 -447.629784) (xy 25.066647 -447.619654)
			(xy 25.013863 -447.601647) (xy 24.964263 -447.576146) (xy 24.918905 -447.543695) (xy 24.878756 -447.504986)
			(xy 24.84467 -447.460843) (xy 24.817374 -447.412208) (xy 24.797451 -447.360117) (xy 24.785325 -447.30568)
			(xy 24.781254 -447.250058) (xy 1.27 -447.250058) (xy 1.27 -447.797428) (xy 13.608302 -447.797428)
			(xy 13.612373 -447.741806) (xy 13.624499 -447.687369) (xy 13.644422 -447.635278) (xy 13.671718 -447.586643)
			(xy 13.705804 -447.5425) (xy 13.745953 -447.503791) (xy 13.791311 -447.47134) (xy 13.840911 -447.445839)
			(xy 13.893695 -447.427832) (xy 13.948538 -447.417702) (xy 14.004272 -447.415665) (xy 14.059709 -447.421765)
			(xy 14.113666 -447.435871) (xy 14.164995 -447.457683) (xy 14.212601 -447.486737) (xy 14.255469 -447.522412)
			(xy 14.292686 -447.563949) (xy 14.323459 -447.610462) (xy 14.347131 -447.660959) (xy 14.363199 -447.714366)
			(xy 14.371319 -447.769542) (xy 14.371828 -447.797428) (xy 14.371319 -447.825314) (xy 14.363199 -447.88049)
			(xy 14.347131 -447.933897) (xy 14.323459 -447.984394) (xy 14.292686 -448.030907) (xy 14.255469 -448.072444)
			(xy 14.212601 -448.108119) (xy 14.164995 -448.137173) (xy 14.113666 -448.158985) (xy 14.059709 -448.173091)
			(xy 14.004272 -448.179191) (xy 13.948538 -448.177154) (xy 13.893695 -448.167024) (xy 13.840911 -448.149017)
			(xy 13.791311 -448.123516) (xy 13.745953 -448.091065) (xy 13.705804 -448.052356) (xy 13.671718 -448.008213)
			(xy 13.644422 -447.959578) (xy 13.624499 -447.907487) (xy 13.612373 -447.85305) (xy 13.608302 -447.797428)
			(xy 1.27 -447.797428) (xy 1.27 -449.141034) (xy 4.839198 -449.141034) (xy 4.839198 -449.047162) (xy 4.847159 -448.953628)
			(xy 4.863023 -448.861106) (xy 4.886677 -448.770263) (xy 4.917949 -448.681754) (xy 4.956615 -448.596215)
			(xy 5.002396 -448.514263) (xy 5.054962 -448.436489) (xy 5.113935 -448.363454) (xy 5.178888 -448.295682)
			(xy 5.249355 -448.233663) (xy 5.324828 -448.177844) (xy 5.404763 -448.128626) (xy 5.488584 -448.086364)
			(xy 5.575687 -448.051364) (xy 5.665444 -448.023876) (xy 5.757209 -448.004099) (xy 5.850321 -447.992176)
			(xy 5.944108 -447.988192) (xy 6.037895 -447.992176) (xy 6.131007 -448.004099) (xy 6.222772 -448.023876)
			(xy 6.312529 -448.051364) (xy 6.399632 -448.086364) (xy 6.483453 -448.128626) (xy 6.563388 -448.177844)
			(xy 6.638861 -448.233663) (xy 6.709328 -448.295682) (xy 6.774281 -448.363454) (xy 6.833254 -448.436489)
			(xy 6.88582 -448.514263) (xy 6.931601 -448.596215) (xy 6.970267 -448.681754) (xy 7.001539 -448.770263)
			(xy 7.025193 -448.861106) (xy 7.041057 -448.953628) (xy 7.049018 -449.047162) (xy 7.049516 -449.094098)
			(xy 7.049018 -449.141034) (xy 10.339314 -449.141034) (xy 10.339314 -449.047162) (xy 10.347275 -448.953628)
			(xy 10.363139 -448.861106) (xy 10.386793 -448.770263) (xy 10.418065 -448.681754) (xy 10.456731 -448.596215)
			(xy 10.502512 -448.514263) (xy 10.555078 -448.436489) (xy 10.614051 -448.363454) (xy 10.679004 -448.295682)
			(xy 10.749471 -448.233663) (xy 10.824944 -448.177844) (xy 10.904879 -448.128626) (xy 10.9887 -448.086364)
			(xy 11.075803 -448.051364) (xy 11.16556 -448.023876) (xy 11.257325 -448.004099) (xy 11.350437 -447.992176)
			(xy 11.444224 -447.988192) (xy 11.538011 -447.992176) (xy 11.631123 -448.004099) (xy 11.722888 -448.023876)
			(xy 11.812645 -448.051364) (xy 11.899748 -448.086364) (xy 11.983569 -448.128626) (xy 12.063504 -448.177844)
			(xy 12.138977 -448.233663) (xy 12.209444 -448.295682) (xy 12.238259 -448.325748) (xy 22.848822 -448.325748)
			(xy 22.852893 -448.270126) (xy 22.865019 -448.215689) (xy 22.884942 -448.163598) (xy 22.912238 -448.114963)
			(xy 22.946324 -448.07082) (xy 22.986473 -448.032111) (xy 23.031831 -447.99966) (xy 23.081431 -447.974159)
			(xy 23.134215 -447.956152) (xy 23.189058 -447.946022) (xy 23.244792 -447.943985) (xy 23.300229 -447.950085)
			(xy 23.354186 -447.964191) (xy 23.405515 -447.986003) (xy 23.453121 -448.015057) (xy 23.495989 -448.050732)
			(xy 23.533206 -448.092269) (xy 23.563979 -448.138782) (xy 23.587651 -448.189279) (xy 23.603719 -448.242686)
			(xy 23.611839 -448.297862) (xy 23.612348 -448.325748) (xy 23.611839 -448.353634) (xy 23.603719 -448.40881)
			(xy 23.587651 -448.462217) (xy 23.573039 -448.493388) (xy 24.790144 -448.493388) (xy 24.794215 -448.437766)
			(xy 24.806341 -448.383329) (xy 24.826264 -448.331238) (xy 24.85356 -448.282603) (xy 24.887646 -448.23846)
			(xy 24.927795 -448.199751) (xy 24.973153 -448.1673) (xy 25.022753 -448.141799) (xy 25.075537 -448.123792)
			(xy 25.13038 -448.113662) (xy 25.186114 -448.111625) (xy 25.241551 -448.117725) (xy 25.295508 -448.131831)
			(xy 25.346837 -448.153643) (xy 25.394443 -448.182697) (xy 25.437311 -448.218372) (xy 25.474528 -448.259909)
			(xy 25.505301 -448.306422) (xy 25.528973 -448.356919) (xy 25.545041 -448.410326) (xy 25.553161 -448.465502)
			(xy 25.55367 -448.493388) (xy 25.553161 -448.521274) (xy 25.545041 -448.57645) (xy 25.528973 -448.629857)
			(xy 25.505301 -448.680354) (xy 25.474528 -448.726867) (xy 25.437311 -448.768404) (xy 25.394443 -448.804079)
			(xy 25.346837 -448.833133) (xy 25.295508 -448.854945) (xy 25.241551 -448.869051) (xy 25.186114 -448.875151)
			(xy 25.13038 -448.873114) (xy 25.075537 -448.862984) (xy 25.022753 -448.844977) (xy 24.973153 -448.819476)
			(xy 24.927795 -448.787025) (xy 24.887646 -448.748316) (xy 24.85356 -448.704173) (xy 24.826264 -448.655538)
			(xy 24.806341 -448.603447) (xy 24.794215 -448.54901) (xy 24.790144 -448.493388) (xy 23.573039 -448.493388)
			(xy 23.563979 -448.512714) (xy 23.533206 -448.559227) (xy 23.495989 -448.600764) (xy 23.453121 -448.636439)
			(xy 23.405515 -448.665493) (xy 23.354186 -448.687305) (xy 23.300229 -448.701411) (xy 23.244792 -448.707511)
			(xy 23.189058 -448.705474) (xy 23.134215 -448.695344) (xy 23.081431 -448.677337) (xy 23.031831 -448.651836)
			(xy 22.986473 -448.619385) (xy 22.946324 -448.580676) (xy 22.912238 -448.536533) (xy 22.884942 -448.487898)
			(xy 22.865019 -448.435807) (xy 22.852893 -448.38137) (xy 22.848822 -448.325748) (xy 12.238259 -448.325748)
			(xy 12.274397 -448.363454) (xy 12.33337 -448.436489) (xy 12.385936 -448.514263) (xy 12.431717 -448.596215)
			(xy 12.470383 -448.681754) (xy 12.501655 -448.770263) (xy 12.525309 -448.861106) (xy 12.541173 -448.953628)
			(xy 12.549134 -449.047162) (xy 12.549632 -449.094098) (xy 12.549134 -449.141034) (xy 12.541173 -449.234568)
			(xy 12.525309 -449.32709) (xy 12.501655 -449.417933) (xy 12.470383 -449.506442) (xy 12.431717 -449.591981)
			(xy 12.385936 -449.673933) (xy 12.33337 -449.751707) (xy 12.300762 -449.79209) (xy 13.726158 -449.79209)
			(xy 13.730229 -449.736468) (xy 13.742355 -449.682031) (xy 13.762278 -449.62994) (xy 13.789574 -449.581305)
			(xy 13.82366 -449.537162) (xy 13.863809 -449.498453) (xy 13.909167 -449.466002) (xy 13.958767 -449.440501)
			(xy 14.011551 -449.422494) (xy 14.066394 -449.412364) (xy 14.122128 -449.410327) (xy 14.177565 -449.416427)
			(xy 14.231522 -449.430533) (xy 14.282851 -449.452345) (xy 14.330457 -449.481399) (xy 14.373325 -449.517074)
			(xy 14.410542 -449.558611) (xy 14.441315 -449.605124) (xy 14.464987 -449.655621) (xy 14.481055 -449.709028)
			(xy 14.489175 -449.764204) (xy 14.489684 -449.79209) (xy 14.489175 -449.819976) (xy 14.481055 -449.875152)
			(xy 14.464987 -449.928559) (xy 14.441315 -449.979056) (xy 14.410542 -450.025569) (xy 14.373325 -450.067106)
			(xy 14.330457 -450.102781) (xy 14.315654 -450.111815) (xy 20.03353 -450.111815) (xy 20.037525 -450.057789)
			(xy 20.049123 -450.004872) (xy 20.06809 -449.954127) (xy 20.094045 -449.906577) (xy 20.126467 -449.863176)
			(xy 20.145248 -449.843652) (xy 20.16051 -449.827612) (xy 20.185864 -449.791322) (xy 20.204544 -449.751187)
			(xy 20.215984 -449.708421) (xy 20.219838 -449.66432) (xy 20.215991 -449.620218) (xy 20.204557 -449.577451)
			(xy 20.185884 -449.537312) (xy 20.160536 -449.501018) (xy 20.145248 -449.485004) (xy 20.126375 -449.465373)
			(xy 20.093818 -449.421722) (xy 20.0678 -449.373884) (xy 20.048848 -449.322833) (xy 20.037349 -449.269606)
			(xy 20.033535 -449.215284) (xy 20.037485 -449.160973) (xy 20.049118 -449.107774) (xy 20.068198 -449.056771)
			(xy 20.094336 -449.008999) (xy 20.127002 -448.96543) (xy 20.165532 -448.926948) (xy 20.209143 -448.894337)
			(xy 20.256947 -448.868259) (xy 20.307975 -448.849243) (xy 20.361187 -448.837677) (xy 20.415504 -448.833795)
			(xy 20.469821 -448.837677) (xy 20.523033 -448.849243) (xy 20.574061 -448.868259) (xy 20.621865 -448.894337)
			(xy 20.665476 -448.926948) (xy 20.704006 -448.96543) (xy 20.736672 -449.008999) (xy 20.76281 -449.056771)
			(xy 20.78189 -449.107774) (xy 20.793523 -449.160973) (xy 20.794424 -449.173362) (xy 29.519874 -449.173362)
			(xy 29.519874 -449.086462) (xy 29.527892 -448.999933) (xy 29.54386 -448.914513) (xy 29.567641 -448.830931)
			(xy 29.599033 -448.749899) (xy 29.637767 -448.67211) (xy 29.683514 -448.598226) (xy 29.735883 -448.528879)
			(xy 29.794427 -448.464659) (xy 29.858647 -448.406115) (xy 29.927994 -448.353746) (xy 30.001878 -448.307999)
			(xy 30.079667 -448.269265) (xy 30.160699 -448.237873) (xy 30.244281 -448.214092) (xy 30.329701 -448.198124)
			(xy 30.41623 -448.190106) (xy 30.50313 -448.190106) (xy 30.589659 -448.198124) (xy 30.675079 -448.214092)
			(xy 30.758661 -448.237873) (xy 30.839693 -448.269265) (xy 30.917482 -448.307999) (xy 30.991366 -448.353746)
			(xy 31.060713 -448.406115) (xy 31.124933 -448.464659) (xy 31.183477 -448.528879) (xy 31.235846 -448.598226)
			(xy 31.281593 -448.67211) (xy 31.320327 -448.749899) (xy 31.351719 -448.830931) (xy 31.3755 -448.914513)
			(xy 31.391468 -448.999933) (xy 31.399486 -449.086462) (xy 31.399988 -449.129912) (xy 31.399486 -449.173362)
			(xy 34.599874 -449.173362) (xy 34.599874 -449.086462) (xy 34.607892 -448.999933) (xy 34.62386 -448.914513)
			(xy 34.647641 -448.830931) (xy 34.679033 -448.749899) (xy 34.717767 -448.67211) (xy 34.763514 -448.598226)
			(xy 34.815883 -448.528879) (xy 34.874427 -448.464659) (xy 34.938647 -448.406115) (xy 35.007994 -448.353746)
			(xy 35.081878 -448.307999) (xy 35.159667 -448.269265) (xy 35.240699 -448.237873) (xy 35.324281 -448.214092)
			(xy 35.409701 -448.198124) (xy 35.49623 -448.190106) (xy 35.58313 -448.190106) (xy 35.669659 -448.198124)
			(xy 35.755079 -448.214092) (xy 35.838661 -448.237873) (xy 35.919693 -448.269265) (xy 35.997482 -448.307999)
			(xy 36.071366 -448.353746) (xy 36.140713 -448.406115) (xy 36.204933 -448.464659) (xy 36.263477 -448.528879)
			(xy 36.315846 -448.598226) (xy 36.361593 -448.67211) (xy 36.400327 -448.749899) (xy 36.431719 -448.830931)
			(xy 36.4555 -448.914513) (xy 36.471468 -448.999933) (xy 36.479486 -449.086462) (xy 36.479988 -449.129912)
			(xy 36.479486 -449.173362) (xy 36.471468 -449.259891) (xy 36.4555 -449.345311) (xy 36.431719 -449.428893)
			(xy 36.400327 -449.509925) (xy 36.361593 -449.587714) (xy 36.315846 -449.661598) (xy 36.263477 -449.730945)
			(xy 36.204933 -449.795165) (xy 36.140713 -449.853709) (xy 36.071366 -449.906078) (xy 35.997482 -449.951825)
			(xy 35.919693 -449.990559) (xy 35.838661 -450.021951) (xy 35.755079 -450.045732) (xy 35.669659 -450.0617)
			(xy 35.58313 -450.069718) (xy 35.49623 -450.069718) (xy 35.409701 -450.0617) (xy 35.324281 -450.045732)
			(xy 35.240699 -450.021951) (xy 35.159667 -449.990559) (xy 35.081878 -449.951825) (xy 35.007994 -449.906078)
			(xy 34.938647 -449.853709) (xy 34.874427 -449.795165) (xy 34.815883 -449.730945) (xy 34.763514 -449.661598)
			(xy 34.717767 -449.587714) (xy 34.679033 -449.509925) (xy 34.647641 -449.428893) (xy 34.62386 -449.345311)
			(xy 34.607892 -449.259891) (xy 34.599874 -449.173362) (xy 31.399486 -449.173362) (xy 31.391468 -449.259891)
			(xy 31.3755 -449.345311) (xy 31.351719 -449.428893) (xy 31.320327 -449.509925) (xy 31.281593 -449.587714)
			(xy 31.235846 -449.661598) (xy 31.183477 -449.730945) (xy 31.124933 -449.795165) (xy 31.060713 -449.853709)
			(xy 30.991366 -449.906078) (xy 30.917482 -449.951825) (xy 30.839693 -449.990559) (xy 30.758661 -450.021951)
			(xy 30.675079 -450.045732) (xy 30.589659 -450.0617) (xy 30.50313 -450.069718) (xy 30.41623 -450.069718)
			(xy 30.329701 -450.0617) (xy 30.244281 -450.045732) (xy 30.160699 -450.021951) (xy 30.079667 -449.990559)
			(xy 30.001878 -449.951825) (xy 29.927994 -449.906078) (xy 29.858647 -449.853709) (xy 29.794427 -449.795165)
			(xy 29.735883 -449.730945) (xy 29.683514 -449.661598) (xy 29.637767 -449.587714) (xy 29.599033 -449.509925)
			(xy 29.567641 -449.428893) (xy 29.54386 -449.345311) (xy 29.527892 -449.259891) (xy 29.519874 -449.173362)
			(xy 20.794424 -449.173362) (xy 20.797473 -449.215284) (xy 20.793659 -449.269606) (xy 20.78216 -449.322833)
			(xy 20.763208 -449.373884) (xy 20.73719 -449.421722) (xy 20.704633 -449.465373) (xy 20.68576 -449.485004)
			(xy 20.670441 -449.500993) (xy 20.645089 -449.537292) (xy 20.626412 -449.577437) (xy 20.614976 -449.620211)
			(xy 20.611128 -449.66432) (xy 20.614983 -449.708428) (xy 20.626425 -449.751201) (xy 20.645109 -449.791342)
			(xy 20.670467 -449.827638) (xy 20.68576 -449.843652) (xy 20.70164 -449.860162) (xy 22.18258 -449.860162)
			(xy 22.186651 -449.80454) (xy 22.198777 -449.750103) (xy 22.2187 -449.698012) (xy 22.245996 -449.649377)
			(xy 22.280082 -449.605234) (xy 22.320231 -449.566525) (xy 22.365589 -449.534074) (xy 22.415189 -449.508573)
			(xy 22.467973 -449.490566) (xy 22.522816 -449.480436) (xy 22.57855 -449.478399) (xy 22.633987 -449.484499)
			(xy 22.687944 -449.498605) (xy 22.739273 -449.520417) (xy 22.786879 -449.549471) (xy 22.829747 -449.585146)
			(xy 22.866964 -449.626683) (xy 22.897737 -449.673196) (xy 22.906082 -449.690998) (xy 26.886152 -449.690998)
			(xy 26.890223 -449.635376) (xy 26.902349 -449.580939) (xy 26.922272 -449.528848) (xy 26.949568 -449.480213)
			(xy 26.983654 -449.43607) (xy 27.023803 -449.397361) (xy 27.069161 -449.36491) (xy 27.118761 -449.339409)
			(xy 27.171545 -449.321402) (xy 27.226388 -449.311272) (xy 27.282122 -449.309235) (xy 27.337559 -449.315335)
			(xy 27.391516 -449.329441) (xy 27.442845 -449.351253) (xy 27.490451 -449.380307) (xy 27.533319 -449.415982)
			(xy 27.570536 -449.457519) (xy 27.601309 -449.504032) (xy 27.624981 -449.554529) (xy 27.641049 -449.607936)
			(xy 27.649169 -449.663112) (xy 27.649678 -449.690998) (xy 27.649169 -449.718884) (xy 27.641049 -449.77406)
			(xy 27.624981 -449.827467) (xy 27.601309 -449.877964) (xy 27.570536 -449.924477) (xy 27.533319 -449.966014)
			(xy 27.490451 -450.001689) (xy 27.442845 -450.030743) (xy 27.391516 -450.052555) (xy 27.337559 -450.066661)
			(xy 27.282122 -450.072761) (xy 27.226388 -450.070724) (xy 27.171545 -450.060594) (xy 27.118761 -450.042587)
			(xy 27.069161 -450.017086) (xy 27.023803 -449.984635) (xy 26.983654 -449.945926) (xy 26.949568 -449.901783)
			(xy 26.922272 -449.853148) (xy 26.902349 -449.801057) (xy 26.890223 -449.74662) (xy 26.886152 -449.690998)
			(xy 22.906082 -449.690998) (xy 22.921409 -449.723693) (xy 22.937477 -449.7771) (xy 22.945597 -449.832276)
			(xy 22.946106 -449.860162) (xy 22.945597 -449.888048) (xy 22.937477 -449.943224) (xy 22.921409 -449.996631)
			(xy 22.897737 -450.047128) (xy 22.866964 -450.093641) (xy 22.829747 -450.135178) (xy 22.786879 -450.170853)
			(xy 22.739273 -450.199907) (xy 22.687944 -450.221719) (xy 22.633987 -450.235825) (xy 22.57855 -450.241925)
			(xy 22.522816 -450.239888) (xy 22.467973 -450.229758) (xy 22.415189 -450.211751) (xy 22.365589 -450.18625)
			(xy 22.320231 -450.153799) (xy 22.280082 -450.11509) (xy 22.245996 -450.070947) (xy 22.2187 -450.022312)
			(xy 22.198777 -449.970221) (xy 22.186651 -449.915784) (xy 22.18258 -449.860162) (xy 20.70164 -449.860162)
			(xy 20.70454 -449.863177) (xy 20.736961 -449.906578) (xy 20.762915 -449.954128) (xy 20.781882 -450.004873)
			(xy 20.79348 -450.05779) (xy 20.797475 -450.111815) (xy 20.793787 -450.165863) (xy 20.78249 -450.218845)
			(xy 20.763812 -450.269696) (xy 20.738127 -450.317393) (xy 20.705954 -450.360978) (xy 20.687284 -450.380608)
			(xy 20.672243 -450.396602) (xy 20.647314 -450.432738) (xy 20.628959 -450.472617) (xy 20.617722 -450.515055)
			(xy 20.613938 -450.558792) (xy 20.61772 -450.602529) (xy 20.628953 -450.644968) (xy 20.647306 -450.684848)
			(xy 20.672233 -450.720986) (xy 20.687284 -450.73697) (xy 20.706592 -450.757274) (xy 20.739649 -450.80251)
			(xy 20.765734 -450.852096) (xy 20.784286 -450.904963) (xy 20.794906 -450.959975) (xy 20.797365 -451.015949)
			(xy 20.791611 -451.071681) (xy 20.777767 -451.125972) (xy 20.756131 -451.177654) (xy 20.727169 -451.225615)
			(xy 20.691503 -451.268825) (xy 20.649901 -451.306353) (xy 20.603256 -451.337393) (xy 20.552574 -451.361276)
			(xy 20.498943 -451.37749) (xy 20.443518 -451.385685) (xy 20.38749 -451.385685) (xy 20.332065 -451.37749)
			(xy 20.278434 -451.361276) (xy 20.227752 -451.337393) (xy 20.181107 -451.306353) (xy 20.139505 -451.268825)
			(xy 20.103839 -451.225615) (xy 20.074877 -451.177654) (xy 20.053241 -451.125972) (xy 20.039397 -451.071681)
			(xy 20.033643 -451.015949) (xy 20.036102 -450.959975) (xy 20.046722 -450.904963) (xy 20.065274 -450.852096)
			(xy 20.091359 -450.80251) (xy 20.124416 -450.757274) (xy 20.143724 -450.73697) (xy 20.158818 -450.721011)
			(xy 20.183803 -450.684888) (xy 20.202201 -450.645004) (xy 20.213464 -450.602551) (xy 20.217254 -450.558792)
			(xy 20.213461 -450.515034) (xy 20.202196 -450.472581) (xy 20.183795 -450.432699) (xy 20.158808 -450.396577)
			(xy 20.143724 -450.380608) (xy 20.125053 -450.360979) (xy 20.092879 -450.317394) (xy 20.067194 -450.269697)
			(xy 20.048515 -450.218846) (xy 20.037218 -450.165863) (xy 20.03353 -450.111815) (xy 14.315654 -450.111815)
			(xy 14.282851 -450.131835) (xy 14.231522 -450.153647) (xy 14.177565 -450.167753) (xy 14.122128 -450.173853)
			(xy 14.066394 -450.171816) (xy 14.011551 -450.161686) (xy 13.958767 -450.143679) (xy 13.909167 -450.118178)
			(xy 13.863809 -450.085727) (xy 13.82366 -450.047018) (xy 13.789574 -450.002875) (xy 13.762278 -449.95424)
			(xy 13.742355 -449.902149) (xy 13.730229 -449.847712) (xy 13.726158 -449.79209) (xy 12.300762 -449.79209)
			(xy 12.274397 -449.824742) (xy 12.209444 -449.892514) (xy 12.138977 -449.954533) (xy 12.063504 -450.010352)
			(xy 11.983569 -450.05957) (xy 11.899748 -450.101832) (xy 11.812645 -450.136832) (xy 11.722888 -450.16432)
			(xy 11.631123 -450.184097) (xy 11.538011 -450.19602) (xy 11.444224 -450.200005) (xy 11.350437 -450.19602)
			(xy 11.257325 -450.184097) (xy 11.16556 -450.16432) (xy 11.075803 -450.136832) (xy 10.9887 -450.101832)
			(xy 10.904879 -450.05957) (xy 10.824944 -450.010352) (xy 10.749471 -449.954533) (xy 10.679004 -449.892514)
			(xy 10.614051 -449.824742) (xy 10.555078 -449.751707) (xy 10.502512 -449.673933) (xy 10.456731 -449.591981)
			(xy 10.418065 -449.506442) (xy 10.386793 -449.417933) (xy 10.363139 -449.32709) (xy 10.347275 -449.234568)
			(xy 10.339314 -449.141034) (xy 7.049018 -449.141034) (xy 7.041057 -449.234568) (xy 7.025193 -449.32709)
			(xy 7.001539 -449.417933) (xy 6.970267 -449.506442) (xy 6.931601 -449.591981) (xy 6.88582 -449.673933)
			(xy 6.833254 -449.751707) (xy 6.774281 -449.824742) (xy 6.709328 -449.892514) (xy 6.638861 -449.954533)
			(xy 6.563388 -450.010352) (xy 6.483453 -450.05957) (xy 6.399632 -450.101832) (xy 6.312529 -450.136832)
			(xy 6.222772 -450.16432) (xy 6.131007 -450.184097) (xy 6.037895 -450.19602) (xy 5.944108 -450.200005)
			(xy 5.850321 -450.19602) (xy 5.757209 -450.184097) (xy 5.665444 -450.16432) (xy 5.575687 -450.136832)
			(xy 5.488584 -450.101832) (xy 5.404763 -450.05957) (xy 5.324828 -450.010352) (xy 5.249355 -449.954533)
			(xy 5.178888 -449.892514) (xy 5.113935 -449.824742) (xy 5.054962 -449.751707) (xy 5.002396 -449.673933)
			(xy 4.956615 -449.591981) (xy 4.917949 -449.506442) (xy 4.886677 -449.417933) (xy 4.863023 -449.32709)
			(xy 4.847159 -449.234568) (xy 4.839198 -449.141034) (xy 1.27 -449.141034) (xy 1.27 -451.706234) (xy 13.949932 -451.706234)
			(xy 13.954003 -451.650612) (xy 13.966129 -451.596175) (xy 13.986052 -451.544084) (xy 14.013348 -451.495449)
			(xy 14.047434 -451.451306) (xy 14.087583 -451.412597) (xy 14.132941 -451.380146) (xy 14.182541 -451.354645)
			(xy 14.235325 -451.336638) (xy 14.290168 -451.326508) (xy 14.345902 -451.324471) (xy 14.401339 -451.330571)
			(xy 14.455296 -451.344677) (xy 14.506625 -451.366489) (xy 14.554231 -451.395543) (xy 14.597099 -451.431218)
			(xy 14.634316 -451.472755) (xy 14.665089 -451.519268) (xy 14.688761 -451.569765) (xy 14.704829 -451.623172)
			(xy 14.712949 -451.678348) (xy 14.713458 -451.706234) (xy 14.713328 -451.713362) (xy 29.519874 -451.713362)
			(xy 29.519874 -451.626462) (xy 29.527892 -451.539933) (xy 29.54386 -451.454513) (xy 29.567641 -451.370931)
			(xy 29.599033 -451.289899) (xy 29.637767 -451.21211) (xy 29.683514 -451.138226) (xy 29.735883 -451.068879)
			(xy 29.794427 -451.004659) (xy 29.858647 -450.946115) (xy 29.927994 -450.893746) (xy 30.001878 -450.847999)
			(xy 30.079667 -450.809265) (xy 30.160699 -450.777873) (xy 30.244281 -450.754092) (xy 30.329701 -450.738124)
			(xy 30.41623 -450.730106) (xy 30.50313 -450.730106) (xy 30.589659 -450.738124) (xy 30.675079 -450.754092)
			(xy 30.758661 -450.777873) (xy 30.839693 -450.809265) (xy 30.917482 -450.847999) (xy 30.991366 -450.893746)
			(xy 31.060713 -450.946115) (xy 31.124933 -451.004659) (xy 31.183477 -451.068879) (xy 31.235846 -451.138226)
			(xy 31.281593 -451.21211) (xy 31.320327 -451.289899) (xy 31.351719 -451.370931) (xy 31.3755 -451.454513)
			(xy 31.391468 -451.539933) (xy 31.399486 -451.626462) (xy 31.399988 -451.669912) (xy 31.399486 -451.713362)
			(xy 34.599874 -451.713362) (xy 34.599874 -451.626462) (xy 34.607892 -451.539933) (xy 34.62386 -451.454513)
			(xy 34.647641 -451.370931) (xy 34.679033 -451.289899) (xy 34.717767 -451.21211) (xy 34.763514 -451.138226)
			(xy 34.815883 -451.068879) (xy 34.874427 -451.004659) (xy 34.938647 -450.946115) (xy 35.007994 -450.893746)
			(xy 35.081878 -450.847999) (xy 35.159667 -450.809265) (xy 35.240699 -450.777873) (xy 35.324281 -450.754092)
			(xy 35.409701 -450.738124) (xy 35.49623 -450.730106) (xy 35.58313 -450.730106) (xy 35.669659 -450.738124)
			(xy 35.755079 -450.754092) (xy 35.838661 -450.777873) (xy 35.919693 -450.809265) (xy 35.997482 -450.847999)
			(xy 36.071366 -450.893746) (xy 36.140713 -450.946115) (xy 36.204933 -451.004659) (xy 36.263477 -451.068879)
			(xy 36.315846 -451.138226) (xy 36.361593 -451.21211) (xy 36.400327 -451.289899) (xy 36.431719 -451.370931)
			(xy 36.442855 -451.41007) (xy 39.818564 -451.41007) (xy 39.819058 -451.352661) (xy 39.826902 -451.238113)
			(xy 39.842544 -451.124366) (xy 39.865911 -451.011952) (xy 39.896896 -450.901394) (xy 39.935352 -450.793209)
			(xy 39.981101 -450.6879) (xy 40.03393 -450.585958) (xy 40.093592 -450.487859) (xy 40.159809 -450.39406)
			(xy 40.232272 -450.304998) (xy 40.310645 -450.221089) (xy 40.39456 -450.142723) (xy 40.483627 -450.070266)
			(xy 40.577431 -450.004056) (xy 40.675535 -449.944402) (xy 40.777481 -449.891581) (xy 40.882793 -449.845839)
			(xy 40.990981 -449.807391) (xy 41.101541 -449.776415) (xy 41.213957 -449.753056) (xy 41.327705 -449.737423)
			(xy 41.442254 -449.729588) (xy 41.557072 -449.729588) (xy 41.671621 -449.737423) (xy 41.785369 -449.753056)
			(xy 41.897785 -449.776415) (xy 42.008345 -449.807391) (xy 42.116533 -449.845839) (xy 42.221845 -449.891581)
			(xy 42.323791 -449.944402) (xy 42.421895 -450.004056) (xy 42.501239 -450.06006) (xy 43.327577 -450.06006)
			(xy 43.331612 -449.984356) (xy 43.343671 -449.909511) (xy 43.363617 -449.83637) (xy 43.391224 -449.765765)
			(xy 43.42618 -449.698494) (xy 43.468088 -449.635319) (xy 43.516474 -449.576957) (xy 43.57079 -449.524069)
			(xy 43.630419 -449.477254) (xy 43.694687 -449.437042) (xy 43.762864 -449.40389) (xy 43.83418 -449.378172)
			(xy 43.907825 -449.36018) (xy 43.982965 -449.350118) (xy 44.058749 -449.348099) (xy 44.134319 -449.354148)
			(xy 44.208817 -449.368195) (xy 44.2814 -449.390081) (xy 44.351246 -449.419558) (xy 44.417563 -449.456293)
			(xy 44.479599 -449.499868) (xy 44.536652 -449.54979) (xy 44.588076 -449.605494) (xy 44.633287 -449.666349)
			(xy 44.671774 -449.731664) (xy 44.7031 -449.8007) (xy 44.72691 -449.872675) (xy 44.742935 -449.946773)
			(xy 44.750994 -450.022154) (xy 44.751498 -450.06006) (xy 45.867577 -450.06006) (xy 45.871612 -449.984356)
			(xy 45.883671 -449.909511) (xy 45.903617 -449.83637) (xy 45.931224 -449.765765) (xy 45.96618 -449.698494)
			(xy 46.008088 -449.635319) (xy 46.056474 -449.576957) (xy 46.11079 -449.524069) (xy 46.170419 -449.477254)
			(xy 46.234687 -449.437042) (xy 46.302864 -449.40389) (xy 46.37418 -449.378172) (xy 46.447825 -449.36018)
			(xy 46.522965 -449.350118) (xy 46.598749 -449.348099) (xy 46.674319 -449.354148) (xy 46.748817 -449.368195)
			(xy 46.8214 -449.390081) (xy 46.891246 -449.419558) (xy 46.957563 -449.456293) (xy 47.019599 -449.499868)
			(xy 47.076652 -449.54979) (xy 47.128076 -449.605494) (xy 47.173287 -449.666349) (xy 47.211774 -449.731664)
			(xy 47.2431 -449.8007) (xy 47.26691 -449.872675) (xy 47.282935 -449.946773) (xy 47.290994 -450.022154)
			(xy 47.291498 -450.06006) (xy 48.407577 -450.06006) (xy 48.411612 -449.984356) (xy 48.423671 -449.909511)
			(xy 48.443617 -449.83637) (xy 48.471224 -449.765765) (xy 48.50618 -449.698494) (xy 48.548088 -449.635319)
			(xy 48.596474 -449.576957) (xy 48.65079 -449.524069) (xy 48.710419 -449.477254) (xy 48.774687 -449.437042)
			(xy 48.842864 -449.40389) (xy 48.91418 -449.378172) (xy 48.987825 -449.36018) (xy 49.062965 -449.350118)
			(xy 49.138749 -449.348099) (xy 49.214319 -449.354148) (xy 49.288817 -449.368195) (xy 49.3614 -449.390081)
			(xy 49.431246 -449.419558) (xy 49.497563 -449.456293) (xy 49.559599 -449.499868) (xy 49.616652 -449.54979)
			(xy 49.668076 -449.605494) (xy 49.713287 -449.666349) (xy 49.751774 -449.731664) (xy 49.7831 -449.8007)
			(xy 49.80691 -449.872675) (xy 49.822935 -449.946773) (xy 49.830994 -450.022154) (xy 49.831498 -450.06006)
			(xy 50.947577 -450.06006) (xy 50.951612 -449.984356) (xy 50.963671 -449.909511) (xy 50.983617 -449.83637)
			(xy 51.011224 -449.765765) (xy 51.04618 -449.698494) (xy 51.088088 -449.635319) (xy 51.136474 -449.576957)
			(xy 51.19079 -449.524069) (xy 51.250419 -449.477254) (xy 51.314687 -449.437042) (xy 51.382864 -449.40389)
			(xy 51.45418 -449.378172) (xy 51.527825 -449.36018) (xy 51.602965 -449.350118) (xy 51.678749 -449.348099)
			(xy 51.754319 -449.354148) (xy 51.828817 -449.368195) (xy 51.9014 -449.390081) (xy 51.971246 -449.419558)
			(xy 52.037563 -449.456293) (xy 52.099599 -449.499868) (xy 52.156652 -449.54979) (xy 52.208076 -449.605494)
			(xy 52.253287 -449.666349) (xy 52.291774 -449.731664) (xy 52.3231 -449.8007) (xy 52.34691 -449.872675)
			(xy 52.362935 -449.946773) (xy 52.370994 -450.022154) (xy 52.371498 -450.06006) (xy 53.487577 -450.06006)
			(xy 53.491612 -449.984356) (xy 53.503671 -449.909511) (xy 53.523617 -449.83637) (xy 53.551224 -449.765765)
			(xy 53.58618 -449.698494) (xy 53.628088 -449.635319) (xy 53.676474 -449.576957) (xy 53.73079 -449.524069)
			(xy 53.790419 -449.477254) (xy 53.854687 -449.437042) (xy 53.922864 -449.40389) (xy 53.99418 -449.378172)
			(xy 54.067825 -449.36018) (xy 54.142965 -449.350118) (xy 54.218749 -449.348099) (xy 54.294319 -449.354148)
			(xy 54.368817 -449.368195) (xy 54.4414 -449.390081) (xy 54.511246 -449.419558) (xy 54.577563 -449.456293)
			(xy 54.639599 -449.499868) (xy 54.696652 -449.54979) (xy 54.748076 -449.605494) (xy 54.793287 -449.666349)
			(xy 54.831774 -449.731664) (xy 54.8631 -449.8007) (xy 54.88691 -449.872675) (xy 54.902935 -449.946773)
			(xy 54.910994 -450.022154) (xy 54.911498 -450.06006) (xy 56.027577 -450.06006) (xy 56.031612 -449.984356)
			(xy 56.043671 -449.909511) (xy 56.063617 -449.83637) (xy 56.091224 -449.765765) (xy 56.12618 -449.698494)
			(xy 56.168088 -449.635319) (xy 56.216474 -449.576957) (xy 56.27079 -449.524069) (xy 56.330419 -449.477254)
			(xy 56.394687 -449.437042) (xy 56.462864 -449.40389) (xy 56.53418 -449.378172) (xy 56.607825 -449.36018)
			(xy 56.682965 -449.350118) (xy 56.758749 -449.348099) (xy 56.834319 -449.354148) (xy 56.908817 -449.368195)
			(xy 56.9814 -449.390081) (xy 57.051246 -449.419558) (xy 57.117563 -449.456293) (xy 57.179599 -449.499868)
			(xy 57.236652 -449.54979) (xy 57.288076 -449.605494) (xy 57.333287 -449.666349) (xy 57.371774 -449.731664)
			(xy 57.4031 -449.8007) (xy 57.42691 -449.872675) (xy 57.442935 -449.946773) (xy 57.450994 -450.022154)
			(xy 57.451498 -450.06006) (xy 58.567577 -450.06006) (xy 58.571612 -449.984356) (xy 58.583671 -449.909511)
			(xy 58.603617 -449.83637) (xy 58.631224 -449.765765) (xy 58.66618 -449.698494) (xy 58.708088 -449.635319)
			(xy 58.756474 -449.576957) (xy 58.81079 -449.524069) (xy 58.870419 -449.477254) (xy 58.934687 -449.437042)
			(xy 59.002864 -449.40389) (xy 59.07418 -449.378172) (xy 59.147825 -449.36018) (xy 59.222965 -449.350118)
			(xy 59.298749 -449.348099) (xy 59.374319 -449.354148) (xy 59.448817 -449.368195) (xy 59.5214 -449.390081)
			(xy 59.591246 -449.419558) (xy 59.657563 -449.456293) (xy 59.719599 -449.499868) (xy 59.776652 -449.54979)
			(xy 59.828076 -449.605494) (xy 59.873287 -449.666349) (xy 59.911774 -449.731664) (xy 59.9431 -449.8007)
			(xy 59.96691 -449.872675) (xy 59.982935 -449.946773) (xy 59.990994 -450.022154) (xy 59.991498 -450.06006)
			(xy 61.107577 -450.06006) (xy 61.111612 -449.984356) (xy 61.123671 -449.909511) (xy 61.143617 -449.83637)
			(xy 61.171224 -449.765765) (xy 61.20618 -449.698494) (xy 61.248088 -449.635319) (xy 61.296474 -449.576957)
			(xy 61.35079 -449.524069) (xy 61.410419 -449.477254) (xy 61.474687 -449.437042) (xy 61.542864 -449.40389)
			(xy 61.61418 -449.378172) (xy 61.687825 -449.36018) (xy 61.762965 -449.350118) (xy 61.838749 -449.348099)
			(xy 61.914319 -449.354148) (xy 61.988817 -449.368195) (xy 62.0614 -449.390081) (xy 62.131246 -449.419558)
			(xy 62.197563 -449.456293) (xy 62.259599 -449.499868) (xy 62.316652 -449.54979) (xy 62.368076 -449.605494)
			(xy 62.413287 -449.666349) (xy 62.451774 -449.731664) (xy 62.4831 -449.8007) (xy 62.50691 -449.872675)
			(xy 62.522935 -449.946773) (xy 62.530994 -450.022154) (xy 62.531498 -450.06006) (xy 62.530994 -450.097966)
			(xy 62.522935 -450.173347) (xy 62.50691 -450.247445) (xy 62.4831 -450.31942) (xy 62.451774 -450.388456)
			(xy 62.413287 -450.453771) (xy 62.368076 -450.514626) (xy 62.316652 -450.57033) (xy 62.259599 -450.620252)
			(xy 62.197563 -450.663827) (xy 62.131246 -450.700562) (xy 62.0614 -450.730039) (xy 61.988817 -450.751925)
			(xy 61.914319 -450.765972) (xy 61.838749 -450.772021) (xy 61.762965 -450.770002) (xy 61.687825 -450.75994)
			(xy 61.61418 -450.741948) (xy 61.542864 -450.71623) (xy 61.474687 -450.683078) (xy 61.410419 -450.642866)
			(xy 61.35079 -450.596051) (xy 61.296474 -450.543163) (xy 61.248088 -450.484801) (xy 61.20618 -450.421626)
			(xy 61.171224 -450.354355) (xy 61.143617 -450.28375) (xy 61.123671 -450.210609) (xy 61.111612 -450.135764)
			(xy 61.107577 -450.06006) (xy 59.991498 -450.06006) (xy 59.990994 -450.097966) (xy 59.982935 -450.173347)
			(xy 59.96691 -450.247445) (xy 59.9431 -450.31942) (xy 59.911774 -450.388456) (xy 59.873287 -450.453771)
			(xy 59.828076 -450.514626) (xy 59.776652 -450.57033) (xy 59.719599 -450.620252) (xy 59.657563 -450.663827)
			(xy 59.591246 -450.700562) (xy 59.5214 -450.730039) (xy 59.448817 -450.751925) (xy 59.374319 -450.765972)
			(xy 59.298749 -450.772021) (xy 59.222965 -450.770002) (xy 59.147825 -450.75994) (xy 59.07418 -450.741948)
			(xy 59.002864 -450.71623) (xy 58.934687 -450.683078) (xy 58.870419 -450.642866) (xy 58.81079 -450.596051)
			(xy 58.756474 -450.543163) (xy 58.708088 -450.484801) (xy 58.66618 -450.421626) (xy 58.631224 -450.354355)
			(xy 58.603617 -450.28375) (xy 58.583671 -450.210609) (xy 58.571612 -450.135764) (xy 58.567577 -450.06006)
			(xy 57.451498 -450.06006) (xy 57.450994 -450.097966) (xy 57.442935 -450.173347) (xy 57.42691 -450.247445)
			(xy 57.4031 -450.31942) (xy 57.371774 -450.388456) (xy 57.333287 -450.453771) (xy 57.288076 -450.514626)
			(xy 57.236652 -450.57033) (xy 57.179599 -450.620252) (xy 57.117563 -450.663827) (xy 57.051246 -450.700562)
			(xy 56.9814 -450.730039) (xy 56.908817 -450.751925) (xy 56.834319 -450.765972) (xy 56.758749 -450.772021)
			(xy 56.682965 -450.770002) (xy 56.607825 -450.75994) (xy 56.53418 -450.741948) (xy 56.462864 -450.71623)
			(xy 56.394687 -450.683078) (xy 56.330419 -450.642866) (xy 56.27079 -450.596051) (xy 56.216474 -450.543163)
			(xy 56.168088 -450.484801) (xy 56.12618 -450.421626) (xy 56.091224 -450.354355) (xy 56.063617 -450.28375)
			(xy 56.043671 -450.210609) (xy 56.031612 -450.135764) (xy 56.027577 -450.06006) (xy 54.911498 -450.06006)
			(xy 54.910994 -450.097966) (xy 54.902935 -450.173347) (xy 54.88691 -450.247445) (xy 54.8631 -450.31942)
			(xy 54.831774 -450.388456) (xy 54.793287 -450.453771) (xy 54.748076 -450.514626) (xy 54.696652 -450.57033)
			(xy 54.639599 -450.620252) (xy 54.577563 -450.663827) (xy 54.511246 -450.700562) (xy 54.4414 -450.730039)
			(xy 54.368817 -450.751925) (xy 54.294319 -450.765972) (xy 54.218749 -450.772021) (xy 54.142965 -450.770002)
			(xy 54.067825 -450.75994) (xy 53.99418 -450.741948) (xy 53.922864 -450.71623) (xy 53.854687 -450.683078)
			(xy 53.790419 -450.642866) (xy 53.73079 -450.596051) (xy 53.676474 -450.543163) (xy 53.628088 -450.484801)
			(xy 53.58618 -450.421626) (xy 53.551224 -450.354355) (xy 53.523617 -450.28375) (xy 53.503671 -450.210609)
			(xy 53.491612 -450.135764) (xy 53.487577 -450.06006) (xy 52.371498 -450.06006) (xy 52.370994 -450.097966)
			(xy 52.362935 -450.173347) (xy 52.34691 -450.247445) (xy 52.3231 -450.31942) (xy 52.291774 -450.388456)
			(xy 52.253287 -450.453771) (xy 52.208076 -450.514626) (xy 52.156652 -450.57033) (xy 52.099599 -450.620252)
			(xy 52.037563 -450.663827) (xy 51.971246 -450.700562) (xy 51.9014 -450.730039) (xy 51.828817 -450.751925)
			(xy 51.754319 -450.765972) (xy 51.678749 -450.772021) (xy 51.602965 -450.770002) (xy 51.527825 -450.75994)
			(xy 51.45418 -450.741948) (xy 51.382864 -450.71623) (xy 51.314687 -450.683078) (xy 51.250419 -450.642866)
			(xy 51.19079 -450.596051) (xy 51.136474 -450.543163) (xy 51.088088 -450.484801) (xy 51.04618 -450.421626)
			(xy 51.011224 -450.354355) (xy 50.983617 -450.28375) (xy 50.963671 -450.210609) (xy 50.951612 -450.135764)
			(xy 50.947577 -450.06006) (xy 49.831498 -450.06006) (xy 49.830994 -450.097966) (xy 49.822935 -450.173347)
			(xy 49.80691 -450.247445) (xy 49.7831 -450.31942) (xy 49.751774 -450.388456) (xy 49.713287 -450.453771)
			(xy 49.668076 -450.514626) (xy 49.616652 -450.57033) (xy 49.559599 -450.620252) (xy 49.497563 -450.663827)
			(xy 49.431246 -450.700562) (xy 49.3614 -450.730039) (xy 49.288817 -450.751925) (xy 49.214319 -450.765972)
			(xy 49.138749 -450.772021) (xy 49.062965 -450.770002) (xy 48.987825 -450.75994) (xy 48.91418 -450.741948)
			(xy 48.842864 -450.71623) (xy 48.774687 -450.683078) (xy 48.710419 -450.642866) (xy 48.65079 -450.596051)
			(xy 48.596474 -450.543163) (xy 48.548088 -450.484801) (xy 48.50618 -450.421626) (xy 48.471224 -450.354355)
			(xy 48.443617 -450.28375) (xy 48.423671 -450.210609) (xy 48.411612 -450.135764) (xy 48.407577 -450.06006)
			(xy 47.291498 -450.06006) (xy 47.290994 -450.097966) (xy 47.282935 -450.173347) (xy 47.26691 -450.247445)
			(xy 47.2431 -450.31942) (xy 47.211774 -450.388456) (xy 47.173287 -450.453771) (xy 47.128076 -450.514626)
			(xy 47.076652 -450.57033) (xy 47.019599 -450.620252) (xy 46.957563 -450.663827) (xy 46.891246 -450.700562)
			(xy 46.8214 -450.730039) (xy 46.748817 -450.751925) (xy 46.674319 -450.765972) (xy 46.598749 -450.772021)
			(xy 46.522965 -450.770002) (xy 46.447825 -450.75994) (xy 46.37418 -450.741948) (xy 46.302864 -450.71623)
			(xy 46.234687 -450.683078) (xy 46.170419 -450.642866) (xy 46.11079 -450.596051) (xy 46.056474 -450.543163)
			(xy 46.008088 -450.484801) (xy 45.96618 -450.421626) (xy 45.931224 -450.354355) (xy 45.903617 -450.28375)
			(xy 45.883671 -450.210609) (xy 45.871612 -450.135764) (xy 45.867577 -450.06006) (xy 44.751498 -450.06006)
			(xy 44.750994 -450.097966) (xy 44.742935 -450.173347) (xy 44.72691 -450.247445) (xy 44.7031 -450.31942)
			(xy 44.671774 -450.388456) (xy 44.633287 -450.453771) (xy 44.588076 -450.514626) (xy 44.536652 -450.57033)
			(xy 44.479599 -450.620252) (xy 44.417563 -450.663827) (xy 44.351246 -450.700562) (xy 44.2814 -450.730039)
			(xy 44.208817 -450.751925) (xy 44.134319 -450.765972) (xy 44.058749 -450.772021) (xy 43.982965 -450.770002)
			(xy 43.907825 -450.75994) (xy 43.83418 -450.741948) (xy 43.762864 -450.71623) (xy 43.694687 -450.683078)
			(xy 43.630419 -450.642866) (xy 43.57079 -450.596051) (xy 43.516474 -450.543163) (xy 43.468088 -450.484801)
			(xy 43.42618 -450.421626) (xy 43.391224 -450.354355) (xy 43.363617 -450.28375) (xy 43.343671 -450.210609)
			(xy 43.331612 -450.135764) (xy 43.327577 -450.06006) (xy 42.501239 -450.06006) (xy 42.515699 -450.070266)
			(xy 42.604766 -450.142723) (xy 42.688681 -450.221089) (xy 42.767054 -450.304998) (xy 42.839517 -450.39406)
			(xy 42.905734 -450.487859) (xy 42.965396 -450.585958) (xy 43.018225 -450.6879) (xy 43.063974 -450.793209)
			(xy 43.10243 -450.901394) (xy 43.133415 -451.011952) (xy 43.156782 -451.124366) (xy 43.172424 -451.238113)
			(xy 43.180268 -451.352661) (xy 43.180762 -451.41007) (xy 43.180576 -451.443253) (xy 43.177909 -451.509567)
			(xy 43.175428 -451.542658) (xy 43.170272 -451.600942) (xy 43.152948 -451.716671) (xy 43.127616 -451.830914)
			(xy 43.094401 -451.943119) (xy 43.053462 -452.052742) (xy 43.004999 -452.159253) (xy 42.949245 -452.262135)
			(xy 42.886471 -452.360891) (xy 42.816981 -452.455042) (xy 42.741111 -452.544132) (xy 42.659229 -452.627729)
			(xy 42.571732 -452.70543) (xy 42.500813 -452.76008) (xy 43.327577 -452.76008) (xy 43.331612 -452.684376)
			(xy 43.343671 -452.609531) (xy 43.363617 -452.53639) (xy 43.391224 -452.465785) (xy 43.42618 -452.398514)
			(xy 43.468088 -452.335339) (xy 43.516474 -452.276977) (xy 43.57079 -452.224089) (xy 43.630419 -452.177274)
			(xy 43.694687 -452.137062) (xy 43.762864 -452.10391) (xy 43.83418 -452.078192) (xy 43.907825 -452.0602)
			(xy 43.982965 -452.050138) (xy 44.058749 -452.048119) (xy 44.134319 -452.054168) (xy 44.208817 -452.068215)
			(xy 44.2814 -452.090101) (xy 44.351246 -452.119578) (xy 44.417563 -452.156313) (xy 44.479599 -452.199888)
			(xy 44.536652 -452.24981) (xy 44.588076 -452.305514) (xy 44.633287 -452.366369) (xy 44.671774 -452.431684)
			(xy 44.7031 -452.50072) (xy 44.72691 -452.572695) (xy 44.742935 -452.646793) (xy 44.750994 -452.722174)
			(xy 44.751498 -452.76008) (xy 45.867577 -452.76008) (xy 45.871612 -452.684376) (xy 45.883671 -452.609531)
			(xy 45.903617 -452.53639) (xy 45.931224 -452.465785) (xy 45.96618 -452.398514) (xy 46.008088 -452.335339)
			(xy 46.056474 -452.276977) (xy 46.11079 -452.224089) (xy 46.170419 -452.177274) (xy 46.234687 -452.137062)
			(xy 46.302864 -452.10391) (xy 46.37418 -452.078192) (xy 46.447825 -452.0602) (xy 46.522965 -452.050138)
			(xy 46.598749 -452.048119) (xy 46.674319 -452.054168) (xy 46.748817 -452.068215) (xy 46.8214 -452.090101)
			(xy 46.891246 -452.119578) (xy 46.957563 -452.156313) (xy 47.019599 -452.199888) (xy 47.076652 -452.24981)
			(xy 47.128076 -452.305514) (xy 47.173287 -452.366369) (xy 47.211774 -452.431684) (xy 47.2431 -452.50072)
			(xy 47.26691 -452.572695) (xy 47.282935 -452.646793) (xy 47.290994 -452.722174) (xy 47.291498 -452.76008)
			(xy 48.407577 -452.76008) (xy 48.411612 -452.684376) (xy 48.423671 -452.609531) (xy 48.443617 -452.53639)
			(xy 48.471224 -452.465785) (xy 48.50618 -452.398514) (xy 48.548088 -452.335339) (xy 48.596474 -452.276977)
			(xy 48.65079 -452.224089) (xy 48.710419 -452.177274) (xy 48.774687 -452.137062) (xy 48.842864 -452.10391)
			(xy 48.91418 -452.078192) (xy 48.987825 -452.0602) (xy 49.062965 -452.050138) (xy 49.138749 -452.048119)
			(xy 49.214319 -452.054168) (xy 49.288817 -452.068215) (xy 49.3614 -452.090101) (xy 49.431246 -452.119578)
			(xy 49.497563 -452.156313) (xy 49.559599 -452.199888) (xy 49.616652 -452.24981) (xy 49.668076 -452.305514)
			(xy 49.713287 -452.366369) (xy 49.751774 -452.431684) (xy 49.7831 -452.50072) (xy 49.80691 -452.572695)
			(xy 49.822935 -452.646793) (xy 49.830994 -452.722174) (xy 49.831498 -452.76008) (xy 50.947577 -452.76008)
			(xy 50.951612 -452.684376) (xy 50.963671 -452.609531) (xy 50.983617 -452.53639) (xy 51.011224 -452.465785)
			(xy 51.04618 -452.398514) (xy 51.088088 -452.335339) (xy 51.136474 -452.276977) (xy 51.19079 -452.224089)
			(xy 51.250419 -452.177274) (xy 51.314687 -452.137062) (xy 51.382864 -452.10391) (xy 51.45418 -452.078192)
			(xy 51.527825 -452.0602) (xy 51.602965 -452.050138) (xy 51.678749 -452.048119) (xy 51.754319 -452.054168)
			(xy 51.828817 -452.068215) (xy 51.9014 -452.090101) (xy 51.971246 -452.119578) (xy 52.037563 -452.156313)
			(xy 52.099599 -452.199888) (xy 52.156652 -452.24981) (xy 52.208076 -452.305514) (xy 52.253287 -452.366369)
			(xy 52.291774 -452.431684) (xy 52.3231 -452.50072) (xy 52.34691 -452.572695) (xy 52.362935 -452.646793)
			(xy 52.370994 -452.722174) (xy 52.371498 -452.76008) (xy 53.487577 -452.76008) (xy 53.491612 -452.684376)
			(xy 53.503671 -452.609531) (xy 53.523617 -452.53639) (xy 53.551224 -452.465785) (xy 53.58618 -452.398514)
			(xy 53.628088 -452.335339) (xy 53.676474 -452.276977) (xy 53.73079 -452.224089) (xy 53.790419 -452.177274)
			(xy 53.854687 -452.137062) (xy 53.922864 -452.10391) (xy 53.99418 -452.078192) (xy 54.067825 -452.0602)
			(xy 54.142965 -452.050138) (xy 54.218749 -452.048119) (xy 54.294319 -452.054168) (xy 54.368817 -452.068215)
			(xy 54.4414 -452.090101) (xy 54.511246 -452.119578) (xy 54.577563 -452.156313) (xy 54.639599 -452.199888)
			(xy 54.696652 -452.24981) (xy 54.748076 -452.305514) (xy 54.793287 -452.366369) (xy 54.831774 -452.431684)
			(xy 54.8631 -452.50072) (xy 54.88691 -452.572695) (xy 54.902935 -452.646793) (xy 54.910994 -452.722174)
			(xy 54.911498 -452.76008) (xy 56.027577 -452.76008) (xy 56.031612 -452.684376) (xy 56.043671 -452.609531)
			(xy 56.063617 -452.53639) (xy 56.091224 -452.465785) (xy 56.12618 -452.398514) (xy 56.168088 -452.335339)
			(xy 56.216474 -452.276977) (xy 56.27079 -452.224089) (xy 56.330419 -452.177274) (xy 56.394687 -452.137062)
			(xy 56.462864 -452.10391) (xy 56.53418 -452.078192) (xy 56.607825 -452.0602) (xy 56.682965 -452.050138)
			(xy 56.758749 -452.048119) (xy 56.834319 -452.054168) (xy 56.908817 -452.068215) (xy 56.9814 -452.090101)
			(xy 57.051246 -452.119578) (xy 57.117563 -452.156313) (xy 57.179599 -452.199888) (xy 57.236652 -452.24981)
			(xy 57.288076 -452.305514) (xy 57.333287 -452.366369) (xy 57.371774 -452.431684) (xy 57.4031 -452.50072)
			(xy 57.42691 -452.572695) (xy 57.442935 -452.646793) (xy 57.450994 -452.722174) (xy 57.451498 -452.76008)
			(xy 58.567577 -452.76008) (xy 58.571612 -452.684376) (xy 58.583671 -452.609531) (xy 58.603617 -452.53639)
			(xy 58.631224 -452.465785) (xy 58.66618 -452.398514) (xy 58.708088 -452.335339) (xy 58.756474 -452.276977)
			(xy 58.81079 -452.224089) (xy 58.870419 -452.177274) (xy 58.934687 -452.137062) (xy 59.002864 -452.10391)
			(xy 59.07418 -452.078192) (xy 59.147825 -452.0602) (xy 59.222965 -452.050138) (xy 59.298749 -452.048119)
			(xy 59.374319 -452.054168) (xy 59.448817 -452.068215) (xy 59.5214 -452.090101) (xy 59.591246 -452.119578)
			(xy 59.657563 -452.156313) (xy 59.719599 -452.199888) (xy 59.776652 -452.24981) (xy 59.828076 -452.305514)
			(xy 59.873287 -452.366369) (xy 59.911774 -452.431684) (xy 59.9431 -452.50072) (xy 59.96691 -452.572695)
			(xy 59.982935 -452.646793) (xy 59.990994 -452.722174) (xy 59.991498 -452.76008) (xy 61.107577 -452.76008)
			(xy 61.111612 -452.684376) (xy 61.123671 -452.609531) (xy 61.143617 -452.53639) (xy 61.171224 -452.465785)
			(xy 61.20618 -452.398514) (xy 61.248088 -452.335339) (xy 61.296474 -452.276977) (xy 61.35079 -452.224089)
			(xy 61.410419 -452.177274) (xy 61.474687 -452.137062) (xy 61.542864 -452.10391) (xy 61.61418 -452.078192)
			(xy 61.687825 -452.0602) (xy 61.762965 -452.050138) (xy 61.838749 -452.048119) (xy 61.914319 -452.054168)
			(xy 61.988817 -452.068215) (xy 62.0614 -452.090101) (xy 62.131246 -452.119578) (xy 62.197563 -452.156313)
			(xy 62.259599 -452.199888) (xy 62.316652 -452.24981) (xy 62.368076 -452.305514) (xy 62.413287 -452.366369)
			(xy 62.451774 -452.431684) (xy 62.4831 -452.50072) (xy 62.50691 -452.572695) (xy 62.522935 -452.646793)
			(xy 62.530994 -452.722174) (xy 62.531498 -452.76008) (xy 62.530994 -452.797986) (xy 62.522935 -452.873367)
			(xy 62.50691 -452.947465) (xy 62.4831 -453.01944) (xy 62.451774 -453.088476) (xy 62.413287 -453.153791)
			(xy 62.368076 -453.214646) (xy 62.316652 -453.27035) (xy 62.259599 -453.320272) (xy 62.197563 -453.363847)
			(xy 62.131246 -453.400582) (xy 62.0614 -453.430059) (xy 61.988817 -453.451945) (xy 61.914319 -453.465992)
			(xy 61.838749 -453.472041) (xy 61.762965 -453.470022) (xy 61.687825 -453.45996) (xy 61.61418 -453.441968)
			(xy 61.542864 -453.41625) (xy 61.474687 -453.383098) (xy 61.410419 -453.342886) (xy 61.35079 -453.296071)
			(xy 61.296474 -453.243183) (xy 61.248088 -453.184821) (xy 61.20618 -453.121646) (xy 61.171224 -453.054375)
			(xy 61.143617 -452.98377) (xy 61.123671 -452.910629) (xy 61.111612 -452.835784) (xy 61.107577 -452.76008)
			(xy 59.991498 -452.76008) (xy 59.990994 -452.797986) (xy 59.982935 -452.873367) (xy 59.96691 -452.947465)
			(xy 59.9431 -453.01944) (xy 59.911774 -453.088476) (xy 59.873287 -453.153791) (xy 59.828076 -453.214646)
			(xy 59.776652 -453.27035) (xy 59.719599 -453.320272) (xy 59.657563 -453.363847) (xy 59.591246 -453.400582)
			(xy 59.5214 -453.430059) (xy 59.448817 -453.451945) (xy 59.374319 -453.465992) (xy 59.298749 -453.472041)
			(xy 59.222965 -453.470022) (xy 59.147825 -453.45996) (xy 59.07418 -453.441968) (xy 59.002864 -453.41625)
			(xy 58.934687 -453.383098) (xy 58.870419 -453.342886) (xy 58.81079 -453.296071) (xy 58.756474 -453.243183)
			(xy 58.708088 -453.184821) (xy 58.66618 -453.121646) (xy 58.631224 -453.054375) (xy 58.603617 -452.98377)
			(xy 58.583671 -452.910629) (xy 58.571612 -452.835784) (xy 58.567577 -452.76008) (xy 57.451498 -452.76008)
			(xy 57.450994 -452.797986) (xy 57.442935 -452.873367) (xy 57.42691 -452.947465) (xy 57.4031 -453.01944)
			(xy 57.371774 -453.088476) (xy 57.333287 -453.153791) (xy 57.288076 -453.214646) (xy 57.236652 -453.27035)
			(xy 57.179599 -453.320272) (xy 57.117563 -453.363847) (xy 57.051246 -453.400582) (xy 56.9814 -453.430059)
			(xy 56.908817 -453.451945) (xy 56.834319 -453.465992) (xy 56.758749 -453.472041) (xy 56.682965 -453.470022)
			(xy 56.607825 -453.45996) (xy 56.53418 -453.441968) (xy 56.462864 -453.41625) (xy 56.394687 -453.383098)
			(xy 56.330419 -453.342886) (xy 56.27079 -453.296071) (xy 56.216474 -453.243183) (xy 56.168088 -453.184821)
			(xy 56.12618 -453.121646) (xy 56.091224 -453.054375) (xy 56.063617 -452.98377) (xy 56.043671 -452.910629)
			(xy 56.031612 -452.835784) (xy 56.027577 -452.76008) (xy 54.911498 -452.76008) (xy 54.910994 -452.797986)
			(xy 54.902935 -452.873367) (xy 54.88691 -452.947465) (xy 54.8631 -453.01944) (xy 54.831774 -453.088476)
			(xy 54.793287 -453.153791) (xy 54.748076 -453.214646) (xy 54.696652 -453.27035) (xy 54.639599 -453.320272)
			(xy 54.577563 -453.363847) (xy 54.511246 -453.400582) (xy 54.4414 -453.430059) (xy 54.368817 -453.451945)
			(xy 54.294319 -453.465992) (xy 54.218749 -453.472041) (xy 54.142965 -453.470022) (xy 54.067825 -453.45996)
			(xy 53.99418 -453.441968) (xy 53.922864 -453.41625) (xy 53.854687 -453.383098) (xy 53.790419 -453.342886)
			(xy 53.73079 -453.296071) (xy 53.676474 -453.243183) (xy 53.628088 -453.184821) (xy 53.58618 -453.121646)
			(xy 53.551224 -453.054375) (xy 53.523617 -452.98377) (xy 53.503671 -452.910629) (xy 53.491612 -452.835784)
			(xy 53.487577 -452.76008) (xy 52.371498 -452.76008) (xy 52.370994 -452.797986) (xy 52.362935 -452.873367)
			(xy 52.34691 -452.947465) (xy 52.3231 -453.01944) (xy 52.291774 -453.088476) (xy 52.253287 -453.153791)
			(xy 52.208076 -453.214646) (xy 52.156652 -453.27035) (xy 52.099599 -453.320272) (xy 52.037563 -453.363847)
			(xy 51.971246 -453.400582) (xy 51.9014 -453.430059) (xy 51.828817 -453.451945) (xy 51.754319 -453.465992)
			(xy 51.678749 -453.472041) (xy 51.602965 -453.470022) (xy 51.527825 -453.45996) (xy 51.45418 -453.441968)
			(xy 51.382864 -453.41625) (xy 51.314687 -453.383098) (xy 51.250419 -453.342886) (xy 51.19079 -453.296071)
			(xy 51.136474 -453.243183) (xy 51.088088 -453.184821) (xy 51.04618 -453.121646) (xy 51.011224 -453.054375)
			(xy 50.983617 -452.98377) (xy 50.963671 -452.910629) (xy 50.951612 -452.835784) (xy 50.947577 -452.76008)
			(xy 49.831498 -452.76008) (xy 49.830994 -452.797986) (xy 49.822935 -452.873367) (xy 49.80691 -452.947465)
			(xy 49.7831 -453.01944) (xy 49.751774 -453.088476) (xy 49.713287 -453.153791) (xy 49.668076 -453.214646)
			(xy 49.616652 -453.27035) (xy 49.559599 -453.320272) (xy 49.497563 -453.363847) (xy 49.431246 -453.400582)
			(xy 49.3614 -453.430059) (xy 49.288817 -453.451945) (xy 49.214319 -453.465992) (xy 49.138749 -453.472041)
			(xy 49.062965 -453.470022) (xy 48.987825 -453.45996) (xy 48.91418 -453.441968) (xy 48.842864 -453.41625)
			(xy 48.774687 -453.383098) (xy 48.710419 -453.342886) (xy 48.65079 -453.296071) (xy 48.596474 -453.243183)
			(xy 48.548088 -453.184821) (xy 48.50618 -453.121646) (xy 48.471224 -453.054375) (xy 48.443617 -452.98377)
			(xy 48.423671 -452.910629) (xy 48.411612 -452.835784) (xy 48.407577 -452.76008) (xy 47.291498 -452.76008)
			(xy 47.290994 -452.797986) (xy 47.282935 -452.873367) (xy 47.26691 -452.947465) (xy 47.2431 -453.01944)
			(xy 47.211774 -453.088476) (xy 47.173287 -453.153791) (xy 47.128076 -453.214646) (xy 47.076652 -453.27035)
			(xy 47.019599 -453.320272) (xy 46.957563 -453.363847) (xy 46.891246 -453.400582) (xy 46.8214 -453.430059)
			(xy 46.748817 -453.451945) (xy 46.674319 -453.465992) (xy 46.598749 -453.472041) (xy 46.522965 -453.470022)
			(xy 46.447825 -453.45996) (xy 46.37418 -453.441968) (xy 46.302864 -453.41625) (xy 46.234687 -453.383098)
			(xy 46.170419 -453.342886) (xy 46.11079 -453.296071) (xy 46.056474 -453.243183) (xy 46.008088 -453.184821)
			(xy 45.96618 -453.121646) (xy 45.931224 -453.054375) (xy 45.903617 -452.98377) (xy 45.883671 -452.910629)
			(xy 45.871612 -452.835784) (xy 45.867577 -452.76008) (xy 44.751498 -452.76008) (xy 44.750994 -452.797986)
			(xy 44.742935 -452.873367) (xy 44.72691 -452.947465) (xy 44.7031 -453.01944) (xy 44.671774 -453.088476)
			(xy 44.633287 -453.153791) (xy 44.588076 -453.214646) (xy 44.536652 -453.27035) (xy 44.479599 -453.320272)
			(xy 44.417563 -453.363847) (xy 44.351246 -453.400582) (xy 44.2814 -453.430059) (xy 44.208817 -453.451945)
			(xy 44.134319 -453.465992) (xy 44.058749 -453.472041) (xy 43.982965 -453.470022) (xy 43.907825 -453.45996)
			(xy 43.83418 -453.441968) (xy 43.762864 -453.41625) (xy 43.694687 -453.383098) (xy 43.630419 -453.342886)
			(xy 43.57079 -453.296071) (xy 43.516474 -453.243183) (xy 43.468088 -453.184821) (xy 43.42618 -453.121646)
			(xy 43.391224 -453.054375) (xy 43.363617 -452.98377) (xy 43.343671 -452.910629) (xy 43.331612 -452.835784)
			(xy 43.327577 -452.76008) (xy 42.500813 -452.76008) (xy 42.479042 -452.776857) (xy 42.381609 -452.841665)
			(xy 42.279905 -452.89954) (xy 42.174422 -452.950202) (xy 42.065671 -452.993404) (xy 41.954179 -453.028939)
			(xy 41.840485 -453.056634) (xy 41.725141 -453.076354) (xy 41.608704 -453.088005) (xy 41.491739 -453.09153)
			(xy 41.374812 -453.086912) (xy 41.258489 -453.074173) (xy 41.143334 -453.053375) (xy 41.029905 -453.024618)
			(xy 40.91875 -452.988042) (xy 40.810407 -452.943825) (xy 40.705403 -452.892179) (xy 40.604244 -452.833356)
			(xy 40.507421 -452.76764) (xy 40.415403 -452.695349) (xy 40.328636 -452.616834) (xy 40.247539 -452.532474)
			(xy 40.172506 -452.442679) (xy 40.103899 -452.347883) (xy 40.042051 -452.248544) (xy 39.987262 -452.145145)
			(xy 39.939796 -452.038186) (xy 39.899884 -451.928185) (xy 39.86772 -451.815674) (xy 39.843457 -451.701199)
			(xy 39.827215 -451.585313) (xy 39.819072 -451.468579) (xy 39.818564 -451.41007) (xy 36.442855 -451.41007)
			(xy 36.4555 -451.454513) (xy 36.471468 -451.539933) (xy 36.479486 -451.626462) (xy 36.479988 -451.669912)
			(xy 36.479486 -451.713362) (xy 36.471468 -451.799891) (xy 36.4555 -451.885311) (xy 36.431719 -451.968893)
			(xy 36.400327 -452.049925) (xy 36.361593 -452.127714) (xy 36.315846 -452.201598) (xy 36.263477 -452.270945)
			(xy 36.204933 -452.335165) (xy 36.140713 -452.393709) (xy 36.071366 -452.446078) (xy 35.997482 -452.491825)
			(xy 35.919693 -452.530559) (xy 35.838661 -452.561951) (xy 35.755079 -452.585732) (xy 35.669659 -452.6017)
			(xy 35.58313 -452.609718) (xy 35.49623 -452.609718) (xy 35.409701 -452.6017) (xy 35.324281 -452.585732)
			(xy 35.240699 -452.561951) (xy 35.159667 -452.530559) (xy 35.081878 -452.491825) (xy 35.007994 -452.446078)
			(xy 34.938647 -452.393709) (xy 34.874427 -452.335165) (xy 34.815883 -452.270945) (xy 34.763514 -452.201598)
			(xy 34.717767 -452.127714) (xy 34.679033 -452.049925) (xy 34.647641 -451.968893) (xy 34.62386 -451.885311)
			(xy 34.607892 -451.799891) (xy 34.599874 -451.713362) (xy 31.399486 -451.713362) (xy 31.391468 -451.799891)
			(xy 31.3755 -451.885311) (xy 31.351719 -451.968893) (xy 31.320327 -452.049925) (xy 31.281593 -452.127714)
			(xy 31.235846 -452.201598) (xy 31.183477 -452.270945) (xy 31.124933 -452.335165) (xy 31.060713 -452.393709)
			(xy 30.991366 -452.446078) (xy 30.917482 -452.491825) (xy 30.839693 -452.530559) (xy 30.758661 -452.561951)
			(xy 30.675079 -452.585732) (xy 30.589659 -452.6017) (xy 30.50313 -452.609718) (xy 30.41623 -452.609718)
			(xy 30.329701 -452.6017) (xy 30.244281 -452.585732) (xy 30.160699 -452.561951) (xy 30.079667 -452.530559)
			(xy 30.001878 -452.491825) (xy 29.927994 -452.446078) (xy 29.858647 -452.393709) (xy 29.794427 -452.335165)
			(xy 29.735883 -452.270945) (xy 29.683514 -452.201598) (xy 29.637767 -452.127714) (xy 29.599033 -452.049925)
			(xy 29.567641 -451.968893) (xy 29.54386 -451.885311) (xy 29.527892 -451.799891) (xy 29.519874 -451.713362)
			(xy 14.713328 -451.713362) (xy 14.712949 -451.73412) (xy 14.704829 -451.789296) (xy 14.688761 -451.842703)
			(xy 14.665089 -451.8932) (xy 14.634316 -451.939713) (xy 14.597099 -451.98125) (xy 14.554231 -452.016925)
			(xy 14.506625 -452.045979) (xy 14.455296 -452.067791) (xy 14.401339 -452.081897) (xy 14.345902 -452.087997)
			(xy 14.290168 -452.08596) (xy 14.235325 -452.07583) (xy 14.182541 -452.057823) (xy 14.132941 -452.032322)
			(xy 14.087583 -451.999871) (xy 14.047434 -451.961162) (xy 14.013348 -451.917019) (xy 13.986052 -451.868384)
			(xy 13.966129 -451.816293) (xy 13.954003 -451.761856) (xy 13.949932 -451.706234) (xy 1.27 -451.706234)
			(xy 1.27 -453.340924) (xy 4.839198 -453.340924) (xy 4.839198 -453.247052) (xy 4.847159 -453.153518)
			(xy 4.863023 -453.060996) (xy 4.886677 -452.970153) (xy 4.917949 -452.881644) (xy 4.956615 -452.796105)
			(xy 5.002396 -452.714153) (xy 5.054962 -452.636379) (xy 5.113935 -452.563344) (xy 5.178888 -452.495572)
			(xy 5.249355 -452.433553) (xy 5.324828 -452.377734) (xy 5.404763 -452.328516) (xy 5.488584 -452.286254)
			(xy 5.575687 -452.251254) (xy 5.665444 -452.223766) (xy 5.757209 -452.203989) (xy 5.850321 -452.192066)
			(xy 5.944108 -452.188082) (xy 6.037895 -452.192066) (xy 6.131007 -452.203989) (xy 6.222772 -452.223766)
			(xy 6.312529 -452.251254) (xy 6.328491 -452.257668) (xy 24.731724 -452.257668) (xy 24.735795 -452.202046)
			(xy 24.747921 -452.147609) (xy 24.767844 -452.095518) (xy 24.79514 -452.046883) (xy 24.829226 -452.00274)
			(xy 24.869375 -451.964031) (xy 24.914733 -451.93158) (xy 24.964333 -451.906079) (xy 25.017117 -451.888072)
			(xy 25.07196 -451.877942) (xy 25.127694 -451.875905) (xy 25.183131 -451.882005) (xy 25.237088 -451.896111)
			(xy 25.288417 -451.917923) (xy 25.336023 -451.946977) (xy 25.378891 -451.982652) (xy 25.416108 -452.024189)
			(xy 25.446881 -452.070702) (xy 25.470553 -452.121199) (xy 25.486621 -452.174606) (xy 25.494741 -452.229782)
			(xy 25.49525 -452.257668) (xy 25.495241 -452.258176) (xy 26.890724 -452.258176) (xy 26.894795 -452.202554)
			(xy 26.906921 -452.148117) (xy 26.926844 -452.096026) (xy 26.95414 -452.047391) (xy 26.988226 -452.003248)
			(xy 27.028375 -451.964539) (xy 27.073733 -451.932088) (xy 27.123333 -451.906587) (xy 27.176117 -451.88858)
			(xy 27.23096 -451.87845) (xy 27.286694 -451.876413) (xy 27.342131 -451.882513) (xy 27.396088 -451.896619)
			(xy 27.447417 -451.918431) (xy 27.495023 -451.947485) (xy 27.537891 -451.98316) (xy 27.575108 -452.024697)
			(xy 27.605881 -452.07121) (xy 27.629553 -452.121707) (xy 27.645621 -452.175114) (xy 27.653741 -452.23029)
			(xy 27.65425 -452.258176) (xy 27.653741 -452.286062) (xy 27.645621 -452.341238) (xy 27.629553 -452.394645)
			(xy 27.605881 -452.445142) (xy 27.575108 -452.491655) (xy 27.537891 -452.533192) (xy 27.495023 -452.568867)
			(xy 27.447417 -452.597921) (xy 27.396088 -452.619733) (xy 27.342131 -452.633839) (xy 27.286694 -452.639939)
			(xy 27.23096 -452.637902) (xy 27.176117 -452.627772) (xy 27.123333 -452.609765) (xy 27.073733 -452.584264)
			(xy 27.028375 -452.551813) (xy 26.988226 -452.513104) (xy 26.95414 -452.468961) (xy 26.926844 -452.420326)
			(xy 26.906921 -452.368235) (xy 26.894795 -452.313798) (xy 26.890724 -452.258176) (xy 25.495241 -452.258176)
			(xy 25.494741 -452.285554) (xy 25.486621 -452.34073) (xy 25.470553 -452.394137) (xy 25.446881 -452.444634)
			(xy 25.416108 -452.491147) (xy 25.378891 -452.532684) (xy 25.336023 -452.568359) (xy 25.288417 -452.597413)
			(xy 25.237088 -452.619225) (xy 25.183131 -452.633331) (xy 25.127694 -452.639431) (xy 25.07196 -452.637394)
			(xy 25.017117 -452.627264) (xy 24.964333 -452.609257) (xy 24.914733 -452.583756) (xy 24.869375 -452.551305)
			(xy 24.829226 -452.512596) (xy 24.79514 -452.468453) (xy 24.767844 -452.419818) (xy 24.747921 -452.367727)
			(xy 24.735795 -452.31329) (xy 24.731724 -452.257668) (xy 6.328491 -452.257668) (xy 6.399632 -452.286254)
			(xy 6.483453 -452.328516) (xy 6.563388 -452.377734) (xy 6.638861 -452.433553) (xy 6.709328 -452.495572)
			(xy 6.774281 -452.563344) (xy 6.833254 -452.636379) (xy 6.88582 -452.714153) (xy 6.931601 -452.796105)
			(xy 6.970267 -452.881644) (xy 7.001539 -452.970153) (xy 7.025193 -453.060996) (xy 7.041057 -453.153518)
			(xy 7.049018 -453.247052) (xy 7.049516 -453.293988) (xy 7.049018 -453.340924) (xy 7.041057 -453.434458)
			(xy 7.025193 -453.52698) (xy 7.023096 -453.535034) (xy 24.77592 -453.535034) (xy 24.779991 -453.479412)
			(xy 24.792117 -453.424975) (xy 24.81204 -453.372884) (xy 24.839336 -453.324249) (xy 24.873422 -453.280106)
			(xy 24.913571 -453.241397) (xy 24.958929 -453.208946) (xy 25.008529 -453.183445) (xy 25.061313 -453.165438)
			(xy 25.116156 -453.155308) (xy 25.17189 -453.153271) (xy 25.227327 -453.159371) (xy 25.281284 -453.173477)
			(xy 25.332613 -453.195289) (xy 25.380219 -453.224343) (xy 25.423087 -453.260018) (xy 25.460304 -453.301555)
			(xy 25.491077 -453.348068) (xy 25.514749 -453.398565) (xy 25.530817 -453.451972) (xy 25.538937 -453.507148)
			(xy 25.539446 -453.535034) (xy 25.538937 -453.56292) (xy 25.530817 -453.618096) (xy 25.514749 -453.671503)
			(xy 25.491077 -453.722) (xy 25.460304 -453.768513) (xy 25.423087 -453.81005) (xy 25.380219 -453.845725)
			(xy 25.332613 -453.874779) (xy 25.281284 -453.896591) (xy 25.227327 -453.910697) (xy 25.17189 -453.916797)
			(xy 25.116156 -453.91476) (xy 25.061313 -453.90463) (xy 25.008529 -453.886623) (xy 24.958929 -453.861122)
			(xy 24.913571 -453.828671) (xy 24.873422 -453.789962) (xy 24.839336 -453.745819) (xy 24.81204 -453.697184)
			(xy 24.792117 -453.645093) (xy 24.779991 -453.590656) (xy 24.77592 -453.535034) (xy 7.023096 -453.535034)
			(xy 7.001539 -453.617823) (xy 6.970267 -453.706332) (xy 6.931601 -453.791871) (xy 6.88582 -453.873823)
			(xy 6.833254 -453.951597) (xy 6.774281 -454.024632) (xy 6.709328 -454.092404) (xy 6.638861 -454.154423)
			(xy 6.563388 -454.210242) (xy 6.493357 -454.253362) (xy 29.519874 -454.253362) (xy 29.519874 -454.166462)
			(xy 29.527892 -454.079933) (xy 29.54386 -453.994513) (xy 29.567641 -453.910931) (xy 29.599033 -453.829899)
			(xy 29.637767 -453.75211) (xy 29.683514 -453.678226) (xy 29.735883 -453.608879) (xy 29.794427 -453.544659)
			(xy 29.858647 -453.486115) (xy 29.927994 -453.433746) (xy 30.001878 -453.387999) (xy 30.079667 -453.349265)
			(xy 30.160699 -453.317873) (xy 30.244281 -453.294092) (xy 30.329701 -453.278124) (xy 30.41623 -453.270106)
			(xy 30.50313 -453.270106) (xy 30.589659 -453.278124) (xy 30.675079 -453.294092) (xy 30.758661 -453.317873)
			(xy 30.839693 -453.349265) (xy 30.917482 -453.387999) (xy 30.991366 -453.433746) (xy 31.060713 -453.486115)
			(xy 31.124933 -453.544659) (xy 31.183477 -453.608879) (xy 31.235846 -453.678226) (xy 31.281593 -453.75211)
			(xy 31.320327 -453.829899) (xy 31.351719 -453.910931) (xy 31.3755 -453.994513) (xy 31.391468 -454.079933)
			(xy 31.399486 -454.166462) (xy 31.399988 -454.209912) (xy 31.399486 -454.253362) (xy 34.599874 -454.253362)
			(xy 34.599874 -454.166462) (xy 34.607892 -454.079933) (xy 34.62386 -453.994513) (xy 34.647641 -453.910931)
			(xy 34.679033 -453.829899) (xy 34.717767 -453.75211) (xy 34.763514 -453.678226) (xy 34.815883 -453.608879)
			(xy 34.874427 -453.544659) (xy 34.938647 -453.486115) (xy 35.007994 -453.433746) (xy 35.081878 -453.387999)
			(xy 35.159667 -453.349265) (xy 35.240699 -453.317873) (xy 35.324281 -453.294092) (xy 35.409701 -453.278124)
			(xy 35.49623 -453.270106) (xy 35.58313 -453.270106) (xy 35.669659 -453.278124) (xy 35.755079 -453.294092)
			(xy 35.838661 -453.317873) (xy 35.919693 -453.349265) (xy 35.997482 -453.387999) (xy 36.071366 -453.433746)
			(xy 36.140713 -453.486115) (xy 36.204933 -453.544659) (xy 36.263477 -453.608879) (xy 36.315846 -453.678226)
			(xy 36.361593 -453.75211) (xy 36.400327 -453.829899) (xy 36.431719 -453.910931) (xy 36.4555 -453.994513)
			(xy 36.471468 -454.079933) (xy 36.479486 -454.166462) (xy 36.479988 -454.209912) (xy 36.479486 -454.253362)
			(xy 36.471468 -454.339891) (xy 36.4555 -454.425311) (xy 36.431719 -454.508893) (xy 36.400327 -454.589925)
			(xy 36.361593 -454.667714) (xy 36.315846 -454.741598) (xy 36.263477 -454.810945) (xy 36.204933 -454.875165)
			(xy 36.140713 -454.933709) (xy 36.071366 -454.986078) (xy 35.997482 -455.031825) (xy 35.919693 -455.070559)
			(xy 35.838661 -455.101951) (xy 35.755079 -455.125732) (xy 35.669659 -455.1417) (xy 35.58313 -455.149718)
			(xy 35.49623 -455.149718) (xy 35.409701 -455.1417) (xy 35.324281 -455.125732) (xy 35.240699 -455.101951)
			(xy 35.159667 -455.070559) (xy 35.081878 -455.031825) (xy 35.007994 -454.986078) (xy 34.938647 -454.933709)
			(xy 34.874427 -454.875165) (xy 34.815883 -454.810945) (xy 34.763514 -454.741598) (xy 34.717767 -454.667714)
			(xy 34.679033 -454.589925) (xy 34.647641 -454.508893) (xy 34.62386 -454.425311) (xy 34.607892 -454.339891)
			(xy 34.599874 -454.253362) (xy 31.399486 -454.253362) (xy 31.391468 -454.339891) (xy 31.3755 -454.425311)
			(xy 31.351719 -454.508893) (xy 31.320327 -454.589925) (xy 31.281593 -454.667714) (xy 31.235846 -454.741598)
			(xy 31.183477 -454.810945) (xy 31.124933 -454.875165) (xy 31.060713 -454.933709) (xy 30.991366 -454.986078)
			(xy 30.917482 -455.031825) (xy 30.839693 -455.070559) (xy 30.758661 -455.101951) (xy 30.675079 -455.125732)
			(xy 30.589659 -455.1417) (xy 30.50313 -455.149718) (xy 30.41623 -455.149718) (xy 30.329701 -455.1417)
			(xy 30.244281 -455.125732) (xy 30.160699 -455.101951) (xy 30.079667 -455.070559) (xy 30.001878 -455.031825)
			(xy 29.927994 -454.986078) (xy 29.858647 -454.933709) (xy 29.794427 -454.875165) (xy 29.735883 -454.810945)
			(xy 29.683514 -454.741598) (xy 29.637767 -454.667714) (xy 29.599033 -454.589925) (xy 29.567641 -454.508893)
			(xy 29.54386 -454.425311) (xy 29.527892 -454.339891) (xy 29.519874 -454.253362) (xy 6.493357 -454.253362)
			(xy 6.483453 -454.25946) (xy 6.399632 -454.301722) (xy 6.312529 -454.336722) (xy 6.222772 -454.36421)
			(xy 6.131007 -454.383987) (xy 6.037895 -454.39591) (xy 5.944108 -454.399895) (xy 5.850321 -454.39591)
			(xy 5.757209 -454.383987) (xy 5.665444 -454.36421) (xy 5.575687 -454.336722) (xy 5.488584 -454.301722)
			(xy 5.404763 -454.25946) (xy 5.324828 -454.210242) (xy 5.249355 -454.154423) (xy 5.178888 -454.092404)
			(xy 5.113935 -454.024632) (xy 5.054962 -453.951597) (xy 5.002396 -453.873823) (xy 4.956615 -453.791871)
			(xy 4.917949 -453.706332) (xy 4.886677 -453.617823) (xy 4.863023 -453.52698) (xy 4.847159 -453.434458)
			(xy 4.839198 -453.340924) (xy 1.27 -453.340924) (xy 1.27 -454.646538) (xy 24.838658 -454.646538)
			(xy 24.842729 -454.590916) (xy 24.854855 -454.536479) (xy 24.874778 -454.484388) (xy 24.902074 -454.435753)
			(xy 24.93616 -454.39161) (xy 24.976309 -454.352901) (xy 25.021667 -454.32045) (xy 25.071267 -454.294949)
			(xy 25.124051 -454.276942) (xy 25.178894 -454.266812) (xy 25.234628 -454.264775) (xy 25.290065 -454.270875)
			(xy 25.344022 -454.284981) (xy 25.395351 -454.306793) (xy 25.442957 -454.335847) (xy 25.485825 -454.371522)
			(xy 25.523042 -454.413059) (xy 25.553815 -454.459572) (xy 25.577487 -454.510069) (xy 25.593555 -454.563476)
			(xy 25.601675 -454.618652) (xy 25.602184 -454.646538) (xy 25.601675 -454.674424) (xy 25.593555 -454.7296)
			(xy 25.577487 -454.783007) (xy 25.553815 -454.833504) (xy 25.523042 -454.880017) (xy 25.485825 -454.921554)
			(xy 25.442957 -454.957229) (xy 25.395351 -454.986283) (xy 25.344022 -455.008095) (xy 25.290065 -455.022201)
			(xy 25.234628 -455.028301) (xy 25.178894 -455.026264) (xy 25.124051 -455.016134) (xy 25.071267 -454.998127)
			(xy 25.021667 -454.972626) (xy 24.976309 -454.940175) (xy 24.93616 -454.901466) (xy 24.902074 -454.857323)
			(xy 24.874778 -454.808688) (xy 24.854855 -454.756597) (xy 24.842729 -454.70216) (xy 24.838658 -454.646538)
			(xy 1.27 -454.646538) (xy 1.27 -455.070073) (xy 26.851826 -455.070073) (xy 26.854933 -455.014607)
			(xy 26.866051 -454.960178) (xy 26.884946 -454.907936) (xy 26.911217 -454.858987) (xy 26.944309 -454.814366)
			(xy 26.983523 -454.775016) (xy 27.02803 -454.741769) (xy 27.076887 -454.715328) (xy 27.129063 -454.696252)
			(xy 27.183453 -454.684945) (xy 27.238908 -454.681646) (xy 27.294256 -454.686424) (xy 27.348325 -454.699179)
			(xy 27.399973 -454.71964) (xy 27.448107 -454.747375) (xy 27.491711 -454.781798) (xy 27.52986 -454.822181)
			(xy 27.56175 -454.867669) (xy 27.586706 -454.917302) (xy 27.604199 -454.970029) (xy 27.613861 -455.024736)
			(xy 27.615487 -455.080265) (xy 27.609042 -455.135443) (xy 27.594662 -455.189104) (xy 27.572653 -455.240111)
			(xy 27.558492 -455.264012) (xy 27.547184 -455.283157) (xy 27.530785 -455.324484) (xy 27.521838 -455.368037)
			(xy 27.520619 -455.412482) (xy 27.527165 -455.456459) (xy 27.541275 -455.498623) (xy 27.562517 -455.537682)
			(xy 27.576018 -455.55535) (xy 27.592935 -455.577387) (xy 27.62084 -455.625427) (xy 27.641483 -455.677005)
			(xy 27.654428 -455.731032) (xy 27.6594 -455.786365) (xy 27.656294 -455.841834) (xy 27.645177 -455.896266)
			(xy 27.626283 -455.94851) (xy 27.600012 -455.997462) (xy 27.566919 -456.042086) (xy 27.527705 -456.081439)
			(xy 27.483197 -456.114689) (xy 27.434338 -456.141132) (xy 27.382161 -456.16021) (xy 27.327768 -456.171519)
			(xy 27.27231 -456.17482) (xy 27.21696 -456.170043) (xy 27.162888 -456.157289) (xy 27.111237 -456.136828)
			(xy 27.0631 -456.109092) (xy 27.019494 -456.074669) (xy 26.981342 -456.034285) (xy 26.94945 -455.988795)
			(xy 26.924492 -455.93916) (xy 26.906997 -455.886431) (xy 26.897334 -455.831722) (xy 26.895707 -455.77619)
			(xy 26.902152 -455.721009) (xy 26.916531 -455.667346) (xy 26.938541 -455.616336) (xy 26.952702 -455.592434)
			(xy 26.963957 -455.573261) (xy 26.980355 -455.531941) (xy 26.989303 -455.488396) (xy 26.990528 -455.443958)
			(xy 26.983992 -455.399986) (xy 26.969895 -455.357825) (xy 26.948669 -455.318766) (xy 26.935176 -455.301096)
			(xy 26.91828 -455.279043) (xy 26.890378 -455.231005) (xy 26.869738 -455.179429) (xy 26.856796 -455.125404)
			(xy 26.851826 -455.070073) (xy 1.27 -455.070073) (xy 1.27 -456.281282) (xy 17.493486 -456.281282)
			(xy 17.497557 -456.22566) (xy 17.509683 -456.171223) (xy 17.529606 -456.119132) (xy 17.556902 -456.070497)
			(xy 17.590988 -456.026354) (xy 17.631137 -455.987645) (xy 17.676495 -455.955194) (xy 17.726095 -455.929693)
			(xy 17.778879 -455.911686) (xy 17.833722 -455.901556) (xy 17.889456 -455.899519) (xy 17.944893 -455.905619)
			(xy 17.99885 -455.919725) (xy 18.050179 -455.941537) (xy 18.097785 -455.970591) (xy 18.140653 -456.006266)
			(xy 18.17787 -456.047803) (xy 18.208643 -456.094316) (xy 18.232315 -456.144813) (xy 18.248383 -456.19822)
			(xy 18.255112 -456.243944) (xy 18.763486 -456.243944) (xy 18.767557 -456.188322) (xy 18.779683 -456.133885)
			(xy 18.799606 -456.081794) (xy 18.826902 -456.033159) (xy 18.860988 -455.989016) (xy 18.901137 -455.950307)
			(xy 18.946495 -455.917856) (xy 18.996095 -455.892355) (xy 19.048879 -455.874348) (xy 19.103722 -455.864218)
			(xy 19.159456 -455.862181) (xy 19.214893 -455.868281) (xy 19.26885 -455.882387) (xy 19.320179 -455.904199)
			(xy 19.367785 -455.933253) (xy 19.410653 -455.968928) (xy 19.44787 -456.010465) (xy 19.478643 -456.056978)
			(xy 19.502315 -456.107475) (xy 19.518383 -456.160882) (xy 19.526503 -456.216058) (xy 19.526674 -456.225402)
			(xy 20.033486 -456.225402) (xy 20.037557 -456.16978) (xy 20.049683 -456.115343) (xy 20.069606 -456.063252)
			(xy 20.096902 -456.014617) (xy 20.130988 -455.970474) (xy 20.171137 -455.931765) (xy 20.216495 -455.899314)
			(xy 20.266095 -455.873813) (xy 20.318879 -455.855806) (xy 20.373722 -455.845676) (xy 20.429456 -455.843639)
			(xy 20.484893 -455.849739) (xy 20.53885 -455.863845) (xy 20.590179 -455.885657) (xy 20.637785 -455.914711)
			(xy 20.680653 -455.950386) (xy 20.71787 -455.991923) (xy 20.748643 -456.038436) (xy 20.772315 -456.088933)
			(xy 20.788383 -456.14234) (xy 20.796503 -456.197516) (xy 20.797012 -456.225402) (xy 20.796674 -456.243944)
			(xy 21.303486 -456.243944) (xy 21.307557 -456.188322) (xy 21.319683 -456.133885) (xy 21.339606 -456.081794)
			(xy 21.366902 -456.033159) (xy 21.400988 -455.989016) (xy 21.441137 -455.950307) (xy 21.486495 -455.917856)
			(xy 21.536095 -455.892355) (xy 21.588879 -455.874348) (xy 21.643722 -455.864218) (xy 21.699456 -455.862181)
			(xy 21.754893 -455.868281) (xy 21.80885 -455.882387) (xy 21.860179 -455.904199) (xy 21.907785 -455.933253)
			(xy 21.950653 -455.968928) (xy 21.98787 -456.010465) (xy 22.018643 -456.056978) (xy 22.042315 -456.107475)
			(xy 22.058383 -456.160882) (xy 22.066503 -456.216058) (xy 22.067012 -456.243944) (xy 22.066503 -456.27183)
			(xy 22.058383 -456.327006) (xy 22.042315 -456.380413) (xy 22.018643 -456.43091) (xy 21.98787 -456.477423)
			(xy 21.950653 -456.51896) (xy 21.907785 -456.554635) (xy 21.860179 -456.583689) (xy 21.80885 -456.605501)
			(xy 21.754893 -456.619607) (xy 21.699456 -456.625707) (xy 21.643722 -456.62367) (xy 21.588879 -456.61354)
			(xy 21.536095 -456.595533) (xy 21.486495 -456.570032) (xy 21.441137 -456.537581) (xy 21.400988 -456.498872)
			(xy 21.366902 -456.454729) (xy 21.339606 -456.406094) (xy 21.319683 -456.354003) (xy 21.307557 -456.299566)
			(xy 21.303486 -456.243944) (xy 20.796674 -456.243944) (xy 20.796503 -456.253288) (xy 20.788383 -456.308464)
			(xy 20.772315 -456.361871) (xy 20.748643 -456.412368) (xy 20.71787 -456.458881) (xy 20.680653 -456.500418)
			(xy 20.637785 -456.536093) (xy 20.590179 -456.565147) (xy 20.53885 -456.586959) (xy 20.484893 -456.601065)
			(xy 20.429456 -456.607165) (xy 20.373722 -456.605128) (xy 20.318879 -456.594998) (xy 20.266095 -456.576991)
			(xy 20.216495 -456.55149) (xy 20.171137 -456.519039) (xy 20.130988 -456.48033) (xy 20.096902 -456.436187)
			(xy 20.069606 -456.387552) (xy 20.049683 -456.335461) (xy 20.037557 -456.281024) (xy 20.033486 -456.225402)
			(xy 19.526674 -456.225402) (xy 19.527012 -456.243944) (xy 19.526503 -456.27183) (xy 19.518383 -456.327006)
			(xy 19.502315 -456.380413) (xy 19.478643 -456.43091) (xy 19.44787 -456.477423) (xy 19.410653 -456.51896)
			(xy 19.367785 -456.554635) (xy 19.320179 -456.583689) (xy 19.26885 -456.605501) (xy 19.214893 -456.619607)
			(xy 19.159456 -456.625707) (xy 19.103722 -456.62367) (xy 19.048879 -456.61354) (xy 18.996095 -456.595533)
			(xy 18.946495 -456.570032) (xy 18.901137 -456.537581) (xy 18.860988 -456.498872) (xy 18.826902 -456.454729)
			(xy 18.799606 -456.406094) (xy 18.779683 -456.354003) (xy 18.767557 -456.299566) (xy 18.763486 -456.243944)
			(xy 18.255112 -456.243944) (xy 18.256503 -456.253396) (xy 18.257012 -456.281282) (xy 18.256503 -456.309168)
			(xy 18.248383 -456.364344) (xy 18.232315 -456.417751) (xy 18.208643 -456.468248) (xy 18.17787 -456.514761)
			(xy 18.140653 -456.556298) (xy 18.097785 -456.591973) (xy 18.050179 -456.621027) (xy 17.99885 -456.642839)
			(xy 17.944893 -456.656945) (xy 17.889456 -456.663045) (xy 17.833722 -456.661008) (xy 17.778879 -456.650878)
			(xy 17.726095 -456.632871) (xy 17.676495 -456.60737) (xy 17.631137 -456.574919) (xy 17.590988 -456.53621)
			(xy 17.556902 -456.492067) (xy 17.529606 -456.443432) (xy 17.509683 -456.391341) (xy 17.497557 -456.336904)
			(xy 17.493486 -456.281282) (xy 1.27 -456.281282) (xy 1.27 -457.541068) (xy 4.839198 -457.541068)
			(xy 4.839198 -457.447196) (xy 4.847159 -457.353662) (xy 4.863023 -457.26114) (xy 4.886677 -457.170297)
			(xy 4.917949 -457.081788) (xy 4.956615 -456.996249) (xy 5.002396 -456.914297) (xy 5.054962 -456.836523)
			(xy 5.113935 -456.763488) (xy 5.178888 -456.695716) (xy 5.249355 -456.633697) (xy 5.324828 -456.577878)
			(xy 5.404763 -456.52866) (xy 5.488584 -456.486398) (xy 5.575687 -456.451398) (xy 5.665444 -456.42391)
			(xy 5.757209 -456.404133) (xy 5.850321 -456.39221) (xy 5.944108 -456.388226) (xy 6.037895 -456.39221)
			(xy 6.131007 -456.404133) (xy 6.222772 -456.42391) (xy 6.312529 -456.451398) (xy 6.399632 -456.486398)
			(xy 6.483453 -456.52866) (xy 6.563388 -456.577878) (xy 6.638861 -456.633697) (xy 6.709328 -456.695716)
			(xy 6.774281 -456.763488) (xy 6.798403 -456.793362) (xy 29.519874 -456.793362) (xy 29.519874 -456.706462)
			(xy 29.527892 -456.619933) (xy 29.54386 -456.534513) (xy 29.567641 -456.450931) (xy 29.599033 -456.369899)
			(xy 29.637767 -456.29211) (xy 29.683514 -456.218226) (xy 29.735883 -456.148879) (xy 29.794427 -456.084659)
			(xy 29.858647 -456.026115) (xy 29.927994 -455.973746) (xy 30.001878 -455.927999) (xy 30.079667 -455.889265)
			(xy 30.160699 -455.857873) (xy 30.244281 -455.834092) (xy 30.329701 -455.818124) (xy 30.41623 -455.810106)
			(xy 30.50313 -455.810106) (xy 30.589659 -455.818124) (xy 30.675079 -455.834092) (xy 30.758661 -455.857873)
			(xy 30.839693 -455.889265) (xy 30.917482 -455.927999) (xy 30.991366 -455.973746) (xy 31.060713 -456.026115)
			(xy 31.124933 -456.084659) (xy 31.183477 -456.148879) (xy 31.235846 -456.218226) (xy 31.281593 -456.29211)
			(xy 31.320327 -456.369899) (xy 31.351719 -456.450931) (xy 31.3755 -456.534513) (xy 31.391468 -456.619933)
			(xy 31.399486 -456.706462) (xy 31.399988 -456.749912) (xy 31.399486 -456.793362) (xy 34.599874 -456.793362)
			(xy 34.599874 -456.706462) (xy 34.607892 -456.619933) (xy 34.62386 -456.534513) (xy 34.647641 -456.450931)
			(xy 34.679033 -456.369899) (xy 34.717767 -456.29211) (xy 34.763514 -456.218226) (xy 34.815883 -456.148879)
			(xy 34.874427 -456.084659) (xy 34.938647 -456.026115) (xy 35.007994 -455.973746) (xy 35.081878 -455.927999)
			(xy 35.159667 -455.889265) (xy 35.240699 -455.857873) (xy 35.324281 -455.834092) (xy 35.409701 -455.818124)
			(xy 35.49623 -455.810106) (xy 35.58313 -455.810106) (xy 35.669659 -455.818124) (xy 35.755079 -455.834092)
			(xy 35.838661 -455.857873) (xy 35.919693 -455.889265) (xy 35.997482 -455.927999) (xy 36.071366 -455.973746)
			(xy 36.140713 -456.026115) (xy 36.204933 -456.084659) (xy 36.263477 -456.148879) (xy 36.315846 -456.218226)
			(xy 36.361593 -456.29211) (xy 36.400327 -456.369899) (xy 36.431719 -456.450931) (xy 36.4555 -456.534513)
			(xy 36.471468 -456.619933) (xy 36.479486 -456.706462) (xy 36.479988 -456.749912) (xy 36.479486 -456.793362)
			(xy 36.471468 -456.879891) (xy 36.4555 -456.965311) (xy 36.431719 -457.048893) (xy 36.400327 -457.129925)
			(xy 36.361593 -457.207714) (xy 36.315846 -457.281598) (xy 36.263477 -457.350945) (xy 36.210978 -457.408534)
			(xy 39.35679 -457.408534) (xy 39.360861 -457.352912) (xy 39.372987 -457.298475) (xy 39.39291 -457.246384)
			(xy 39.420206 -457.197749) (xy 39.454292 -457.153606) (xy 39.494441 -457.114897) (xy 39.539799 -457.082446)
			(xy 39.589399 -457.056945) (xy 39.642183 -457.038938) (xy 39.697026 -457.028808) (xy 39.75276 -457.026771)
			(xy 39.808197 -457.032871) (xy 39.862154 -457.046977) (xy 39.913483 -457.068789) (xy 39.961089 -457.097843)
			(xy 40.003957 -457.133518) (xy 40.041174 -457.175055) (xy 40.071947 -457.221568) (xy 40.095619 -457.272065)
			(xy 40.111687 -457.325472) (xy 40.119807 -457.380648) (xy 40.120316 -457.408534) (xy 40.119807 -457.43642)
			(xy 40.111687 -457.491596) (xy 40.095619 -457.545003) (xy 40.071947 -457.5955) (xy 40.041174 -457.642013)
			(xy 40.003957 -457.68355) (xy 39.961089 -457.719225) (xy 39.913483 -457.748279) (xy 39.862154 -457.770091)
			(xy 39.808197 -457.784197) (xy 39.75276 -457.790297) (xy 39.697026 -457.78826) (xy 39.642183 -457.77813)
			(xy 39.589399 -457.760123) (xy 39.539799 -457.734622) (xy 39.494441 -457.702171) (xy 39.454292 -457.663462)
			(xy 39.420206 -457.619319) (xy 39.39291 -457.570684) (xy 39.372987 -457.518593) (xy 39.360861 -457.464156)
			(xy 39.35679 -457.408534) (xy 36.210978 -457.408534) (xy 36.204933 -457.415165) (xy 36.140713 -457.473709)
			(xy 36.071366 -457.526078) (xy 35.997482 -457.571825) (xy 35.919693 -457.610559) (xy 35.838661 -457.641951)
			(xy 35.755079 -457.665732) (xy 35.669659 -457.6817) (xy 35.58313 -457.689718) (xy 35.49623 -457.689718)
			(xy 35.409701 -457.6817) (xy 35.324281 -457.665732) (xy 35.240699 -457.641951) (xy 35.159667 -457.610559)
			(xy 35.081878 -457.571825) (xy 35.007994 -457.526078) (xy 34.938647 -457.473709) (xy 34.874427 -457.415165)
			(xy 34.815883 -457.350945) (xy 34.763514 -457.281598) (xy 34.717767 -457.207714) (xy 34.679033 -457.129925)
			(xy 34.647641 -457.048893) (xy 34.62386 -456.965311) (xy 34.607892 -456.879891) (xy 34.599874 -456.793362)
			(xy 31.399486 -456.793362) (xy 31.391468 -456.879891) (xy 31.3755 -456.965311) (xy 31.351719 -457.048893)
			(xy 31.320327 -457.129925) (xy 31.281593 -457.207714) (xy 31.235846 -457.281598) (xy 31.183477 -457.350945)
			(xy 31.124933 -457.415165) (xy 31.060713 -457.473709) (xy 30.991366 -457.526078) (xy 30.917482 -457.571825)
			(xy 30.839693 -457.610559) (xy 30.758661 -457.641951) (xy 30.675079 -457.665732) (xy 30.589659 -457.6817)
			(xy 30.50313 -457.689718) (xy 30.41623 -457.689718) (xy 30.329701 -457.6817) (xy 30.244281 -457.665732)
			(xy 30.160699 -457.641951) (xy 30.079667 -457.610559) (xy 30.001878 -457.571825) (xy 29.927994 -457.526078)
			(xy 29.858647 -457.473709) (xy 29.794427 -457.415165) (xy 29.735883 -457.350945) (xy 29.683514 -457.281598)
			(xy 29.637767 -457.207714) (xy 29.599033 -457.129925) (xy 29.567641 -457.048893) (xy 29.54386 -456.965311)
			(xy 29.527892 -456.879891) (xy 29.519874 -456.793362) (xy 6.798403 -456.793362) (xy 6.833254 -456.836523)
			(xy 6.88582 -456.914297) (xy 6.931601 -456.996249) (xy 6.970267 -457.081788) (xy 7.001539 -457.170297)
			(xy 7.025193 -457.26114) (xy 7.041057 -457.353662) (xy 7.049018 -457.447196) (xy 7.049516 -457.494132)
			(xy 7.049018 -457.541068) (xy 7.041057 -457.634602) (xy 7.025193 -457.727124) (xy 7.014961 -457.76642)
			(xy 26.750008 -457.76642) (xy 26.754079 -457.710798) (xy 26.766205 -457.656361) (xy 26.786128 -457.60427)
			(xy 26.813424 -457.555635) (xy 26.84751 -457.511492) (xy 26.887659 -457.472783) (xy 26.933017 -457.440332)
			(xy 26.982617 -457.414831) (xy 27.035401 -457.396824) (xy 27.090244 -457.386694) (xy 27.145978 -457.384657)
			(xy 27.201415 -457.390757) (xy 27.255372 -457.404863) (xy 27.306701 -457.426675) (xy 27.354307 -457.455729)
			(xy 27.397175 -457.491404) (xy 27.434392 -457.532941) (xy 27.465165 -457.579454) (xy 27.488837 -457.629951)
			(xy 27.504905 -457.683358) (xy 27.513025 -457.738534) (xy 27.513534 -457.76642) (xy 27.513025 -457.794306)
			(xy 27.504905 -457.849482) (xy 27.488837 -457.902889) (xy 27.465165 -457.953386) (xy 27.434392 -457.999899)
			(xy 27.397175 -458.041436) (xy 27.354307 -458.077111) (xy 27.306701 -458.106165) (xy 27.255372 -458.127977)
			(xy 27.201415 -458.142083) (xy 27.145978 -458.148183) (xy 27.090244 -458.146146) (xy 27.035401 -458.136016)
			(xy 26.982617 -458.118009) (xy 26.933017 -458.092508) (xy 26.887659 -458.060057) (xy 26.84751 -458.021348)
			(xy 26.813424 -457.977205) (xy 26.786128 -457.92857) (xy 26.766205 -457.876479) (xy 26.754079 -457.822042)
			(xy 26.750008 -457.76642) (xy 7.014961 -457.76642) (xy 7.001539 -457.817967) (xy 6.970267 -457.906476)
			(xy 6.931601 -457.992015) (xy 6.88582 -458.073967) (xy 6.833254 -458.151741) (xy 6.774281 -458.224776)
			(xy 6.709328 -458.292548) (xy 6.638861 -458.354567) (xy 6.563388 -458.410386) (xy 6.483453 -458.459604)
			(xy 6.399632 -458.501866) (xy 6.312529 -458.536866) (xy 6.222772 -458.564354) (xy 6.131007 -458.584131)
			(xy 6.037895 -458.596054) (xy 5.944108 -458.600039) (xy 5.850321 -458.596054) (xy 5.757209 -458.584131)
			(xy 5.665444 -458.564354) (xy 5.575687 -458.536866) (xy 5.488584 -458.501866) (xy 5.404763 -458.459604)
			(xy 5.324828 -458.410386) (xy 5.249355 -458.354567) (xy 5.178888 -458.292548) (xy 5.113935 -458.224776)
			(xy 5.054962 -458.151741) (xy 5.002396 -458.073967) (xy 4.956615 -457.992015) (xy 4.917949 -457.906476)
			(xy 4.886677 -457.817967) (xy 4.863023 -457.727124) (xy 4.847159 -457.634602) (xy 4.839198 -457.541068)
			(xy 1.27 -457.541068) (xy 1.27 -459.333362) (xy 29.519874 -459.333362) (xy 29.519874 -459.246462)
			(xy 29.527892 -459.159933) (xy 29.54386 -459.074513) (xy 29.567641 -458.990931) (xy 29.599033 -458.909899)
			(xy 29.637767 -458.83211) (xy 29.683514 -458.758226) (xy 29.735883 -458.688879) (xy 29.794427 -458.624659)
			(xy 29.858647 -458.566115) (xy 29.927994 -458.513746) (xy 30.001878 -458.467999) (xy 30.079667 -458.429265)
			(xy 30.160699 -458.397873) (xy 30.244281 -458.374092) (xy 30.329701 -458.358124) (xy 30.41623 -458.350106)
			(xy 30.50313 -458.350106) (xy 30.589659 -458.358124) (xy 30.675079 -458.374092) (xy 30.758661 -458.397873)
			(xy 30.839693 -458.429265) (xy 30.917482 -458.467999) (xy 30.991366 -458.513746) (xy 31.060713 -458.566115)
			(xy 31.124933 -458.624659) (xy 31.183477 -458.688879) (xy 31.235846 -458.758226) (xy 31.281593 -458.83211)
			(xy 31.320327 -458.909899) (xy 31.351719 -458.990931) (xy 31.3755 -459.074513) (xy 31.391468 -459.159933)
			(xy 31.399486 -459.246462) (xy 31.399988 -459.289912) (xy 31.399486 -459.333362) (xy 34.599874 -459.333362)
			(xy 34.599874 -459.246462) (xy 34.607892 -459.159933) (xy 34.62386 -459.074513) (xy 34.647641 -458.990931)
			(xy 34.679033 -458.909899) (xy 34.717767 -458.83211) (xy 34.763514 -458.758226) (xy 34.815883 -458.688879)
			(xy 34.874427 -458.624659) (xy 34.938647 -458.566115) (xy 35.007994 -458.513746) (xy 35.081878 -458.467999)
			(xy 35.159667 -458.429265) (xy 35.240699 -458.397873) (xy 35.324281 -458.374092) (xy 35.409701 -458.358124)
			(xy 35.49623 -458.350106) (xy 35.58313 -458.350106) (xy 35.669659 -458.358124) (xy 35.755079 -458.374092)
			(xy 35.838661 -458.397873) (xy 35.919693 -458.429265) (xy 35.997482 -458.467999) (xy 36.071366 -458.513746)
			(xy 36.140713 -458.566115) (xy 36.204933 -458.624659) (xy 36.263477 -458.688879) (xy 36.315846 -458.758226)
			(xy 36.361593 -458.83211) (xy 36.400327 -458.909899) (xy 36.431719 -458.990931) (xy 36.4555 -459.074513)
			(xy 36.471468 -459.159933) (xy 36.472026 -459.16596) (xy 40.801542 -459.16596) (xy 40.805613 -459.110338)
			(xy 40.817739 -459.055901) (xy 40.837662 -459.00381) (xy 40.864958 -458.955175) (xy 40.899044 -458.911032)
			(xy 40.939193 -458.872323) (xy 40.984551 -458.839872) (xy 41.034151 -458.814371) (xy 41.086935 -458.796364)
			(xy 41.141778 -458.786234) (xy 41.197512 -458.784197) (xy 41.252949 -458.790297) (xy 41.306906 -458.804403)
			(xy 41.358235 -458.826215) (xy 41.405841 -458.855269) (xy 41.448709 -458.890944) (xy 41.485926 -458.932481)
			(xy 41.516699 -458.978994) (xy 41.540371 -459.029491) (xy 41.556439 -459.082898) (xy 41.564559 -459.138074)
			(xy 41.565068 -459.16596) (xy 41.564559 -459.193846) (xy 41.556439 -459.249022) (xy 41.540371 -459.302429)
			(xy 41.516699 -459.352926) (xy 41.485926 -459.399439) (xy 41.448709 -459.440976) (xy 41.405841 -459.476651)
			(xy 41.358235 -459.505705) (xy 41.306906 -459.527517) (xy 41.252949 -459.541623) (xy 41.197512 -459.547723)
			(xy 41.141778 -459.545686) (xy 41.086935 -459.535556) (xy 41.034151 -459.517549) (xy 40.984551 -459.492048)
			(xy 40.939193 -459.459597) (xy 40.899044 -459.420888) (xy 40.864958 -459.376745) (xy 40.837662 -459.32811)
			(xy 40.817739 -459.276019) (xy 40.805613 -459.221582) (xy 40.801542 -459.16596) (xy 36.472026 -459.16596)
			(xy 36.479486 -459.246462) (xy 36.479988 -459.289912) (xy 36.479486 -459.333362) (xy 36.471468 -459.419891)
			(xy 36.4555 -459.505311) (xy 36.431719 -459.588893) (xy 36.400327 -459.669925) (xy 36.361593 -459.747714)
			(xy 36.315846 -459.821598) (xy 36.263477 -459.890945) (xy 36.204933 -459.955165) (xy 36.140713 -460.013709)
			(xy 36.071366 -460.066078) (xy 35.997482 -460.111825) (xy 35.919693 -460.150559) (xy 35.838661 -460.181951)
			(xy 35.755079 -460.205732) (xy 35.669659 -460.2217) (xy 35.58313 -460.229718) (xy 35.49623 -460.229718)
			(xy 35.409701 -460.2217) (xy 35.324281 -460.205732) (xy 35.240699 -460.181951) (xy 35.159667 -460.150559)
			(xy 35.081878 -460.111825) (xy 35.007994 -460.066078) (xy 34.938647 -460.013709) (xy 34.874427 -459.955165)
			(xy 34.815883 -459.890945) (xy 34.763514 -459.821598) (xy 34.717767 -459.747714) (xy 34.679033 -459.669925)
			(xy 34.647641 -459.588893) (xy 34.62386 -459.505311) (xy 34.607892 -459.419891) (xy 34.599874 -459.333362)
			(xy 31.399486 -459.333362) (xy 31.391468 -459.419891) (xy 31.3755 -459.505311) (xy 31.351719 -459.588893)
			(xy 31.320327 -459.669925) (xy 31.281593 -459.747714) (xy 31.235846 -459.821598) (xy 31.183477 -459.890945)
			(xy 31.124933 -459.955165) (xy 31.060713 -460.013709) (xy 30.991366 -460.066078) (xy 30.917482 -460.111825)
			(xy 30.839693 -460.150559) (xy 30.758661 -460.181951) (xy 30.675079 -460.205732) (xy 30.589659 -460.2217)
			(xy 30.50313 -460.229718) (xy 30.41623 -460.229718) (xy 30.329701 -460.2217) (xy 30.244281 -460.205732)
			(xy 30.160699 -460.181951) (xy 30.079667 -460.150559) (xy 30.001878 -460.111825) (xy 29.927994 -460.066078)
			(xy 29.858647 -460.013709) (xy 29.794427 -459.955165) (xy 29.735883 -459.890945) (xy 29.683514 -459.821598)
			(xy 29.637767 -459.747714) (xy 29.599033 -459.669925) (xy 29.567641 -459.588893) (xy 29.54386 -459.505311)
			(xy 29.527892 -459.419891) (xy 29.519874 -459.333362) (xy 1.27 -459.333362) (xy 1.27 -460.277972)
			(xy 27.258008 -460.277972) (xy 27.262079 -460.22235) (xy 27.274205 -460.167913) (xy 27.294128 -460.115822)
			(xy 27.321424 -460.067187) (xy 27.35551 -460.023044) (xy 27.395659 -459.984335) (xy 27.441017 -459.951884)
			(xy 27.490617 -459.926383) (xy 27.543401 -459.908376) (xy 27.598244 -459.898246) (xy 27.653978 -459.896209)
			(xy 27.709415 -459.902309) (xy 27.763372 -459.916415) (xy 27.814701 -459.938227) (xy 27.862307 -459.967281)
			(xy 27.905175 -460.002956) (xy 27.942392 -460.044493) (xy 27.973165 -460.091006) (xy 27.996837 -460.141503)
			(xy 28.012905 -460.19491) (xy 28.021025 -460.250086) (xy 28.021534 -460.277972) (xy 28.021025 -460.305858)
			(xy 28.012905 -460.361034) (xy 27.996837 -460.414441) (xy 27.973165 -460.464938) (xy 27.942392 -460.511451)
			(xy 27.905175 -460.552988) (xy 27.862307 -460.588663) (xy 27.814701 -460.617717) (xy 27.763372 -460.639529)
			(xy 27.709415 -460.653635) (xy 27.653978 -460.659735) (xy 27.598244 -460.657698) (xy 27.543401 -460.647568)
			(xy 27.490617 -460.629561) (xy 27.441017 -460.60406) (xy 27.395659 -460.571609) (xy 27.35551 -460.5329)
			(xy 27.321424 -460.488757) (xy 27.294128 -460.440122) (xy 27.274205 -460.388031) (xy 27.262079 -460.333594)
			(xy 27.258008 -460.277972) (xy 1.27 -460.277972) (xy 1.27 -461.740958) (xy 4.839198 -461.740958)
			(xy 4.839198 -461.647086) (xy 4.847159 -461.553552) (xy 4.863023 -461.46103) (xy 4.886677 -461.370187)
			(xy 4.917949 -461.281678) (xy 4.956615 -461.196139) (xy 5.002396 -461.114187) (xy 5.054962 -461.036413)
			(xy 5.113935 -460.963378) (xy 5.178888 -460.895606) (xy 5.249355 -460.833587) (xy 5.324828 -460.777768)
			(xy 5.404763 -460.72855) (xy 5.488584 -460.686288) (xy 5.575687 -460.651288) (xy 5.665444 -460.6238)
			(xy 5.757209 -460.604023) (xy 5.850321 -460.5921) (xy 5.944108 -460.588116) (xy 6.037895 -460.5921)
			(xy 6.131007 -460.604023) (xy 6.222772 -460.6238) (xy 6.312529 -460.651288) (xy 6.399632 -460.686288)
			(xy 6.483453 -460.72855) (xy 6.563388 -460.777768) (xy 6.638861 -460.833587) (xy 6.709328 -460.895606)
			(xy 6.774281 -460.963378) (xy 6.833254 -461.036413) (xy 6.88582 -461.114187) (xy 6.931601 -461.196139)
			(xy 6.970267 -461.281678) (xy 7.001539 -461.370187) (xy 7.025193 -461.46103) (xy 7.041057 -461.553552)
			(xy 7.049018 -461.647086) (xy 7.049516 -461.694022) (xy 7.049018 -461.740958) (xy 10.339314 -461.740958)
			(xy 10.339314 -461.647086) (xy 10.347275 -461.553552) (xy 10.363139 -461.46103) (xy 10.386793 -461.370187)
			(xy 10.418065 -461.281678) (xy 10.456731 -461.196139) (xy 10.502512 -461.114187) (xy 10.555078 -461.036413)
			(xy 10.614051 -460.963378) (xy 10.679004 -460.895606) (xy 10.749471 -460.833587) (xy 10.824944 -460.777768)
			(xy 10.904879 -460.72855) (xy 10.9887 -460.686288) (xy 11.075803 -460.651288) (xy 11.16556 -460.6238)
			(xy 11.257325 -460.604023) (xy 11.350437 -460.5921) (xy 11.444224 -460.588116) (xy 11.538011 -460.5921)
			(xy 11.631123 -460.604023) (xy 11.722888 -460.6238) (xy 11.812645 -460.651288) (xy 11.899748 -460.686288)
			(xy 11.983569 -460.72855) (xy 12.063504 -460.777768) (xy 12.138977 -460.833587) (xy 12.209444 -460.895606)
			(xy 12.274397 -460.963378) (xy 12.33337 -461.036413) (xy 12.354488 -461.067658) (xy 26.457908 -461.067658)
			(xy 26.461979 -461.012036) (xy 26.474105 -460.957599) (xy 26.494028 -460.905508) (xy 26.521324 -460.856873)
			(xy 26.55541 -460.81273) (xy 26.595559 -460.774021) (xy 26.640917 -460.74157) (xy 26.690517 -460.716069)
			(xy 26.743301 -460.698062) (xy 26.798144 -460.687932) (xy 26.853878 -460.685895) (xy 26.909315 -460.691995)
			(xy 26.963272 -460.706101) (xy 27.014601 -460.727913) (xy 27.062207 -460.756967) (xy 27.105075 -460.792642)
			(xy 27.142292 -460.834179) (xy 27.173065 -460.880692) (xy 27.196737 -460.931189) (xy 27.212805 -460.984596)
			(xy 27.220925 -461.039772) (xy 27.221434 -461.067658) (xy 27.220925 -461.095544) (xy 27.212805 -461.15072)
			(xy 27.196737 -461.204127) (xy 27.173065 -461.254624) (xy 27.142292 -461.301137) (xy 27.105075 -461.342674)
			(xy 27.062207 -461.378349) (xy 27.014601 -461.407403) (xy 26.963272 -461.429215) (xy 26.909315 -461.443321)
			(xy 26.853878 -461.449421) (xy 26.798144 -461.447384) (xy 26.743301 -461.437254) (xy 26.690517 -461.419247)
			(xy 26.640917 -461.393746) (xy 26.595559 -461.361295) (xy 26.55541 -461.322586) (xy 26.521324 -461.278443)
			(xy 26.494028 -461.229808) (xy 26.474105 -461.177717) (xy 26.461979 -461.12328) (xy 26.457908 -461.067658)
			(xy 12.354488 -461.067658) (xy 12.385936 -461.114187) (xy 12.431717 -461.196139) (xy 12.470383 -461.281678)
			(xy 12.501655 -461.370187) (xy 12.525309 -461.46103) (xy 12.541173 -461.553552) (xy 12.549134 -461.647086)
			(xy 12.549632 -461.694022) (xy 12.549134 -461.740958) (xy 12.541173 -461.834492) (xy 12.534508 -461.873362)
			(xy 29.519874 -461.873362) (xy 29.519874 -461.786462) (xy 29.527892 -461.699933) (xy 29.54386 -461.614513)
			(xy 29.567641 -461.530931) (xy 29.599033 -461.449899) (xy 29.637767 -461.37211) (xy 29.683514 -461.298226)
			(xy 29.735883 -461.228879) (xy 29.794427 -461.164659) (xy 29.858647 -461.106115) (xy 29.927994 -461.053746)
			(xy 30.001878 -461.007999) (xy 30.079667 -460.969265) (xy 30.160699 -460.937873) (xy 30.244281 -460.914092)
			(xy 30.329701 -460.898124) (xy 30.41623 -460.890106) (xy 30.50313 -460.890106) (xy 30.589659 -460.898124)
			(xy 30.675079 -460.914092) (xy 30.758661 -460.937873) (xy 30.839693 -460.969265) (xy 30.917482 -461.007999)
			(xy 30.991366 -461.053746) (xy 31.060713 -461.106115) (xy 31.124933 -461.164659) (xy 31.183477 -461.228879)
			(xy 31.235846 -461.298226) (xy 31.281593 -461.37211) (xy 31.320327 -461.449899) (xy 31.351719 -461.530931)
			(xy 31.3755 -461.614513) (xy 31.391468 -461.699933) (xy 31.399486 -461.786462) (xy 31.399988 -461.829912)
			(xy 31.399486 -461.873362) (xy 34.599874 -461.873362) (xy 34.599874 -461.786462) (xy 34.607892 -461.699933)
			(xy 34.62386 -461.614513) (xy 34.647641 -461.530931) (xy 34.679033 -461.449899) (xy 34.717767 -461.37211)
			(xy 34.763514 -461.298226) (xy 34.815883 -461.228879) (xy 34.874427 -461.164659) (xy 34.938647 -461.106115)
			(xy 35.007994 -461.053746) (xy 35.081878 -461.007999) (xy 35.159667 -460.969265) (xy 35.240699 -460.937873)
			(xy 35.324281 -460.914092) (xy 35.409701 -460.898124) (xy 35.49623 -460.890106) (xy 35.58313 -460.890106)
			(xy 35.669659 -460.898124) (xy 35.755079 -460.914092) (xy 35.838661 -460.937873) (xy 35.919693 -460.969265)
			(xy 35.997482 -461.007999) (xy 36.071366 -461.053746) (xy 36.140713 -461.106115) (xy 36.204933 -461.164659)
			(xy 36.210052 -461.170274) (xy 41.083482 -461.170274) (xy 41.087553 -461.114652) (xy 41.099679 -461.060215)
			(xy 41.119602 -461.008124) (xy 41.146898 -460.959489) (xy 41.180984 -460.915346) (xy 41.221133 -460.876637)
			(xy 41.266491 -460.844186) (xy 41.316091 -460.818685) (xy 41.368875 -460.800678) (xy 41.423718 -460.790548)
			(xy 41.479452 -460.788511) (xy 41.534889 -460.794611) (xy 41.588846 -460.808717) (xy 41.640175 -460.830529)
			(xy 41.687781 -460.859583) (xy 41.730649 -460.895258) (xy 41.767866 -460.936795) (xy 41.798639 -460.983308)
			(xy 41.822311 -461.033805) (xy 41.838379 -461.087212) (xy 41.846499 -461.142388) (xy 41.847008 -461.170274)
			(xy 41.846499 -461.19816) (xy 41.838379 -461.253336) (xy 41.822311 -461.306743) (xy 41.798639 -461.35724)
			(xy 41.767866 -461.403753) (xy 41.730649 -461.44529) (xy 41.687781 -461.480965) (xy 41.640175 -461.510019)
			(xy 41.588846 -461.531831) (xy 41.534889 -461.545937) (xy 41.479452 -461.552037) (xy 41.423718 -461.55)
			(xy 41.368875 -461.53987) (xy 41.316091 -461.521863) (xy 41.266491 -461.496362) (xy 41.221133 -461.463911)
			(xy 41.180984 -461.425202) (xy 41.146898 -461.381059) (xy 41.119602 -461.332424) (xy 41.099679 -461.280333)
			(xy 41.087553 -461.225896) (xy 41.083482 -461.170274) (xy 36.210052 -461.170274) (xy 36.263477 -461.228879)
			(xy 36.315846 -461.298226) (xy 36.361593 -461.37211) (xy 36.400327 -461.449899) (xy 36.431719 -461.530931)
			(xy 36.4555 -461.614513) (xy 36.471468 -461.699933) (xy 36.479486 -461.786462) (xy 36.479988 -461.829912)
			(xy 36.479486 -461.873362) (xy 36.471468 -461.959891) (xy 36.4555 -462.045311) (xy 36.431719 -462.128893)
			(xy 36.400327 -462.209925) (xy 36.361593 -462.287714) (xy 36.315846 -462.361598) (xy 36.263477 -462.430945)
			(xy 36.204933 -462.495165) (xy 36.140713 -462.553709) (xy 36.071366 -462.606078) (xy 35.997482 -462.651825)
			(xy 35.919693 -462.690559) (xy 35.838661 -462.721951) (xy 35.755079 -462.745732) (xy 35.669659 -462.7617)
			(xy 35.58313 -462.769718) (xy 35.49623 -462.769718) (xy 35.409701 -462.7617) (xy 35.324281 -462.745732)
			(xy 35.240699 -462.721951) (xy 35.159667 -462.690559) (xy 35.081878 -462.651825) (xy 35.007994 -462.606078)
			(xy 34.938647 -462.553709) (xy 34.874427 -462.495165) (xy 34.815883 -462.430945) (xy 34.763514 -462.361598)
			(xy 34.717767 -462.287714) (xy 34.679033 -462.209925) (xy 34.647641 -462.128893) (xy 34.62386 -462.045311)
			(xy 34.607892 -461.959891) (xy 34.599874 -461.873362) (xy 31.399486 -461.873362) (xy 31.391468 -461.959891)
			(xy 31.3755 -462.045311) (xy 31.351719 -462.128893) (xy 31.320327 -462.209925) (xy 31.281593 -462.287714)
			(xy 31.235846 -462.361598) (xy 31.183477 -462.430945) (xy 31.124933 -462.495165) (xy 31.060713 -462.553709)
			(xy 30.991366 -462.606078) (xy 30.917482 -462.651825) (xy 30.839693 -462.690559) (xy 30.758661 -462.721951)
			(xy 30.675079 -462.745732) (xy 30.589659 -462.7617) (xy 30.50313 -462.769718) (xy 30.41623 -462.769718)
			(xy 30.329701 -462.7617) (xy 30.244281 -462.745732) (xy 30.160699 -462.721951) (xy 30.079667 -462.690559)
			(xy 30.001878 -462.651825) (xy 29.927994 -462.606078) (xy 29.858647 -462.553709) (xy 29.794427 -462.495165)
			(xy 29.735883 -462.430945) (xy 29.683514 -462.361598) (xy 29.637767 -462.287714) (xy 29.599033 -462.209925)
			(xy 29.567641 -462.128893) (xy 29.54386 -462.045311) (xy 29.527892 -461.959891) (xy 29.519874 -461.873362)
			(xy 12.534508 -461.873362) (xy 12.525309 -461.927014) (xy 12.501655 -462.017857) (xy 12.470383 -462.106366)
			(xy 12.431717 -462.191905) (xy 12.385936 -462.273857) (xy 12.33337 -462.351631) (xy 12.274397 -462.424666)
			(xy 12.209444 -462.492438) (xy 12.138977 -462.554457) (xy 12.063504 -462.610276) (xy 11.983569 -462.659494)
			(xy 11.899748 -462.701756) (xy 11.812645 -462.736756) (xy 11.722888 -462.764244) (xy 11.631123 -462.784021)
			(xy 11.538011 -462.795944) (xy 11.444224 -462.799929) (xy 11.350437 -462.795944) (xy 11.257325 -462.784021)
			(xy 11.16556 -462.764244) (xy 11.075803 -462.736756) (xy 10.9887 -462.701756) (xy 10.904879 -462.659494)
			(xy 10.824944 -462.610276) (xy 10.749471 -462.554457) (xy 10.679004 -462.492438) (xy 10.614051 -462.424666)
			(xy 10.555078 -462.351631) (xy 10.502512 -462.273857) (xy 10.456731 -462.191905) (xy 10.418065 -462.106366)
			(xy 10.386793 -462.017857) (xy 10.363139 -461.927014) (xy 10.347275 -461.834492) (xy 10.339314 -461.740958)
			(xy 7.049018 -461.740958) (xy 7.041057 -461.834492) (xy 7.025193 -461.927014) (xy 7.001539 -462.017857)
			(xy 6.970267 -462.106366) (xy 6.931601 -462.191905) (xy 6.88582 -462.273857) (xy 6.833254 -462.351631)
			(xy 6.774281 -462.424666) (xy 6.709328 -462.492438) (xy 6.638861 -462.554457) (xy 6.563388 -462.610276)
			(xy 6.483453 -462.659494) (xy 6.399632 -462.701756) (xy 6.312529 -462.736756) (xy 6.222772 -462.764244)
			(xy 6.131007 -462.784021) (xy 6.037895 -462.795944) (xy 5.944108 -462.799929) (xy 5.850321 -462.795944)
			(xy 5.757209 -462.784021) (xy 5.665444 -462.764244) (xy 5.575687 -462.736756) (xy 5.488584 -462.701756)
			(xy 5.404763 -462.659494) (xy 5.324828 -462.610276) (xy 5.249355 -462.554457) (xy 5.178888 -462.492438)
			(xy 5.113935 -462.424666) (xy 5.054962 -462.351631) (xy 5.002396 -462.273857) (xy 4.956615 -462.191905)
			(xy 4.917949 -462.106366) (xy 4.886677 -462.017857) (xy 4.863023 -461.927014) (xy 4.847159 -461.834492)
			(xy 4.839198 -461.740958) (xy 1.27 -461.740958) (xy 1.27 -463.41538) (xy 27.258008 -463.41538) (xy 27.262079 -463.359758)
			(xy 27.274205 -463.305321) (xy 27.294128 -463.25323) (xy 27.321424 -463.204595) (xy 27.35551 -463.160452)
			(xy 27.395659 -463.121743) (xy 27.441017 -463.089292) (xy 27.490617 -463.063791) (xy 27.543401 -463.045784)
			(xy 27.598244 -463.035654) (xy 27.653978 -463.033617) (xy 27.709415 -463.039717) (xy 27.763372 -463.053823)
			(xy 27.814701 -463.075635) (xy 27.862307 -463.104689) (xy 27.904994 -463.140213) (xy 47.82311 -463.140213)
			(xy 47.82311 -463.059103) (xy 47.83106 -462.978384) (xy 47.846883 -462.898833) (xy 47.870428 -462.821217)
			(xy 47.901467 -462.746281) (xy 47.939702 -462.674749) (xy 47.984764 -462.607309) (xy 48.036219 -462.54461)
			(xy 48.093572 -462.487257) (xy 48.156271 -462.435802) (xy 48.223711 -462.39074) (xy 48.295243 -462.352505)
			(xy 48.370179 -462.321466) (xy 48.447795 -462.297921) (xy 48.527346 -462.282098) (xy 48.608065 -462.274148)
			(xy 48.689175 -462.274148) (xy 48.769894 -462.282098) (xy 48.849445 -462.297921) (xy 48.927061 -462.321466)
			(xy 49.001997 -462.352505) (xy 49.073529 -462.39074) (xy 49.140969 -462.435802) (xy 49.203668 -462.487257)
			(xy 49.261021 -462.54461) (xy 49.312476 -462.607309) (xy 49.357538 -462.674749) (xy 49.395773 -462.746281)
			(xy 49.426812 -462.821217) (xy 49.450357 -462.898833) (xy 49.46618 -462.978384) (xy 49.47413 -463.059103)
			(xy 49.474628 -463.099658) (xy 49.47413 -463.140213) (xy 51.32323 -463.140213) (xy 51.32323 -463.059103)
			(xy 51.33118 -462.978384) (xy 51.347003 -462.898833) (xy 51.370548 -462.821217) (xy 51.401587 -462.746281)
			(xy 51.439822 -462.674749) (xy 51.484884 -462.607309) (xy 51.536339 -462.54461) (xy 51.593692 -462.487257)
			(xy 51.656391 -462.435802) (xy 51.723831 -462.39074) (xy 51.795363 -462.352505) (xy 51.870299 -462.321466)
			(xy 51.947915 -462.297921) (xy 52.027466 -462.282098) (xy 52.108185 -462.274148) (xy 52.189295 -462.274148)
			(xy 52.270014 -462.282098) (xy 52.349565 -462.297921) (xy 52.427181 -462.321466) (xy 52.502117 -462.352505)
			(xy 52.573649 -462.39074) (xy 52.641089 -462.435802) (xy 52.703788 -462.487257) (xy 52.761141 -462.54461)
			(xy 52.812596 -462.607309) (xy 52.857658 -462.674749) (xy 52.895893 -462.746281) (xy 52.926932 -462.821217)
			(xy 52.950477 -462.898833) (xy 52.9663 -462.978384) (xy 52.97425 -463.059103) (xy 52.974748 -463.099658)
			(xy 52.97425 -463.140213) (xy 52.9663 -463.220932) (xy 52.950477 -463.300483) (xy 52.926932 -463.378099)
			(xy 52.895893 -463.453035) (xy 52.857658 -463.524567) (xy 52.812596 -463.592007) (xy 52.761141 -463.654706)
			(xy 52.703788 -463.712059) (xy 52.641089 -463.763514) (xy 52.573649 -463.808576) (xy 52.502117 -463.846811)
			(xy 52.427181 -463.87785) (xy 52.349565 -463.901395) (xy 52.270014 -463.917218) (xy 52.189295 -463.925168)
			(xy 52.108185 -463.925168) (xy 52.027466 -463.917218) (xy 51.947915 -463.901395) (xy 51.870299 -463.87785)
			(xy 51.795363 -463.846811) (xy 51.723831 -463.808576) (xy 51.656391 -463.763514) (xy 51.593692 -463.712059)
			(xy 51.536339 -463.654706) (xy 51.484884 -463.592007) (xy 51.439822 -463.524567) (xy 51.401587 -463.453035)
			(xy 51.370548 -463.378099) (xy 51.347003 -463.300483) (xy 51.33118 -463.220932) (xy 51.32323 -463.140213)
			(xy 49.47413 -463.140213) (xy 49.46618 -463.220932) (xy 49.450357 -463.300483) (xy 49.426812 -463.378099)
			(xy 49.395773 -463.453035) (xy 49.357538 -463.524567) (xy 49.312476 -463.592007) (xy 49.261021 -463.654706)
			(xy 49.203668 -463.712059) (xy 49.140969 -463.763514) (xy 49.073529 -463.808576) (xy 49.001997 -463.846811)
			(xy 48.927061 -463.87785) (xy 48.849445 -463.901395) (xy 48.769894 -463.917218) (xy 48.689175 -463.925168)
			(xy 48.608065 -463.925168) (xy 48.527346 -463.917218) (xy 48.447795 -463.901395) (xy 48.370179 -463.87785)
			(xy 48.295243 -463.846811) (xy 48.223711 -463.808576) (xy 48.156271 -463.763514) (xy 48.093572 -463.712059)
			(xy 48.036219 -463.654706) (xy 47.984764 -463.592007) (xy 47.939702 -463.524567) (xy 47.901467 -463.453035)
			(xy 47.870428 -463.378099) (xy 47.846883 -463.300483) (xy 47.83106 -463.220932) (xy 47.82311 -463.140213)
			(xy 27.904994 -463.140213) (xy 27.905175 -463.140364) (xy 27.942392 -463.181901) (xy 27.973165 -463.228414)
			(xy 27.996837 -463.278911) (xy 28.012905 -463.332318) (xy 28.021025 -463.387494) (xy 28.021534 -463.41538)
			(xy 28.021025 -463.443266) (xy 28.012905 -463.498442) (xy 27.996837 -463.551849) (xy 27.973165 -463.602346)
			(xy 27.942392 -463.648859) (xy 27.905175 -463.690396) (xy 27.862307 -463.726071) (xy 27.814701 -463.755125)
			(xy 27.763372 -463.776937) (xy 27.709415 -463.791043) (xy 27.653978 -463.797143) (xy 27.598244 -463.795106)
			(xy 27.543401 -463.784976) (xy 27.490617 -463.766969) (xy 27.441017 -463.741468) (xy 27.395659 -463.709017)
			(xy 27.35551 -463.670308) (xy 27.321424 -463.626165) (xy 27.294128 -463.57753) (xy 27.274205 -463.525439)
			(xy 27.262079 -463.471002) (xy 27.258008 -463.41538) (xy 1.27 -463.41538) (xy 1.27 -464.413362) (xy 29.519874 -464.413362)
			(xy 29.519874 -464.326462) (xy 29.527892 -464.239933) (xy 29.54386 -464.154513) (xy 29.567641 -464.070931)
			(xy 29.599033 -463.989899) (xy 29.637767 -463.91211) (xy 29.683514 -463.838226) (xy 29.735883 -463.768879)
			(xy 29.794427 -463.704659) (xy 29.858647 -463.646115) (xy 29.927994 -463.593746) (xy 30.001878 -463.547999)
			(xy 30.079667 -463.509265) (xy 30.160699 -463.477873) (xy 30.244281 -463.454092) (xy 30.329701 -463.438124)
			(xy 30.41623 -463.430106) (xy 30.50313 -463.430106) (xy 30.589659 -463.438124) (xy 30.675079 -463.454092)
			(xy 30.758661 -463.477873) (xy 30.839693 -463.509265) (xy 30.917482 -463.547999) (xy 30.991366 -463.593746)
			(xy 31.060713 -463.646115) (xy 31.124933 -463.704659) (xy 31.183477 -463.768879) (xy 31.235846 -463.838226)
			(xy 31.281593 -463.91211) (xy 31.320327 -463.989899) (xy 31.351719 -464.070931) (xy 31.3755 -464.154513)
			(xy 31.391468 -464.239933) (xy 31.399486 -464.326462) (xy 31.399988 -464.369912) (xy 31.399486 -464.413362)
			(xy 34.599874 -464.413362) (xy 34.599874 -464.326462) (xy 34.607892 -464.239933) (xy 34.62386 -464.154513)
			(xy 34.647641 -464.070931) (xy 34.679033 -463.989899) (xy 34.717767 -463.91211) (xy 34.763514 -463.838226)
			(xy 34.815883 -463.768879) (xy 34.874427 -463.704659) (xy 34.938647 -463.646115) (xy 35.007994 -463.593746)
			(xy 35.081878 -463.547999) (xy 35.159667 -463.509265) (xy 35.240699 -463.477873) (xy 35.324281 -463.454092)
			(xy 35.409701 -463.438124) (xy 35.49623 -463.430106) (xy 35.58313 -463.430106) (xy 35.669659 -463.438124)
			(xy 35.755079 -463.454092) (xy 35.838661 -463.477873) (xy 35.919693 -463.509265) (xy 35.997482 -463.547999)
			(xy 36.036403 -463.572098) (xy 40.023032 -463.572098) (xy 40.027103 -463.516476) (xy 40.039229 -463.462039)
			(xy 40.059152 -463.409948) (xy 40.086448 -463.361313) (xy 40.120534 -463.31717) (xy 40.160683 -463.278461)
			(xy 40.206041 -463.24601) (xy 40.255641 -463.220509) (xy 40.308425 -463.202502) (xy 40.363268 -463.192372)
			(xy 40.419002 -463.190335) (xy 40.474439 -463.196435) (xy 40.528396 -463.210541) (xy 40.579725 -463.232353)
			(xy 40.627331 -463.261407) (xy 40.670199 -463.297082) (xy 40.707416 -463.338619) (xy 40.738189 -463.385132)
			(xy 40.761861 -463.435629) (xy 40.777929 -463.489036) (xy 40.786049 -463.544212) (xy 40.786558 -463.572098)
			(xy 40.786049 -463.599984) (xy 40.777929 -463.65516) (xy 40.761861 -463.708567) (xy 40.738189 -463.759064)
			(xy 40.707416 -463.805577) (xy 40.670199 -463.847114) (xy 40.627331 -463.882789) (xy 40.579725 -463.911843)
			(xy 40.528396 -463.933655) (xy 40.474439 -463.947761) (xy 40.419002 -463.953861) (xy 40.363268 -463.951824)
			(xy 40.308425 -463.941694) (xy 40.255641 -463.923687) (xy 40.206041 -463.898186) (xy 40.160683 -463.865735)
			(xy 40.120534 -463.827026) (xy 40.086448 -463.782883) (xy 40.059152 -463.734248) (xy 40.039229 -463.682157)
			(xy 40.027103 -463.62772) (xy 40.023032 -463.572098) (xy 36.036403 -463.572098) (xy 36.071366 -463.593746)
			(xy 36.140713 -463.646115) (xy 36.204933 -463.704659) (xy 36.263477 -463.768879) (xy 36.315846 -463.838226)
			(xy 36.361593 -463.91211) (xy 36.400327 -463.989899) (xy 36.431719 -464.070931) (xy 36.4555 -464.154513)
			(xy 36.471468 -464.239933) (xy 36.479486 -464.326462) (xy 36.479988 -464.369912) (xy 36.479486 -464.413362)
			(xy 36.471468 -464.499891) (xy 36.4555 -464.585311) (xy 36.432087 -464.6676) (xy 72.420224 -464.6676)
			(xy 72.424295 -464.611978) (xy 72.436421 -464.557541) (xy 72.456344 -464.50545) (xy 72.48364 -464.456815)
			(xy 72.517726 -464.412672) (xy 72.557875 -464.373963) (xy 72.603233 -464.341512) (xy 72.652833 -464.316011)
			(xy 72.705617 -464.298004) (xy 72.76046 -464.287874) (xy 72.816194 -464.285837) (xy 72.871631 -464.291937)
			(xy 72.925588 -464.306043) (xy 72.976917 -464.327855) (xy 73.024523 -464.356909) (xy 73.067391 -464.392584)
			(xy 73.104608 -464.434121) (xy 73.135381 -464.480634) (xy 73.159053 -464.531131) (xy 73.175121 -464.584538)
			(xy 73.183241 -464.639714) (xy 73.18375 -464.6676) (xy 73.183241 -464.695486) (xy 73.175121 -464.750662)
			(xy 73.166028 -464.780884) (xy 73.671682 -464.780884) (xy 73.675753 -464.725262) (xy 73.687879 -464.670825)
			(xy 73.707802 -464.618734) (xy 73.735098 -464.570099) (xy 73.769184 -464.525956) (xy 73.809333 -464.487247)
			(xy 73.854691 -464.454796) (xy 73.904291 -464.429295) (xy 73.957075 -464.411288) (xy 74.011918 -464.401158)
			(xy 74.067652 -464.399121) (xy 74.123089 -464.405221) (xy 74.177046 -464.419327) (xy 74.228375 -464.441139)
			(xy 74.275981 -464.470193) (xy 74.318849 -464.505868) (xy 74.356066 -464.547405) (xy 74.386839 -464.593918)
			(xy 74.410511 -464.644415) (xy 74.426579 -464.697822) (xy 74.434699 -464.752998) (xy 74.435208 -464.780884)
			(xy 74.434699 -464.80877) (xy 74.426579 -464.863946) (xy 74.410511 -464.917353) (xy 74.386839 -464.96785)
			(xy 74.356066 -465.014363) (xy 74.318849 -465.0559) (xy 74.275981 -465.091575) (xy 74.228375 -465.120629)
			(xy 74.177046 -465.142441) (xy 74.123089 -465.156547) (xy 74.067652 -465.162647) (xy 74.011918 -465.16061)
			(xy 73.957075 -465.15048) (xy 73.904291 -465.132473) (xy 73.854691 -465.106972) (xy 73.809333 -465.074521)
			(xy 73.769184 -465.035812) (xy 73.735098 -464.991669) (xy 73.707802 -464.943034) (xy 73.687879 -464.890943)
			(xy 73.675753 -464.836506) (xy 73.671682 -464.780884) (xy 73.166028 -464.780884) (xy 73.159053 -464.804069)
			(xy 73.135381 -464.854566) (xy 73.104608 -464.901079) (xy 73.067391 -464.942616) (xy 73.024523 -464.978291)
			(xy 72.976917 -465.007345) (xy 72.925588 -465.029157) (xy 72.871631 -465.043263) (xy 72.816194 -465.049363)
			(xy 72.76046 -465.047326) (xy 72.705617 -465.037196) (xy 72.652833 -465.019189) (xy 72.603233 -464.993688)
			(xy 72.557875 -464.961237) (xy 72.517726 -464.922528) (xy 72.48364 -464.878385) (xy 72.456344 -464.82975)
			(xy 72.436421 -464.777659) (xy 72.424295 -464.723222) (xy 72.420224 -464.6676) (xy 36.432087 -464.6676)
			(xy 36.431719 -464.668893) (xy 36.400327 -464.749925) (xy 36.361593 -464.827714) (xy 36.315846 -464.901598)
			(xy 36.263477 -464.970945) (xy 36.204933 -465.035165) (xy 36.140713 -465.093709) (xy 36.071366 -465.146078)
			(xy 36.031891 -465.17052) (xy 40.21277 -465.17052) (xy 40.216841 -465.114898) (xy 40.228967 -465.060461)
			(xy 40.24889 -465.00837) (xy 40.276186 -464.959735) (xy 40.310272 -464.915592) (xy 40.350421 -464.876883)
			(xy 40.395779 -464.844432) (xy 40.445379 -464.818931) (xy 40.498163 -464.800924) (xy 40.553006 -464.790794)
			(xy 40.60874 -464.788757) (xy 40.664177 -464.794857) (xy 40.718134 -464.808963) (xy 40.769463 -464.830775)
			(xy 40.817069 -464.859829) (xy 40.859937 -464.895504) (xy 40.897154 -464.937041) (xy 40.927927 -464.983554)
			(xy 40.951599 -465.034051) (xy 40.967667 -465.087458) (xy 40.975787 -465.142634) (xy 40.976296 -465.17052)
			(xy 40.975787 -465.198406) (xy 40.967667 -465.253582) (xy 40.951599 -465.306989) (xy 40.927927 -465.357486)
			(xy 40.897154 -465.403999) (xy 40.859937 -465.445536) (xy 40.817069 -465.481211) (xy 40.769463 -465.510265)
			(xy 40.718134 -465.532077) (xy 40.664177 -465.546183) (xy 40.60874 -465.552283) (xy 40.553006 -465.550246)
			(xy 40.498163 -465.540116) (xy 40.445379 -465.522109) (xy 40.395779 -465.496608) (xy 40.350421 -465.464157)
			(xy 40.310272 -465.425448) (xy 40.276186 -465.381305) (xy 40.24889 -465.33267) (xy 40.228967 -465.280579)
			(xy 40.216841 -465.226142) (xy 40.21277 -465.17052) (xy 36.031891 -465.17052) (xy 35.997482 -465.191825)
			(xy 35.919693 -465.230559) (xy 35.838661 -465.261951) (xy 35.755079 -465.285732) (xy 35.669659 -465.3017)
			(xy 35.58313 -465.309718) (xy 35.49623 -465.309718) (xy 35.409701 -465.3017) (xy 35.324281 -465.285732)
			(xy 35.240699 -465.261951) (xy 35.159667 -465.230559) (xy 35.081878 -465.191825) (xy 35.007994 -465.146078)
			(xy 34.938647 -465.093709) (xy 34.874427 -465.035165) (xy 34.815883 -464.970945) (xy 34.763514 -464.901598)
			(xy 34.717767 -464.827714) (xy 34.679033 -464.749925) (xy 34.647641 -464.668893) (xy 34.62386 -464.585311)
			(xy 34.607892 -464.499891) (xy 34.599874 -464.413362) (xy 31.399486 -464.413362) (xy 31.391468 -464.499891)
			(xy 31.3755 -464.585311) (xy 31.351719 -464.668893) (xy 31.320327 -464.749925) (xy 31.281593 -464.827714)
			(xy 31.235846 -464.901598) (xy 31.183477 -464.970945) (xy 31.124933 -465.035165) (xy 31.060713 -465.093709)
			(xy 30.991366 -465.146078) (xy 30.917482 -465.191825) (xy 30.839693 -465.230559) (xy 30.758661 -465.261951)
			(xy 30.675079 -465.285732) (xy 30.589659 -465.3017) (xy 30.50313 -465.309718) (xy 30.41623 -465.309718)
			(xy 30.329701 -465.3017) (xy 30.244281 -465.285732) (xy 30.160699 -465.261951) (xy 30.079667 -465.230559)
			(xy 30.001878 -465.191825) (xy 29.927994 -465.146078) (xy 29.858647 -465.093709) (xy 29.794427 -465.035165)
			(xy 29.735883 -464.970945) (xy 29.683514 -464.901598) (xy 29.637767 -464.827714) (xy 29.599033 -464.749925)
			(xy 29.567641 -464.668893) (xy 29.54386 -464.585311) (xy 29.527892 -464.499891) (xy 29.519874 -464.413362)
			(xy 1.27 -464.413362) (xy 1.27 -466.953362) (xy 29.519874 -466.953362) (xy 29.519874 -466.866462)
			(xy 29.527892 -466.779933) (xy 29.54386 -466.694513) (xy 29.567641 -466.610931) (xy 29.599033 -466.529899)
			(xy 29.637767 -466.45211) (xy 29.683514 -466.378226) (xy 29.735883 -466.308879) (xy 29.794427 -466.244659)
			(xy 29.858647 -466.186115) (xy 29.927994 -466.133746) (xy 30.001878 -466.087999) (xy 30.079667 -466.049265)
			(xy 30.160699 -466.017873) (xy 30.244281 -465.994092) (xy 30.329701 -465.978124) (xy 30.41623 -465.970106)
			(xy 30.50313 -465.970106) (xy 30.589659 -465.978124) (xy 30.675079 -465.994092) (xy 30.758661 -466.017873)
			(xy 30.839693 -466.049265) (xy 30.917482 -466.087999) (xy 30.991366 -466.133746) (xy 31.060713 -466.186115)
			(xy 31.124933 -466.244659) (xy 31.183477 -466.308879) (xy 31.235846 -466.378226) (xy 31.281593 -466.45211)
			(xy 31.320327 -466.529899) (xy 31.351719 -466.610931) (xy 31.3755 -466.694513) (xy 31.391468 -466.779933)
			(xy 31.399486 -466.866462) (xy 31.399988 -466.909912) (xy 31.399486 -466.953362) (xy 34.599874 -466.953362)
			(xy 34.599874 -466.866462) (xy 34.607892 -466.779933) (xy 34.62386 -466.694513) (xy 34.647641 -466.610931)
			(xy 34.679033 -466.529899) (xy 34.717767 -466.45211) (xy 34.763514 -466.378226) (xy 34.815883 -466.308879)
			(xy 34.874427 -466.244659) (xy 34.938647 -466.186115) (xy 35.007994 -466.133746) (xy 35.081878 -466.087999)
			(xy 35.159667 -466.049265) (xy 35.240699 -466.017873) (xy 35.324281 -465.994092) (xy 35.409701 -465.978124)
			(xy 35.49623 -465.970106) (xy 35.58313 -465.970106) (xy 35.669659 -465.978124) (xy 35.682508 -465.980526)
			(xy 71.008746 -465.980526) (xy 71.012817 -465.924904) (xy 71.024943 -465.870467) (xy 71.044866 -465.818376)
			(xy 71.072162 -465.769741) (xy 71.106248 -465.725598) (xy 71.146397 -465.686889) (xy 71.191755 -465.654438)
			(xy 71.241355 -465.628937) (xy 71.294139 -465.61093) (xy 71.348982 -465.6008) (xy 71.404716 -465.598763)
			(xy 71.460153 -465.604863) (xy 71.51411 -465.618969) (xy 71.565439 -465.640781) (xy 71.613045 -465.669835)
			(xy 71.655913 -465.70551) (xy 71.69313 -465.747047) (xy 71.723903 -465.79356) (xy 71.747575 -465.844057)
			(xy 71.763643 -465.897464) (xy 71.771763 -465.95264) (xy 71.772272 -465.980526) (xy 71.771763 -466.008412)
			(xy 71.763643 -466.063588) (xy 71.747575 -466.116995) (xy 71.723903 -466.167492) (xy 71.69313 -466.214005)
			(xy 71.655913 -466.255542) (xy 71.613045 -466.291217) (xy 71.565439 -466.320271) (xy 71.51411 -466.342083)
			(xy 71.460153 -466.356189) (xy 71.404716 -466.362289) (xy 71.348982 -466.360252) (xy 71.294139 -466.350122)
			(xy 71.241355 -466.332115) (xy 71.191755 -466.306614) (xy 71.146397 -466.274163) (xy 71.106248 -466.235454)
			(xy 71.072162 -466.191311) (xy 71.044866 -466.142676) (xy 71.024943 -466.090585) (xy 71.012817 -466.036148)
			(xy 71.008746 -465.980526) (xy 35.682508 -465.980526) (xy 35.755079 -465.994092) (xy 35.838661 -466.017873)
			(xy 35.919693 -466.049265) (xy 35.997482 -466.087999) (xy 36.071366 -466.133746) (xy 36.140713 -466.186115)
			(xy 36.204933 -466.244659) (xy 36.263477 -466.308879) (xy 36.315846 -466.378226) (xy 36.361593 -466.45211)
			(xy 36.400327 -466.529899) (xy 36.431719 -466.610931) (xy 36.4555 -466.694513) (xy 36.471468 -466.779933)
			(xy 36.479486 -466.866462) (xy 36.479988 -466.909912) (xy 36.479486 -466.953362) (xy 36.471468 -467.039891)
			(xy 36.4555 -467.125311) (xy 36.431719 -467.208893) (xy 36.400327 -467.289925) (xy 36.361593 -467.367714)
			(xy 36.315846 -467.441598) (xy 36.263477 -467.510945) (xy 36.204933 -467.575165) (xy 36.140713 -467.633709)
			(xy 36.071366 -467.686078) (xy 35.997482 -467.731825) (xy 35.919693 -467.770559) (xy 35.838661 -467.801951)
			(xy 35.755079 -467.825732) (xy 35.669659 -467.8417) (xy 35.58313 -467.849718) (xy 35.49623 -467.849718)
			(xy 35.409701 -467.8417) (xy 35.324281 -467.825732) (xy 35.240699 -467.801951) (xy 35.159667 -467.770559)
			(xy 35.081878 -467.731825) (xy 35.007994 -467.686078) (xy 34.938647 -467.633709) (xy 34.874427 -467.575165)
			(xy 34.815883 -467.510945) (xy 34.763514 -467.441598) (xy 34.717767 -467.367714) (xy 34.679033 -467.289925)
			(xy 34.647641 -467.208893) (xy 34.62386 -467.125311) (xy 34.607892 -467.039891) (xy 34.599874 -466.953362)
			(xy 31.399486 -466.953362) (xy 31.391468 -467.039891) (xy 31.3755 -467.125311) (xy 31.351719 -467.208893)
			(xy 31.320327 -467.289925) (xy 31.281593 -467.367714) (xy 31.235846 -467.441598) (xy 31.183477 -467.510945)
			(xy 31.124933 -467.575165) (xy 31.060713 -467.633709) (xy 30.991366 -467.686078) (xy 30.917482 -467.731825)
			(xy 30.839693 -467.770559) (xy 30.758661 -467.801951) (xy 30.675079 -467.825732) (xy 30.589659 -467.8417)
			(xy 30.50313 -467.849718) (xy 30.41623 -467.849718) (xy 30.329701 -467.8417) (xy 30.244281 -467.825732)
			(xy 30.160699 -467.801951) (xy 30.079667 -467.770559) (xy 30.001878 -467.731825) (xy 29.927994 -467.686078)
			(xy 29.858647 -467.633709) (xy 29.794427 -467.575165) (xy 29.735883 -467.510945) (xy 29.683514 -467.441598)
			(xy 29.637767 -467.367714) (xy 29.599033 -467.289925) (xy 29.567641 -467.208893) (xy 29.54386 -467.125311)
			(xy 29.527892 -467.039891) (xy 29.519874 -466.953362) (xy 1.27 -466.953362) (xy 1.27 -471.172032)
			(xy 6.671831 -471.172032) (xy 6.675786 -471.080195) (xy 6.687621 -470.989038) (xy 6.707248 -470.899235)
			(xy 6.734522 -470.811453) (xy 6.769242 -470.726339) (xy 6.81115 -470.644526) (xy 6.859936 -470.566618)
			(xy 6.915239 -470.493193) (xy 6.976649 -470.424793) (xy 7.043711 -470.361926) (xy 7.11593 -470.305056)
			(xy 7.19277 -470.254605) (xy 7.273663 -470.210946) (xy 7.358009 -470.174403) (xy 7.445185 -470.145246)
			(xy 7.534544 -470.123692) (xy 7.625425 -470.109898) (xy 7.717156 -470.103968) (xy 7.809057 -470.105946)
			(xy 7.900448 -470.115817) (xy 7.990652 -470.133507) (xy 8.079001 -470.158887) (xy 8.164841 -470.191767)
			(xy 8.247537 -470.231905) (xy 8.326477 -470.279004) (xy 8.401075 -470.332714) (xy 8.470781 -470.392638)
			(xy 8.535076 -470.458332) (xy 8.593487 -470.52931) (xy 8.645579 -470.605047) (xy 8.690968 -470.684982)
			(xy 8.729318 -470.768522) (xy 8.760343 -470.85505) (xy 8.783816 -470.943925) (xy 8.799562 -471.034489)
			(xy 8.807464 -471.126071) (xy 8.807958 -471.172032) (xy 8.807464 -471.217993) (xy 8.799562 -471.309575)
			(xy 8.783816 -471.400139) (xy 8.760343 -471.489014) (xy 8.729318 -471.575542) (xy 8.690968 -471.659082)
			(xy 8.645579 -471.739017) (xy 8.593487 -471.814754) (xy 8.535076 -471.885732) (xy 8.470781 -471.951426)
			(xy 8.401075 -472.01135) (xy 8.326477 -472.06506) (xy 8.247537 -472.112159) (xy 8.164841 -472.152297)
			(xy 8.079001 -472.185177) (xy 7.990652 -472.210557) (xy 7.900448 -472.228247) (xy 7.809057 -472.238118)
			(xy 7.717156 -472.240096) (xy 7.625425 -472.234166) (xy 7.534544 -472.220372) (xy 7.445185 -472.198818)
			(xy 7.358009 -472.169661) (xy 7.273663 -472.133118) (xy 7.19277 -472.089459) (xy 7.11593 -472.039008)
			(xy 7.043711 -471.982138) (xy 6.976649 -471.919271) (xy 6.915239 -471.850871) (xy 6.859936 -471.777446)
			(xy 6.81115 -471.699538) (xy 6.769242 -471.617725) (xy 6.734522 -471.532611) (xy 6.707248 -471.444829)
			(xy 6.687621 -471.355026) (xy 6.675786 -471.263869) (xy 6.671831 -471.172032) (xy 1.27 -471.172032)
			(xy 1.27 -474.214889) (xy 4.852911 -474.214889) (xy 4.852911 -474.129163) (xy 4.860821 -474.043803)
			(xy 4.876573 -473.959536) (xy 4.900033 -473.877083) (xy 4.931001 -473.797146) (xy 4.969212 -473.720407)
			(xy 5.014341 -473.647521) (xy 5.066002 -473.57911) (xy 5.123756 -473.515758) (xy 5.187108 -473.458004)
			(xy 5.255519 -473.406343) (xy 5.328405 -473.361214) (xy 5.405144 -473.323003) (xy 5.485081 -473.292035)
			(xy 5.567534 -473.268575) (xy 5.651801 -473.252823) (xy 5.737161 -473.244913) (xy 5.822887 -473.244913)
			(xy 5.908247 -473.252823) (xy 5.992514 -473.268575) (xy 6.074967 -473.292035) (xy 6.154904 -473.323003)
			(xy 6.231643 -473.361214) (xy 6.304529 -473.406343) (xy 6.37294 -473.458004) (xy 6.436292 -473.515758)
			(xy 6.494046 -473.57911) (xy 6.545707 -473.647521) (xy 6.578101 -473.69984) (xy 11.345672 -473.69984)
			(xy 11.346163 -473.596662) (xy 11.354255 -473.390463) (xy 11.370436 -473.184742) (xy 11.394682 -472.979814)
			(xy 11.426955 -472.775996) (xy 11.467204 -472.573603) (xy 11.515369 -472.372946) (xy 11.571375 -472.174334)
			(xy 11.635136 -471.978075) (xy 11.706552 -471.78447) (xy 11.785515 -471.593818) (xy 11.871902 -471.406413)
			(xy 11.96558 -471.222545) (xy 12.066404 -471.042496) (xy 12.17422 -470.866544) (xy 12.288861 -470.694961)
			(xy 12.410149 -470.528012) (xy 12.537899 -470.365952) (xy 12.671913 -470.209034) (xy 12.811985 -470.057498)
			(xy 12.957898 -469.911578) (xy 13.109427 -469.771499) (xy 13.266339 -469.637478) (xy 13.428392 -469.50972)
			(xy 13.595336 -469.388424) (xy 13.766914 -469.273775) (xy 13.94286 -469.165951) (xy 14.122904 -469.065117)
			(xy 14.306768 -468.971431) (xy 14.494169 -468.885035) (xy 14.684817 -468.806063) (xy 14.878418 -468.734637)
			(xy 15.074675 -468.670868) (xy 15.273284 -468.614853) (xy 15.473939 -468.566678) (xy 15.67633 -468.526419)
			(xy 15.880146 -468.494136) (xy 16.085073 -468.469881) (xy 16.290794 -468.45369) (xy 16.496992 -468.445588)
			(xy 16.60017 -468.445088) (xy 16.703348 -468.445592) (xy 16.909546 -468.453694) (xy 17.115267 -468.469885)
			(xy 17.320193 -468.49414) (xy 17.524009 -468.526422) (xy 17.726401 -468.566682) (xy 17.927055 -468.614856)
			(xy 18.125664 -468.670872) (xy 18.32192 -468.734641) (xy 18.515522 -468.806067) (xy 18.70617 -468.885039)
			(xy 18.89357 -468.971434) (xy 19.077434 -469.065121) (xy 19.257478 -469.165954) (xy 19.433424 -469.273778)
			(xy 19.605002 -469.388427) (xy 19.749427 -469.493362) (xy 29.519874 -469.493362) (xy 29.519874 -469.406462)
			(xy 29.527892 -469.319933) (xy 29.54386 -469.234513) (xy 29.567641 -469.150931) (xy 29.599033 -469.069899)
			(xy 29.637767 -468.99211) (xy 29.683514 -468.918226) (xy 29.735883 -468.848879) (xy 29.794427 -468.784659)
			(xy 29.858647 -468.726115) (xy 29.927994 -468.673746) (xy 30.001878 -468.627999) (xy 30.079667 -468.589265)
			(xy 30.160699 -468.557873) (xy 30.244281 -468.534092) (xy 30.329701 -468.518124) (xy 30.41623 -468.510106)
			(xy 30.50313 -468.510106) (xy 30.589659 -468.518124) (xy 30.675079 -468.534092) (xy 30.758661 -468.557873)
			(xy 30.839693 -468.589265) (xy 30.917482 -468.627999) (xy 30.991366 -468.673746) (xy 31.060713 -468.726115)
			(xy 31.124933 -468.784659) (xy 31.183477 -468.848879) (xy 31.235846 -468.918226) (xy 31.281593 -468.99211)
			(xy 31.320327 -469.069899) (xy 31.351719 -469.150931) (xy 31.3755 -469.234513) (xy 31.391468 -469.319933)
			(xy 31.399486 -469.406462) (xy 31.399988 -469.449912) (xy 31.399486 -469.493362) (xy 34.599874 -469.493362)
			(xy 34.599874 -469.406462) (xy 34.607892 -469.319933) (xy 34.62386 -469.234513) (xy 34.647641 -469.150931)
			(xy 34.679033 -469.069899) (xy 34.717767 -468.99211) (xy 34.763514 -468.918226) (xy 34.815883 -468.848879)
			(xy 34.874427 -468.784659) (xy 34.938647 -468.726115) (xy 35.007994 -468.673746) (xy 35.081878 -468.627999)
			(xy 35.159667 -468.589265) (xy 35.240699 -468.557873) (xy 35.324281 -468.534092) (xy 35.409701 -468.518124)
			(xy 35.49623 -468.510106) (xy 35.58313 -468.510106) (xy 35.669659 -468.518124) (xy 35.755079 -468.534092)
			(xy 35.838661 -468.557873) (xy 35.919693 -468.589265) (xy 35.997482 -468.627999) (xy 36.071366 -468.673746)
			(xy 36.140713 -468.726115) (xy 36.204933 -468.784659) (xy 36.263477 -468.848879) (xy 36.315846 -468.918226)
			(xy 36.361593 -468.99211) (xy 36.400327 -469.069899) (xy 36.431719 -469.150931) (xy 36.4555 -469.234513)
			(xy 36.471468 -469.319933) (xy 36.479486 -469.406462) (xy 36.479988 -469.449912) (xy 36.479486 -469.493362)
			(xy 36.471468 -469.579891) (xy 36.4555 -469.665311) (xy 36.431719 -469.748893) (xy 36.400327 -469.829925)
			(xy 36.361593 -469.907714) (xy 36.315846 -469.981598) (xy 36.263477 -470.050945) (xy 36.204933 -470.115165)
			(xy 36.140713 -470.173709) (xy 36.071366 -470.226078) (xy 35.997482 -470.271825) (xy 35.919693 -470.310559)
			(xy 35.838661 -470.341951) (xy 35.755079 -470.365732) (xy 35.669659 -470.3817) (xy 35.58313 -470.389718)
			(xy 35.49623 -470.389718) (xy 35.409701 -470.3817) (xy 35.324281 -470.365732) (xy 35.240699 -470.341951)
			(xy 35.159667 -470.310559) (xy 35.081878 -470.271825) (xy 35.007994 -470.226078) (xy 34.938647 -470.173709)
			(xy 34.874427 -470.115165) (xy 34.815883 -470.050945) (xy 34.763514 -469.981598) (xy 34.717767 -469.907714)
			(xy 34.679033 -469.829925) (xy 34.647641 -469.748893) (xy 34.62386 -469.665311) (xy 34.607892 -469.579891)
			(xy 34.599874 -469.493362) (xy 31.399486 -469.493362) (xy 31.391468 -469.579891) (xy 31.3755 -469.665311)
			(xy 31.351719 -469.748893) (xy 31.320327 -469.829925) (xy 31.281593 -469.907714) (xy 31.235846 -469.981598)
			(xy 31.183477 -470.050945) (xy 31.124933 -470.115165) (xy 31.060713 -470.173709) (xy 30.991366 -470.226078)
			(xy 30.917482 -470.271825) (xy 30.839693 -470.310559) (xy 30.758661 -470.341951) (xy 30.675079 -470.365732)
			(xy 30.589659 -470.3817) (xy 30.50313 -470.389718) (xy 30.41623 -470.389718) (xy 30.329701 -470.3817)
			(xy 30.244281 -470.365732) (xy 30.160699 -470.341951) (xy 30.079667 -470.310559) (xy 30.001878 -470.271825)
			(xy 29.927994 -470.226078) (xy 29.858647 -470.173709) (xy 29.794427 -470.115165) (xy 29.735883 -470.050945)
			(xy 29.683514 -469.981598) (xy 29.637767 -469.907714) (xy 29.599033 -469.829925) (xy 29.567641 -469.748893)
			(xy 29.54386 -469.665311) (xy 29.527892 -469.579891) (xy 29.519874 -469.493362) (xy 19.749427 -469.493362)
			(xy 19.771945 -469.509723) (xy 19.933998 -469.637481) (xy 20.09091 -469.771502) (xy 20.24244 -469.911581)
			(xy 20.388352 -470.057501) (xy 20.528424 -470.209037) (xy 20.662438 -470.365955) (xy 20.790187 -470.528014)
			(xy 20.911476 -470.694964) (xy 21.026117 -470.866546) (xy 21.133932 -471.042498) (xy 21.234757 -471.222547)
			(xy 21.328435 -471.406415) (xy 21.414822 -471.593819) (xy 21.493784 -471.784471) (xy 21.565201 -471.978076)
			(xy 21.583162 -472.033362) (xy 29.519874 -472.033362) (xy 29.519874 -471.946462) (xy 29.527892 -471.859933)
			(xy 29.54386 -471.774513) (xy 29.567641 -471.690931) (xy 29.599033 -471.609899) (xy 29.637767 -471.53211)
			(xy 29.683514 -471.458226) (xy 29.735883 -471.388879) (xy 29.794427 -471.324659) (xy 29.858647 -471.266115)
			(xy 29.927994 -471.213746) (xy 30.001878 -471.167999) (xy 30.079667 -471.129265) (xy 30.160699 -471.097873)
			(xy 30.244281 -471.074092) (xy 30.329701 -471.058124) (xy 30.41623 -471.050106) (xy 30.50313 -471.050106)
			(xy 30.589659 -471.058124) (xy 30.675079 -471.074092) (xy 30.758661 -471.097873) (xy 30.839693 -471.129265)
			(xy 30.917482 -471.167999) (xy 30.991366 -471.213746) (xy 31.060713 -471.266115) (xy 31.124933 -471.324659)
			(xy 31.183477 -471.388879) (xy 31.235846 -471.458226) (xy 31.281593 -471.53211) (xy 31.320327 -471.609899)
			(xy 31.351719 -471.690931) (xy 31.3755 -471.774513) (xy 31.391468 -471.859933) (xy 31.399486 -471.946462)
			(xy 31.399988 -471.989912) (xy 31.399486 -472.033362) (xy 34.599874 -472.033362) (xy 34.599874 -471.946462)
			(xy 34.607892 -471.859933) (xy 34.62386 -471.774513) (xy 34.647641 -471.690931) (xy 34.679033 -471.609899)
			(xy 34.717767 -471.53211) (xy 34.763514 -471.458226) (xy 34.815883 -471.388879) (xy 34.874427 -471.324659)
			(xy 34.938647 -471.266115) (xy 35.007994 -471.213746) (xy 35.081878 -471.167999) (xy 35.159667 -471.129265)
			(xy 35.240699 -471.097873) (xy 35.324281 -471.074092) (xy 35.409701 -471.058124) (xy 35.49623 -471.050106)
			(xy 35.58313 -471.050106) (xy 35.669659 -471.058124) (xy 35.755079 -471.074092) (xy 35.838661 -471.097873)
			(xy 35.919693 -471.129265) (xy 35.997482 -471.167999) (xy 36.071366 -471.213746) (xy 36.140713 -471.266115)
			(xy 36.204933 -471.324659) (xy 36.263477 -471.388879) (xy 36.315846 -471.458226) (xy 36.361593 -471.53211)
			(xy 36.400327 -471.609899) (xy 36.431719 -471.690931) (xy 36.4555 -471.774513) (xy 36.471468 -471.859933)
			(xy 36.479486 -471.946462) (xy 36.479988 -471.989912) (xy 36.479486 -472.033362) (xy 36.473156 -472.101672)
			(xy 70.798942 -472.101672) (xy 70.803013 -472.04605) (xy 70.815139 -471.991613) (xy 70.835062 -471.939522)
			(xy 70.862358 -471.890887) (xy 70.896444 -471.846744) (xy 70.936593 -471.808035) (xy 70.981951 -471.775584)
			(xy 71.031551 -471.750083) (xy 71.084335 -471.732076) (xy 71.139178 -471.721946) (xy 71.194912 -471.719909)
			(xy 71.250349 -471.726009) (xy 71.304306 -471.740115) (xy 71.355635 -471.761927) (xy 71.403241 -471.790981)
			(xy 71.446109 -471.826656) (xy 71.483326 -471.868193) (xy 71.514099 -471.914706) (xy 71.537771 -471.965203)
			(xy 71.553839 -472.01861) (xy 71.561959 -472.073786) (xy 71.562468 -472.101672) (xy 74.193906 -472.101672)
			(xy 74.197977 -472.04605) (xy 74.210103 -471.991613) (xy 74.230026 -471.939522) (xy 74.257322 -471.890887)
			(xy 74.291408 -471.846744) (xy 74.331557 -471.808035) (xy 74.376915 -471.775584) (xy 74.426515 -471.750083)
			(xy 74.479299 -471.732076) (xy 74.534142 -471.721946) (xy 74.589876 -471.719909) (xy 74.645313 -471.726009)
			(xy 74.69927 -471.740115) (xy 74.750599 -471.761927) (xy 74.798205 -471.790981) (xy 74.841073 -471.826656)
			(xy 74.87829 -471.868193) (xy 74.909063 -471.914706) (xy 74.932735 -471.965203) (xy 74.948803 -472.01861)
			(xy 74.956923 -472.073786) (xy 74.957432 -472.101672) (xy 74.956923 -472.129558) (xy 74.948803 -472.184734)
			(xy 74.932735 -472.238141) (xy 74.909063 -472.288638) (xy 74.87829 -472.335151) (xy 74.841073 -472.376688)
			(xy 74.798205 -472.412363) (xy 74.750599 -472.441417) (xy 74.69927 -472.463229) (xy 74.645313 -472.477335)
			(xy 74.589876 -472.483435) (xy 74.534142 -472.481398) (xy 74.479299 -472.471268) (xy 74.426515 -472.453261)
			(xy 74.376915 -472.42776) (xy 74.331557 -472.395309) (xy 74.291408 -472.3566) (xy 74.257322 -472.312457)
			(xy 74.230026 -472.263822) (xy 74.210103 -472.211731) (xy 74.197977 -472.157294) (xy 74.193906 -472.101672)
			(xy 71.562468 -472.101672) (xy 71.561959 -472.129558) (xy 71.553839 -472.184734) (xy 71.537771 -472.238141)
			(xy 71.514099 -472.288638) (xy 71.483326 -472.335151) (xy 71.446109 -472.376688) (xy 71.403241 -472.412363)
			(xy 71.355635 -472.441417) (xy 71.304306 -472.463229) (xy 71.250349 -472.477335) (xy 71.194912 -472.483435)
			(xy 71.139178 -472.481398) (xy 71.084335 -472.471268) (xy 71.031551 -472.453261) (xy 70.981951 -472.42776)
			(xy 70.936593 -472.395309) (xy 70.896444 -472.3566) (xy 70.862358 -472.312457) (xy 70.835062 -472.263822)
			(xy 70.815139 -472.211731) (xy 70.803013 -472.157294) (xy 70.798942 -472.101672) (xy 36.473156 -472.101672)
			(xy 36.471468 -472.119891) (xy 36.4555 -472.205311) (xy 36.431719 -472.288893) (xy 36.400327 -472.369925)
			(xy 36.361593 -472.447714) (xy 36.315846 -472.521598) (xy 36.263477 -472.590945) (xy 36.204933 -472.655165)
			(xy 36.140713 -472.713709) (xy 36.071366 -472.766078) (xy 35.997482 -472.811825) (xy 35.919693 -472.850559)
			(xy 35.838661 -472.881951) (xy 35.755079 -472.905732) (xy 35.669659 -472.9217) (xy 35.58313 -472.929718)
			(xy 35.49623 -472.929718) (xy 35.409701 -472.9217) (xy 35.324281 -472.905732) (xy 35.240699 -472.881951)
			(xy 35.159667 -472.850559) (xy 35.081878 -472.811825) (xy 35.007994 -472.766078) (xy 34.938647 -472.713709)
			(xy 34.874427 -472.655165) (xy 34.815883 -472.590945) (xy 34.763514 -472.521598) (xy 34.717767 -472.447714)
			(xy 34.679033 -472.369925) (xy 34.647641 -472.288893) (xy 34.62386 -472.205311) (xy 34.607892 -472.119891)
			(xy 34.599874 -472.033362) (xy 31.399486 -472.033362) (xy 31.391468 -472.119891) (xy 31.3755 -472.205311)
			(xy 31.351719 -472.288893) (xy 31.320327 -472.369925) (xy 31.281593 -472.447714) (xy 31.235846 -472.521598)
			(xy 31.183477 -472.590945) (xy 31.124933 -472.655165) (xy 31.060713 -472.713709) (xy 30.991366 -472.766078)
			(xy 30.917482 -472.811825) (xy 30.839693 -472.850559) (xy 30.758661 -472.881951) (xy 30.675079 -472.905732)
			(xy 30.589659 -472.9217) (xy 30.50313 -472.929718) (xy 30.41623 -472.929718) (xy 30.329701 -472.9217)
			(xy 30.244281 -472.905732) (xy 30.160699 -472.881951) (xy 30.079667 -472.850559) (xy 30.001878 -472.811825)
			(xy 29.927994 -472.766078) (xy 29.858647 -472.713709) (xy 29.794427 -472.655165) (xy 29.735883 -472.590945)
			(xy 29.683514 -472.521598) (xy 29.637767 -472.447714) (xy 29.599033 -472.369925) (xy 29.567641 -472.288893)
			(xy 29.54386 -472.205311) (xy 29.527892 -472.119891) (xy 29.519874 -472.033362) (xy 21.583162 -472.033362)
			(xy 21.628961 -472.174335) (xy 21.684967 -472.372947) (xy 21.733132 -472.573604) (xy 21.773381 -472.775997)
			(xy 21.805654 -472.979815) (xy 21.8299 -473.184742) (xy 21.846081 -473.390464) (xy 21.854173 -473.596662)
			(xy 21.854668 -473.69984) (xy 21.854174 -473.801741) (xy 21.846271 -474.005391) (xy 21.830478 -474.20858)
			(xy 21.806818 -474.411005) (xy 21.781426 -474.573362) (xy 29.519874 -474.573362) (xy 29.519874 -474.486462)
			(xy 29.527892 -474.399933) (xy 29.54386 -474.314513) (xy 29.567641 -474.230931) (xy 29.599033 -474.149899)
			(xy 29.637767 -474.07211) (xy 29.683514 -473.998226) (xy 29.735883 -473.928879) (xy 29.794427 -473.864659)
			(xy 29.858647 -473.806115) (xy 29.927994 -473.753746) (xy 30.001878 -473.707999) (xy 30.079667 -473.669265)
			(xy 30.160699 -473.637873) (xy 30.244281 -473.614092) (xy 30.329701 -473.598124) (xy 30.41623 -473.590106)
			(xy 30.50313 -473.590106) (xy 30.589659 -473.598124) (xy 30.675079 -473.614092) (xy 30.758661 -473.637873)
			(xy 30.839693 -473.669265) (xy 30.917482 -473.707999) (xy 30.991366 -473.753746) (xy 31.060713 -473.806115)
			(xy 31.124933 -473.864659) (xy 31.183477 -473.928879) (xy 31.235846 -473.998226) (xy 31.281593 -474.07211)
			(xy 31.320327 -474.149899) (xy 31.351719 -474.230931) (xy 31.3755 -474.314513) (xy 31.391468 -474.399933)
			(xy 31.399486 -474.486462) (xy 31.399988 -474.529912) (xy 31.399486 -474.573362) (xy 34.599874 -474.573362)
			(xy 34.599874 -474.486462) (xy 34.607892 -474.399933) (xy 34.62386 -474.314513) (xy 34.647641 -474.230931)
			(xy 34.679033 -474.149899) (xy 34.717767 -474.07211) (xy 34.763514 -473.998226) (xy 34.815883 -473.928879)
			(xy 34.874427 -473.864659) (xy 34.938647 -473.806115) (xy 35.007994 -473.753746) (xy 35.081878 -473.707999)
			(xy 35.159667 -473.669265) (xy 35.240699 -473.637873) (xy 35.324281 -473.614092) (xy 35.409701 -473.598124)
			(xy 35.49623 -473.590106) (xy 35.58313 -473.590106) (xy 35.669659 -473.598124) (xy 35.755079 -473.614092)
			(xy 35.838661 -473.637873) (xy 35.919693 -473.669265) (xy 35.997482 -473.707999) (xy 36.071366 -473.753746)
			(xy 36.140713 -473.806115) (xy 36.204933 -473.864659) (xy 36.263477 -473.928879) (xy 36.290621 -473.964823)
			(xy 38.249145 -473.964823) (xy 38.25303 -473.910461) (xy 38.264612 -473.857206) (xy 38.283656 -473.806142)
			(xy 38.309773 -473.758308) (xy 38.342433 -473.714677) (xy 38.38097 -473.676139) (xy 38.424599 -473.643479)
			(xy 38.472433 -473.61736) (xy 38.523497 -473.598315) (xy 38.576752 -473.586731) (xy 38.631113 -473.582845)
			(xy 38.685474 -473.586735) (xy 38.738728 -473.598322) (xy 38.789791 -473.617371) (xy 38.837623 -473.643493)
			(xy 38.859714 -473.659454) (xy 38.878726 -473.67305) (xy 38.920609 -473.693782) (xy 38.965577 -473.706508)
			(xy 39.012114 -473.710798) (xy 39.058651 -473.706508) (xy 39.103619 -473.693782) (xy 39.145502 -473.67305)
			(xy 39.164514 -473.659454) (xy 39.186637 -473.643546) (xy 39.23446 -473.617433) (xy 39.285512 -473.598391)
			(xy 39.338754 -473.586809) (xy 39.393103 -473.582922) (xy 39.447451 -473.58681) (xy 39.500694 -473.598393)
			(xy 39.551745 -473.617435) (xy 39.599567 -473.643549) (xy 39.643186 -473.676204) (xy 39.681713 -473.714734)
			(xy 39.714364 -473.758354) (xy 39.740475 -473.806178) (xy 39.759514 -473.857231) (xy 39.771094 -473.910474)
			(xy 39.774978 -473.964823) (xy 40.135837 -473.964823) (xy 40.139723 -473.91046) (xy 40.151305 -473.857203)
			(xy 40.17035 -473.806137) (xy 40.196469 -473.758302) (xy 40.22913 -473.71467) (xy 40.267668 -473.676132)
			(xy 40.311299 -473.64347) (xy 40.359135 -473.617351) (xy 40.4102 -473.598306) (xy 40.463457 -473.586723)
			(xy 40.51782 -473.582837) (xy 40.572183 -473.586729) (xy 40.625438 -473.598317) (xy 40.676502 -473.617368)
			(xy 40.724334 -473.643492) (xy 40.746426 -473.659454) (xy 40.765438 -473.67305) (xy 40.807321 -473.693782)
			(xy 40.852289 -473.706508) (xy 40.898826 -473.710798) (xy 40.945363 -473.706508) (xy 40.990331 -473.693782)
			(xy 41.032214 -473.67305) (xy 41.051226 -473.659454) (xy 41.073349 -473.643548) (xy 41.121171 -473.617436)
			(xy 41.172221 -473.598396) (xy 41.225462 -473.586815) (xy 41.27981 -473.582929) (xy 41.334156 -473.586818)
			(xy 41.387397 -473.598401) (xy 41.39037 -473.59951) (xy 70.731886 -473.59951) (xy 70.735957 -473.543888)
			(xy 70.748083 -473.489451) (xy 70.768006 -473.43736) (xy 70.795302 -473.388725) (xy 70.829388 -473.344582)
			(xy 70.869537 -473.305873) (xy 70.914895 -473.273422) (xy 70.964495 -473.247921) (xy 71.017279 -473.229914)
			(xy 71.072122 -473.219784) (xy 71.127856 -473.217747) (xy 71.183293 -473.223847) (xy 71.23725 -473.237953)
			(xy 71.288579 -473.259765) (xy 71.336185 -473.288819) (xy 71.379053 -473.324494) (xy 71.41627 -473.366031)
			(xy 71.447043 -473.412544) (xy 71.470715 -473.463041) (xy 71.486783 -473.516448) (xy 71.494903 -473.571624)
			(xy 71.495412 -473.59951) (xy 71.494903 -473.627396) (xy 71.486783 -473.682572) (xy 71.470715 -473.735979)
			(xy 71.447043 -473.786476) (xy 71.41627 -473.832989) (xy 71.379053 -473.874526) (xy 71.336185 -473.910201)
			(xy 71.288579 -473.939255) (xy 71.23725 -473.961067) (xy 71.183293 -473.975173) (xy 71.127856 -473.981273)
			(xy 71.072122 -473.979236) (xy 71.017279 -473.969106) (xy 70.964495 -473.951099) (xy 70.914895 -473.925598)
			(xy 70.869537 -473.893147) (xy 70.829388 -473.854438) (xy 70.795302 -473.810295) (xy 70.768006 -473.76166)
			(xy 70.748083 -473.709569) (xy 70.735957 -473.655132) (xy 70.731886 -473.59951) (xy 41.39037 -473.59951)
			(xy 41.438447 -473.617444) (xy 41.486267 -473.643558) (xy 41.529884 -473.676212) (xy 41.568409 -473.714741)
			(xy 41.60106 -473.75836) (xy 41.62717 -473.806183) (xy 41.646208 -473.857234) (xy 41.657787 -473.910476)
			(xy 41.661671 -473.964823) (xy 41.65778 -474.01917) (xy 41.646195 -474.07241) (xy 41.627151 -474.123459)
			(xy 41.601035 -474.171278) (xy 41.56838 -474.214894) (xy 41.529849 -474.253418) (xy 41.486229 -474.286067)
			(xy 41.438405 -474.312175) (xy 41.387353 -474.331212) (xy 41.334111 -474.342789) (xy 41.279764 -474.346671)
			(xy 41.225417 -474.342778) (xy 41.172178 -474.331191) (xy 41.121129 -474.312145) (xy 41.073311 -474.286028)
			(xy 41.051226 -474.27007) (xy 41.032214 -474.256474) (xy 40.990331 -474.235742) (xy 40.945363 -474.223016)
			(xy 40.898826 -474.218726) (xy 40.852289 -474.223016) (xy 40.807321 -474.235742) (xy 40.765438 -474.256474)
			(xy 40.746426 -474.27007) (xy 40.724373 -474.286083) (xy 40.676543 -474.312213) (xy 40.625482 -474.33127)
			(xy 40.572228 -474.342865) (xy 40.517866 -474.346763) (xy 40.463502 -474.342883) (xy 40.410244 -474.331307)
			(xy 40.359176 -474.312268) (xy 40.311338 -474.286154) (xy 40.267703 -474.253498) (xy 40.22916 -474.214964)
			(xy 40.196493 -474.171337) (xy 40.170369 -474.123504) (xy 40.151318 -474.072441) (xy 40.139729 -474.019185)
			(xy 40.135837 -473.964823) (xy 39.774978 -473.964823) (xy 39.771087 -474.019171) (xy 39.759502 -474.072413)
			(xy 39.740456 -474.123463) (xy 39.71434 -474.171284) (xy 39.681683 -474.214901) (xy 39.643151 -474.253426)
			(xy 39.599529 -474.286075) (xy 39.551704 -474.312184) (xy 39.50065 -474.33122) (xy 39.447406 -474.342797)
			(xy 39.393057 -474.346678) (xy 39.338709 -474.342784) (xy 39.285468 -474.331196) (xy 39.234418 -474.312148)
			(xy 39.186599 -474.286029) (xy 39.164514 -474.27007) (xy 39.145502 -474.256474) (xy 39.103619 -474.235742)
			(xy 39.058651 -474.223016) (xy 39.012114 -474.218726) (xy 38.965577 -474.223016) (xy 38.920609 -474.235742)
			(xy 38.878726 -474.256474) (xy 38.859714 -474.27007) (xy 38.837661 -474.286082) (xy 38.789832 -474.31221)
			(xy 38.738772 -474.331265) (xy 38.685519 -474.342859) (xy 38.631159 -474.346755) (xy 38.576797 -474.342875)
			(xy 38.523541 -474.331298) (xy 38.472475 -474.312259) (xy 38.424638 -474.286146) (xy 38.381005 -474.25349)
			(xy 38.342463 -474.214957) (xy 38.309798 -474.171331) (xy 38.283675 -474.1235) (xy 38.264625 -474.072437)
			(xy 38.253036 -474.019184) (xy 38.249145 -473.964823) (xy 36.290621 -473.964823) (xy 36.315846 -473.998226)
			(xy 36.361593 -474.07211) (xy 36.400327 -474.149899) (xy 36.431719 -474.230931) (xy 36.4555 -474.314513)
			(xy 36.471468 -474.399933) (xy 36.479486 -474.486462) (xy 36.479988 -474.529912) (xy 36.479486 -474.573362)
			(xy 36.471468 -474.659891) (xy 36.4555 -474.745311) (xy 36.431719 -474.828893) (xy 36.400327 -474.909925)
			(xy 36.361593 -474.987714) (xy 36.315846 -475.061598) (xy 36.263477 -475.130945) (xy 36.204933 -475.195165)
			(xy 36.140713 -475.253709) (xy 36.071366 -475.306078) (xy 35.997482 -475.351825) (xy 35.919693 -475.390559)
			(xy 35.838661 -475.421951) (xy 35.755079 -475.445732) (xy 35.669659 -475.4617) (xy 35.58313 -475.469718)
			(xy 35.49623 -475.469718) (xy 35.409701 -475.4617) (xy 35.324281 -475.445732) (xy 35.240699 -475.421951)
			(xy 35.159667 -475.390559) (xy 35.081878 -475.351825) (xy 35.007994 -475.306078) (xy 34.938647 -475.253709)
			(xy 34.874427 -475.195165) (xy 34.815883 -475.130945) (xy 34.763514 -475.061598) (xy 34.717767 -474.987714)
			(xy 34.679033 -474.909925) (xy 34.647641 -474.828893) (xy 34.62386 -474.745311) (xy 34.607892 -474.659891)
			(xy 34.599874 -474.573362) (xy 31.399486 -474.573362) (xy 31.391468 -474.659891) (xy 31.3755 -474.745311)
			(xy 31.351719 -474.828893) (xy 31.320327 -474.909925) (xy 31.281593 -474.987714) (xy 31.235846 -475.061598)
			(xy 31.183477 -475.130945) (xy 31.124933 -475.195165) (xy 31.060713 -475.253709) (xy 30.991366 -475.306078)
			(xy 30.917482 -475.351825) (xy 30.839693 -475.390559) (xy 30.758661 -475.421951) (xy 30.675079 -475.445732)
			(xy 30.589659 -475.4617) (xy 30.50313 -475.469718) (xy 30.41623 -475.469718) (xy 30.329701 -475.4617)
			(xy 30.244281 -475.445732) (xy 30.160699 -475.421951) (xy 30.079667 -475.390559) (xy 30.001878 -475.351825)
			(xy 29.927994 -475.306078) (xy 29.858647 -475.253709) (xy 29.794427 -475.195165) (xy 29.735883 -475.130945)
			(xy 29.683514 -475.061598) (xy 29.637767 -474.987714) (xy 29.599033 -474.909925) (xy 29.567641 -474.828893)
			(xy 29.54386 -474.745311) (xy 29.527892 -474.659891) (xy 29.519874 -474.573362) (xy 21.781426 -474.573362)
			(xy 21.775327 -474.61236) (xy 21.736052 -474.812342) (xy 21.689051 -475.010651) (xy 21.634397 -475.206989)
			(xy 21.572171 -475.401059) (xy 21.502466 -475.592571) (xy 21.425388 -475.781236) (xy 21.417583 -475.798407)
			(xy 38.249165 -475.798407) (xy 38.253052 -475.744049) (xy 38.264636 -475.690797) (xy 38.283681 -475.639736)
			(xy 38.309799 -475.591906) (xy 38.342459 -475.548279) (xy 38.380995 -475.509745) (xy 38.424624 -475.477088)
			(xy 38.472456 -475.450972) (xy 38.523518 -475.43193) (xy 38.57677 -475.420349) (xy 38.631129 -475.416465)
			(xy 38.685487 -475.420358) (xy 38.738737 -475.431946) (xy 38.789796 -475.450996) (xy 38.837625 -475.477119)
			(xy 38.859714 -475.49308) (xy 38.878726 -475.506676) (xy 38.920609 -475.527408) (xy 38.965577 -475.540134)
			(xy 39.012114 -475.544424) (xy 39.058651 -475.540134) (xy 39.103619 -475.527408) (xy 39.145502 -475.506676)
			(xy 39.164514 -475.49308) (xy 39.186613 -475.477137) (xy 39.234437 -475.451021) (xy 39.285491 -475.431976)
			(xy 39.338736 -475.420391) (xy 39.393087 -475.416501) (xy 39.447439 -475.420387) (xy 39.500684 -475.431968)
			(xy 39.55174 -475.45101) (xy 39.599565 -475.477124) (xy 39.643188 -475.509778) (xy 39.681718 -475.548308)
			(xy 39.714373 -475.59193) (xy 39.740488 -475.639755) (xy 39.75953 -475.69081) (xy 39.771112 -475.744055)
			(xy 39.774999 -475.798407) (xy 40.135858 -475.798407) (xy 40.139745 -475.744047) (xy 40.15133 -475.690794)
			(xy 40.170375 -475.639732) (xy 40.196495 -475.5919) (xy 40.229156 -475.548272) (xy 40.267694 -475.509737)
			(xy 40.311324 -475.477079) (xy 40.359157 -475.450964) (xy 40.410221 -475.431922) (xy 40.463475 -475.420341)
			(xy 40.517836 -475.416458) (xy 40.572195 -475.420352) (xy 40.625447 -475.431942) (xy 40.676507 -475.450993)
			(xy 40.724336 -475.477118) (xy 40.746426 -475.49308) (xy 40.765438 -475.506676) (xy 40.807321 -475.527408)
			(xy 40.852289 -475.540134) (xy 40.898826 -475.544424) (xy 40.945363 -475.540134) (xy 40.990331 -475.527408)
			(xy 41.032214 -475.506676) (xy 41.051226 -475.49308) (xy 41.073325 -475.477138) (xy 41.121148 -475.451023)
			(xy 41.172201 -475.43198) (xy 41.225444 -475.420397) (xy 41.279794 -475.416509) (xy 41.334144 -475.420395)
			(xy 41.387388 -475.431977) (xy 41.438441 -475.451018) (xy 41.486265 -475.477132) (xy 41.529886 -475.509786)
			(xy 41.568415 -475.548315) (xy 41.601069 -475.591936) (xy 41.627182 -475.63976) (xy 41.646223 -475.690813)
			(xy 41.657805 -475.744057) (xy 41.661691 -475.798407) (xy 42.376993 -475.798407) (xy 42.380879 -475.744055)
			(xy 42.392461 -475.69081) (xy 42.411503 -475.639754) (xy 42.437617 -475.591929) (xy 42.470272 -475.548306)
			(xy 42.508803 -475.509775) (xy 42.552425 -475.47712) (xy 42.60025 -475.451005) (xy 42.651305 -475.431963)
			(xy 42.704551 -475.42038) (xy 42.758903 -475.416493) (xy 42.813255 -475.420381) (xy 42.8665 -475.431964)
			(xy 42.917555 -475.451007) (xy 42.96538 -475.477123) (xy 42.987468 -475.49308) (xy 43.00648 -475.506676)
			(xy 43.048363 -475.527408) (xy 43.093331 -475.540134) (xy 43.139868 -475.544424) (xy 43.186405 -475.540134)
			(xy 43.231373 -475.527408) (xy 43.273256 -475.506676) (xy 43.292268 -475.49308) (xy 43.314368 -475.477134)
			(xy 43.362195 -475.451009) (xy 43.413253 -475.431958) (xy 43.466503 -475.420368) (xy 43.520861 -475.416474)
			(xy 43.575219 -475.420356) (xy 43.628472 -475.431936) (xy 43.679534 -475.450977) (xy 43.727366 -475.477091)
			(xy 43.770995 -475.509748) (xy 43.809531 -475.548281) (xy 43.842191 -475.591907) (xy 43.86831 -475.639737)
			(xy 43.887355 -475.690798) (xy 43.898939 -475.744049) (xy 43.902826 -475.798407) (xy 44.281003 -475.798407)
			(xy 44.284889 -475.744057) (xy 44.29647 -475.690814) (xy 44.315511 -475.63976) (xy 44.341624 -475.591937)
			(xy 44.374277 -475.548316) (xy 44.412805 -475.509786) (xy 44.456425 -475.477131) (xy 44.504248 -475.451017)
			(xy 44.555301 -475.431974) (xy 44.608544 -475.420391) (xy 44.662894 -475.416503) (xy 44.717243 -475.420389)
			(xy 44.770487 -475.43197) (xy 44.82154 -475.451011) (xy 44.869364 -475.477124) (xy 44.891452 -475.49308)
			(xy 44.910464 -475.506676) (xy 44.952347 -475.527408) (xy 44.997315 -475.540134) (xy 45.043852 -475.544424)
			(xy 45.090389 -475.540134) (xy 45.135357 -475.527408) (xy 45.17724 -475.506676) (xy 45.196252 -475.49308)
			(xy 45.218353 -475.477132) (xy 45.266181 -475.451005) (xy 45.31724 -475.431952) (xy 45.370492 -475.420359)
			(xy 45.424852 -475.416464) (xy 45.479212 -475.420346) (xy 45.532467 -475.431925) (xy 45.583532 -475.450965)
			(xy 45.631366 -475.47708) (xy 45.674997 -475.509737) (xy 45.713536 -475.548272) (xy 45.746198 -475.591899)
			(xy 45.772318 -475.639731) (xy 45.791364 -475.690794) (xy 45.802948 -475.744047) (xy 45.806836 -475.798407)
			(xy 45.802946 -475.852767) (xy 45.79136 -475.90602) (xy 45.772312 -475.957082) (xy 45.74619 -476.004913)
			(xy 45.713527 -476.048539) (xy 45.674986 -476.087072) (xy 45.631354 -476.119728) (xy 45.583519 -476.145841)
			(xy 45.532453 -476.164879) (xy 45.479198 -476.176456) (xy 45.424837 -476.180336) (xy 45.370478 -476.176439)
			(xy 45.317227 -476.164844) (xy 45.266168 -476.145789) (xy 45.21834 -476.11966) (xy 45.196252 -476.103696)
			(xy 45.17724 -476.0901) (xy 45.135357 -476.069368) (xy 45.090389 -476.056642) (xy 45.043852 -476.052352)
			(xy 44.997315 -476.056642) (xy 44.952347 -476.069368) (xy 44.910464 -476.0901) (xy 44.891452 -476.103696)
			(xy 44.869376 -476.119668) (xy 44.821553 -476.145783) (xy 44.770501 -476.164826) (xy 44.717258 -476.176409)
			(xy 44.662908 -476.180297) (xy 44.608558 -476.176411) (xy 44.555315 -476.16483) (xy 44.504261 -476.145789)
			(xy 44.456437 -476.119677) (xy 44.412816 -476.087024) (xy 44.374286 -476.048495) (xy 44.341632 -476.004876)
			(xy 44.315517 -475.957053) (xy 44.296474 -475.906) (xy 44.284891 -475.852757) (xy 44.281003 -475.798407)
			(xy 43.902826 -475.798407) (xy 43.898937 -475.852765) (xy 43.887351 -475.906016) (xy 43.868304 -475.957076)
			(xy 43.842184 -476.004905) (xy 43.809522 -476.04853) (xy 43.770984 -476.087062) (xy 43.727354 -476.119716)
			(xy 43.679521 -476.145829) (xy 43.628458 -476.164868) (xy 43.575205 -476.176446) (xy 43.520847 -476.180326)
			(xy 43.466489 -476.17643) (xy 43.41324 -476.164838) (xy 43.362182 -476.145785) (xy 43.314356 -476.119659)
			(xy 43.292268 -476.103696) (xy 43.273256 -476.0901) (xy 43.231373 -476.069368) (xy 43.186405 -476.056642)
			(xy 43.139868 -476.052352) (xy 43.093331 -476.056642) (xy 43.048363 -476.069368) (xy 43.00648 -476.0901)
			(xy 42.987468 -476.103696) (xy 42.965392 -476.119669) (xy 42.917568 -476.145787) (xy 42.866514 -476.164832)
			(xy 42.813269 -476.176417) (xy 42.758917 -476.180307) (xy 42.704565 -476.176422) (xy 42.651319 -476.164841)
			(xy 42.600263 -476.145801) (xy 42.552437 -476.119688) (xy 42.508814 -476.087034) (xy 42.470282 -476.048505)
			(xy 42.437625 -476.004884) (xy 42.411509 -475.957059) (xy 42.392465 -475.906004) (xy 42.380881 -475.852759)
			(xy 42.376993 -475.798407) (xy 41.661691 -475.798407) (xy 41.657803 -475.852757) (xy 41.646219 -475.906)
			(xy 41.627176 -475.957053) (xy 41.601061 -476.004876) (xy 41.568406 -476.048496) (xy 41.529875 -476.087024)
			(xy 41.486253 -476.119676) (xy 41.438428 -476.145788) (xy 41.387374 -476.164827) (xy 41.33413 -476.176407)
			(xy 41.27978 -476.180291) (xy 41.22543 -476.176401) (xy 41.172187 -476.164816) (xy 41.121135 -476.145771)
			(xy 41.073313 -476.119654) (xy 41.051226 -476.103696) (xy 41.032214 -476.0901) (xy 40.990331 -476.069368)
			(xy 40.945363 -476.056642) (xy 40.898826 -476.052352) (xy 40.852289 -476.056642) (xy 40.807321 -476.069368)
			(xy 40.765438 -476.0901) (xy 40.746426 -476.103696) (xy 40.724348 -476.119674) (xy 40.67652 -476.145801)
			(xy 40.625461 -476.164854) (xy 40.572209 -476.176446) (xy 40.51785 -476.180342) (xy 40.46349 -476.176461)
			(xy 40.410235 -476.164882) (xy 40.359171 -476.145842) (xy 40.311336 -476.119728) (xy 40.267704 -476.087072)
			(xy 40.229165 -476.048539) (xy 40.196503 -476.004912) (xy 40.170381 -475.957081) (xy 40.151334 -475.90602)
			(xy 40.139747 -475.852767) (xy 40.135858 -475.798407) (xy 39.774999 -475.798407) (xy 39.77111 -475.852759)
			(xy 39.759526 -475.906004) (xy 39.740482 -475.957058) (xy 39.714366 -476.004882) (xy 39.681709 -476.048503)
			(xy 39.643177 -476.087032) (xy 39.599553 -476.119684) (xy 39.551727 -476.145796) (xy 39.500671 -476.164836)
			(xy 39.447425 -476.176415) (xy 39.393073 -476.180299) (xy 39.338721 -476.176407) (xy 39.285477 -476.16482)
			(xy 39.234424 -476.145774) (xy 39.186601 -476.119655) (xy 39.164514 -476.103696) (xy 39.145502 -476.0901)
			(xy 39.103619 -476.069368) (xy 39.058651 -476.056642) (xy 39.012114 -476.052352) (xy 38.965577 -476.056642)
			(xy 38.920609 -476.069368) (xy 38.878726 -476.0901) (xy 38.859714 -476.103696) (xy 38.837637 -476.119673)
			(xy 38.78981 -476.145798) (xy 38.738751 -476.164849) (xy 38.685501 -476.17644) (xy 38.631143 -476.180335)
			(xy 38.576785 -476.176453) (xy 38.523532 -476.164874) (xy 38.472469 -476.145834) (xy 38.424636 -476.11972)
			(xy 38.381006 -476.087064) (xy 38.342469 -476.048532) (xy 38.309807 -476.004906) (xy 38.283687 -475.957077)
			(xy 38.26464 -475.906017) (xy 38.253055 -475.852765) (xy 38.249165 -475.798407) (xy 21.417583 -475.798407)
			(xy 21.341053 -475.96677) (xy 21.249586 -476.148895) (xy 21.151127 -476.327336) (xy 21.045822 -476.501825)
			(xy 20.933831 -476.6721) (xy 20.815321 -476.837904) (xy 20.690471 -476.998988) (xy 20.5945 -477.113362)
			(xy 29.519874 -477.113362) (xy 29.519874 -477.026462) (xy 29.527892 -476.939933) (xy 29.54386 -476.854513)
			(xy 29.567641 -476.770931) (xy 29.599033 -476.689899) (xy 29.637767 -476.61211) (xy 29.683514 -476.538226)
			(xy 29.735883 -476.468879) (xy 29.794427 -476.404659) (xy 29.858647 -476.346115) (xy 29.927994 -476.293746)
			(xy 30.001878 -476.247999) (xy 30.079667 -476.209265) (xy 30.160699 -476.177873) (xy 30.244281 -476.154092)
			(xy 30.329701 -476.138124) (xy 30.41623 -476.130106) (xy 30.50313 -476.130106) (xy 30.589659 -476.138124)
			(xy 30.675079 -476.154092) (xy 30.758661 -476.177873) (xy 30.839693 -476.209265) (xy 30.917482 -476.247999)
			(xy 30.991366 -476.293746) (xy 31.060713 -476.346115) (xy 31.124933 -476.404659) (xy 31.183477 -476.468879)
			(xy 31.235846 -476.538226) (xy 31.281593 -476.61211) (xy 31.320327 -476.689899) (xy 31.351719 -476.770931)
			(xy 31.3755 -476.854513) (xy 31.391468 -476.939933) (xy 31.399486 -477.026462) (xy 31.399988 -477.069912)
			(xy 31.399486 -477.113362) (xy 34.599874 -477.113362) (xy 34.599874 -477.026462) (xy 34.607892 -476.939933)
			(xy 34.62386 -476.854513) (xy 34.647641 -476.770931) (xy 34.679033 -476.689899) (xy 34.717767 -476.61211)
			(xy 34.763514 -476.538226) (xy 34.815883 -476.468879) (xy 34.874427 -476.404659) (xy 34.938647 -476.346115)
			(xy 35.007994 -476.293746) (xy 35.081878 -476.247999) (xy 35.159667 -476.209265) (xy 35.240699 -476.177873)
			(xy 35.324281 -476.154092) (xy 35.409701 -476.138124) (xy 35.49623 -476.130106) (xy 35.58313 -476.130106)
			(xy 35.669659 -476.138124) (xy 35.755079 -476.154092) (xy 35.838661 -476.177873) (xy 35.919693 -476.209265)
			(xy 35.997482 -476.247999) (xy 36.071366 -476.293746) (xy 36.140713 -476.346115) (xy 36.204933 -476.404659)
			(xy 36.263477 -476.468879) (xy 36.315846 -476.538226) (xy 36.361593 -476.61211) (xy 36.400327 -476.689899)
			(xy 36.431719 -476.770931) (xy 36.4555 -476.854513) (xy 36.471468 -476.939933) (xy 36.479486 -477.026462)
			(xy 36.479988 -477.069912) (xy 36.479486 -477.113362) (xy 36.471468 -477.199891) (xy 36.4555 -477.285311)
			(xy 36.431719 -477.368893) (xy 36.400327 -477.449925) (xy 36.361593 -477.527714) (xy 36.315846 -477.601598)
			(xy 36.263477 -477.670945) (xy 36.237641 -477.699286) (xy 38.249194 -477.699286) (xy 38.253084 -477.644932)
			(xy 38.26467 -477.591685) (xy 38.283716 -477.540629) (xy 38.309835 -477.492803) (xy 38.342495 -477.449182)
			(xy 38.381031 -477.410653) (xy 38.424658 -477.378) (xy 38.472488 -477.351889) (xy 38.523547 -477.332852)
			(xy 38.576796 -477.321275) (xy 38.63115 -477.317394) (xy 38.685504 -477.321289) (xy 38.73875 -477.33288)
			(xy 38.789804 -477.351931) (xy 38.837627 -477.378055) (xy 38.859714 -477.394016) (xy 38.878726 -477.407612)
			(xy 38.920609 -477.428344) (xy 38.965577 -477.44107) (xy 39.012114 -477.44536) (xy 39.058651 -477.44107)
			(xy 39.103619 -477.428344) (xy 39.145502 -477.407612) (xy 39.164514 -477.394016) (xy 39.186579 -477.378025)
			(xy 39.234405 -477.351903) (xy 39.285462 -477.332854) (xy 39.33871 -477.321265) (xy 39.393066 -477.317373)
			(xy 39.447422 -477.321255) (xy 39.500672 -477.332835) (xy 39.551732 -477.351875) (xy 39.599563 -477.377988)
			(xy 39.64319 -477.410642) (xy 39.681726 -477.449173) (xy 39.714386 -477.492796) (xy 39.740505 -477.540624)
			(xy 39.759552 -477.591681) (xy 39.771138 -477.64493) (xy 39.775027 -477.699286) (xy 40.135887 -477.699286)
			(xy 40.139777 -477.64493) (xy 40.151364 -477.591681) (xy 40.170411 -477.540624) (xy 40.196531 -477.492797)
			(xy 40.229192 -477.449175) (xy 40.267729 -477.410645) (xy 40.311357 -477.377992) (xy 40.359189 -477.351881)
			(xy 40.41025 -477.332843) (xy 40.463501 -477.321267) (xy 40.517857 -477.317387) (xy 40.572212 -477.321283)
			(xy 40.62546 -477.332876) (xy 40.676515 -477.351928) (xy 40.724339 -477.378054) (xy 40.746426 -477.394016)
			(xy 40.765438 -477.407612) (xy 40.807321 -477.428344) (xy 40.852289 -477.44107) (xy 40.898826 -477.44536)
			(xy 40.945363 -477.44107) (xy 40.990331 -477.428344) (xy 41.032214 -477.407612) (xy 41.051226 -477.394016)
			(xy 41.073291 -477.378026) (xy 41.121116 -477.351906) (xy 41.172172 -477.332859) (xy 41.225419 -477.321271)
			(xy 41.279772 -477.31738) (xy 41.334127 -477.321263) (xy 41.387375 -477.332843) (xy 41.438433 -477.351883)
			(xy 41.486262 -477.377996) (xy 41.529888 -477.41065) (xy 41.568423 -477.44918) (xy 41.601081 -477.492802)
			(xy 41.627199 -477.540628) (xy 41.646245 -477.591685) (xy 41.657831 -477.644932) (xy 41.66172 -477.699286)
			(xy 42.377022 -477.699286) (xy 42.380911 -477.644938) (xy 42.392495 -477.591697) (xy 42.411539 -477.540647)
			(xy 42.437653 -477.492826) (xy 42.470308 -477.449209) (xy 42.508838 -477.410683) (xy 42.552458 -477.378033)
			(xy 42.600282 -477.351922) (xy 42.651334 -477.332884) (xy 42.704576 -477.321306) (xy 42.758924 -477.317422)
			(xy 42.813272 -477.321312) (xy 42.866512 -477.332898) (xy 42.917562 -477.351943) (xy 42.965382 -477.378059)
			(xy 42.987468 -477.394016) (xy 43.00648 -477.407612) (xy 43.048363 -477.428344) (xy 43.093331 -477.44107)
			(xy 43.139868 -477.44536) (xy 43.186405 -477.44107) (xy 43.231373 -477.428344) (xy 43.273256 -477.407612)
			(xy 43.292268 -477.394016) (xy 43.314334 -477.378021) (xy 43.362164 -477.351892) (xy 43.413225 -477.332836)
			(xy 43.466478 -477.321242) (xy 43.520839 -477.317345) (xy 43.575202 -477.321225) (xy 43.628459 -477.332802)
			(xy 43.679526 -477.351842) (xy 43.727364 -477.377955) (xy 43.770997 -477.410612) (xy 43.809539 -477.449146)
			(xy 43.842204 -477.492773) (xy 43.868327 -477.540606) (xy 43.887377 -477.591669) (xy 43.898965 -477.644924)
			(xy 43.902855 -477.699286) (xy 44.281031 -477.699286) (xy 44.28492 -477.64494) (xy 44.296504 -477.591701)
			(xy 44.315546 -477.540653) (xy 44.34166 -477.492834) (xy 44.374313 -477.449218) (xy 44.41284 -477.410693)
			(xy 44.456459 -477.378044) (xy 44.50428 -477.351934) (xy 44.55533 -477.332896) (xy 44.608569 -477.321316)
			(xy 44.662915 -477.317431) (xy 44.717261 -477.32132) (xy 44.770499 -477.332904) (xy 44.821548 -477.351947)
			(xy 44.869367 -477.37806) (xy 44.891452 -477.394016) (xy 44.910464 -477.407612) (xy 44.952347 -477.428344)
			(xy 44.997315 -477.44107) (xy 45.043852 -477.44536) (xy 45.090389 -477.44107) (xy 45.135357 -477.428344)
			(xy 45.17724 -477.407612) (xy 45.196252 -477.394016) (xy 45.218319 -477.37802) (xy 45.266149 -477.351888)
			(xy 45.317212 -477.33283) (xy 45.370467 -477.321234) (xy 45.42483 -477.317336) (xy 45.479195 -477.321214)
			(xy 45.532455 -477.332791) (xy 45.583524 -477.35183) (xy 45.631364 -477.377944) (xy 45.675 -477.410601)
			(xy 45.713544 -477.449137) (xy 45.74621 -477.492765) (xy 45.772335 -477.540599) (xy 45.791385 -477.591665)
			(xy 45.802974 -477.644922) (xy 45.806865 -477.699286) (xy 45.802978 -477.75365) (xy 45.791866 -477.804734)
			(xy 74.887582 -477.804734) (xy 74.888066 -477.726859) (xy 74.895869 -477.571306) (xy 74.911442 -477.416337)
			(xy 74.934747 -477.262341) (xy 74.965724 -477.109703) (xy 75.004296 -476.958806) (xy 75.050368 -476.810026)
			(xy 75.103822 -476.663738) (xy 75.164527 -476.520305) (xy 75.232329 -476.380089) (xy 75.307059 -476.243438)
			(xy 75.38853 -476.110697) (xy 75.476538 -475.982196) (xy 75.570863 -475.858258) (xy 75.671268 -475.739192)
			(xy 75.777503 -475.625298) (xy 75.889301 -475.516859) (xy 75.947524 -475.46514) (xy 76.008014 -475.412661)
			(xy 76.133594 -475.313261) (xy 76.264126 -475.220458) (xy 76.399265 -475.134501) (xy 76.53865 -475.055617)
			(xy 76.681912 -474.984015) (xy 76.828672 -474.919886) (xy 76.978539 -474.863399) (xy 77.131117 -474.814705)
			(xy 77.285999 -474.773932) (xy 77.442776 -474.74119) (xy 77.60103 -474.716564) (xy 77.760343 -474.70012)
			(xy 77.920291 -474.691902) (xy 78.08045 -474.691931) (xy 78.240395 -474.700208) (xy 78.399702 -474.71671)
			(xy 78.557948 -474.741394) (xy 78.714712 -474.774195) (xy 78.86958 -474.815024) (xy 79.022139 -474.863774)
			(xy 79.171985 -474.920316) (xy 79.318722 -474.984499) (xy 79.461958 -475.056154) (xy 79.601314 -475.135089)
			(xy 79.736421 -475.221096) (xy 79.866919 -475.313946) (xy 79.992463 -475.413393) (xy 80.052926 -475.465902)
			(xy 80.111074 -475.517651) (xy 80.22278 -475.62608) (xy 80.328926 -475.739959) (xy 80.429246 -475.859002)
			(xy 80.523489 -475.982912) (xy 80.611419 -476.111379) (xy 80.692816 -476.244081) (xy 80.767477 -476.380687)
			(xy 80.835215 -476.520854) (xy 80.89586 -476.664233) (xy 80.949261 -476.810464) (xy 80.995285 -476.959183)
			(xy 81.033815 -477.110016) (xy 81.064757 -477.262588) (xy 81.088032 -477.416515) (xy 81.103582 -477.571413)
			(xy 81.111368 -477.726895) (xy 81.111852 -477.804734) (xy 81.111852 -478.795334) (xy 81.111371 -478.874704)
			(xy 81.103273 -479.033238) (xy 81.087104 -479.191153) (xy 81.062907 -479.348038) (xy 81.030744 -479.503486)
			(xy 80.9907 -479.657093) (xy 80.942878 -479.808459) (xy 80.887402 -479.95719) (xy 80.824417 -480.1029)
			(xy 80.754087 -480.24521) (xy 80.676594 -480.383751) (xy 80.59214 -480.518161) (xy 80.500944 -480.648091)
			(xy 80.403245 -480.773204) (xy 80.299294 -480.893175) (xy 80.189364 -481.00769) (xy 80.073739 -481.116454)
			(xy 80.013556 -481.168202) (xy 79.953637 -481.218513) (xy 79.829479 -481.313747) (xy 79.700688 -481.402615)
			(xy 79.567588 -481.484891) (xy 79.430517 -481.560366) (xy 79.289823 -481.628849) (xy 79.145862 -481.690167)
			(xy 78.998998 -481.744164) (xy 78.849603 -481.790704) (xy 78.698055 -481.829669) (xy 78.54474 -481.86096)
			(xy 78.390044 -481.884498) (xy 78.23436 -481.900223) (xy 78.078082 -481.908096) (xy 77.921606 -481.908096)
			(xy 77.765328 -481.900223) (xy 77.609644 -481.884498) (xy 77.454948 -481.86096) (xy 77.301633 -481.829669)
			(xy 77.150085 -481.790704) (xy 77.00069 -481.744164) (xy 76.853826 -481.690167) (xy 76.709865 -481.628849)
			(xy 76.569171 -481.560366) (xy 76.4321 -481.484891) (xy 76.299 -481.402615) (xy 76.170209 -481.313747)
			(xy 76.046051 -481.218513) (xy 75.986132 -481.168202) (xy 75.925932 -481.116473) (xy 75.810304 -481.007712)
			(xy 75.700371 -480.893197) (xy 75.596418 -480.773228) (xy 75.498717 -480.648114) (xy 75.407521 -480.518183)
			(xy 75.323067 -480.383772) (xy 75.245575 -480.24523) (xy 75.175246 -480.102918) (xy 75.112264 -479.957206)
			(xy 75.056791 -479.808472) (xy 75.008974 -479.657104) (xy 74.968934 -479.503495) (xy 74.936778 -479.348044)
			(xy 74.912588 -479.191157) (xy 74.896428 -479.03324) (xy 74.888339 -478.874705) (xy 74.887836 -478.795334)
			(xy 74.887582 -477.804734) (xy 45.791866 -477.804734) (xy 45.791393 -477.806908) (xy 45.772347 -477.857974)
			(xy 45.746226 -477.90581) (xy 45.713562 -477.949442) (xy 45.675022 -477.98798) (xy 45.631388 -478.02064)
			(xy 45.58355 -478.046758) (xy 45.532482 -478.065801) (xy 45.479224 -478.077382) (xy 45.424859 -478.081265)
			(xy 45.370495 -478.07737) (xy 45.317239 -478.065778) (xy 45.266175 -478.046724) (xy 45.218343 -478.020596)
			(xy 45.196252 -478.004632) (xy 45.17724 -477.991036) (xy 45.135357 -477.970304) (xy 45.090389 -477.957578)
			(xy 45.043852 -477.953288) (xy 44.997315 -477.957578) (xy 44.952347 -477.970304) (xy 44.910464 -477.991036)
			(xy 44.891452 -478.004632) (xy 44.869342 -478.020556) (xy 44.821522 -478.046665) (xy 44.770472 -478.065704)
			(xy 44.717232 -478.077284) (xy 44.662886 -478.081169) (xy 44.608541 -478.07728) (xy 44.555302 -478.065696)
			(xy 44.504253 -478.046654) (xy 44.456435 -478.020541) (xy 44.412819 -477.987888) (xy 44.374294 -477.94936)
			(xy 44.341644 -477.905742) (xy 44.315534 -477.857921) (xy 44.296496 -477.806871) (xy 44.284916 -477.753631)
			(xy 44.281031 -477.699286) (xy 43.902855 -477.699286) (xy 43.898969 -477.753648) (xy 43.887385 -477.806903)
			(xy 43.868339 -477.857968) (xy 43.84222 -477.905802) (xy 43.809558 -477.949432) (xy 43.771019 -477.987969)
			(xy 43.727388 -478.020629) (xy 43.679552 -478.046746) (xy 43.628487 -478.06579) (xy 43.57523 -478.077371)
			(xy 43.520868 -478.081255) (xy 43.466506 -478.077362) (xy 43.413252 -478.065772) (xy 43.36219 -478.04672)
			(xy 43.314359 -478.020595) (xy 43.292268 -478.004632) (xy 43.273256 -477.991036) (xy 43.231373 -477.970304)
			(xy 43.186405 -477.957578) (xy 43.139868 -477.953288) (xy 43.093331 -477.957578) (xy 43.048363 -477.970304)
			(xy 43.00648 -477.991036) (xy 42.987468 -478.004632) (xy 42.965358 -478.020557) (xy 42.917536 -478.046669)
			(xy 42.866485 -478.06571) (xy 42.813243 -478.077292) (xy 42.758895 -478.081178) (xy 42.704548 -478.07729)
			(xy 42.651306 -478.065708) (xy 42.600255 -478.046666) (xy 42.552434 -478.020552) (xy 42.508816 -477.987898)
			(xy 42.470289 -477.949369) (xy 42.437638 -477.90575) (xy 42.411527 -477.857927) (xy 42.392487 -477.806875)
			(xy 42.380907 -477.753634) (xy 42.377022 -477.699286) (xy 41.66172 -477.699286) (xy 41.657835 -477.75364)
			(xy 41.646253 -477.806888) (xy 41.627211 -477.857946) (xy 41.601097 -477.905774) (xy 41.568441 -477.949398)
			(xy 41.52991 -477.987931) (xy 41.486287 -478.020588) (xy 41.43846 -478.046705) (xy 41.387403 -478.065749)
			(xy 41.334155 -478.077332) (xy 41.279801 -478.08122) (xy 41.225447 -478.077333) (xy 41.172199 -478.065749)
			(xy 41.121142 -478.046706) (xy 41.073315 -478.02059) (xy 41.051226 -478.004632) (xy 41.032214 -477.991036)
			(xy 40.990331 -477.970304) (xy 40.945363 -477.957578) (xy 40.898826 -477.953288) (xy 40.852289 -477.957578)
			(xy 40.807321 -477.970304) (xy 40.765438 -477.991036) (xy 40.746426 -478.004632) (xy 40.724315 -478.020562)
			(xy 40.676489 -478.046684) (xy 40.625432 -478.065733) (xy 40.572184 -478.077321) (xy 40.517828 -478.081213)
			(xy 40.463472 -478.077329) (xy 40.410223 -478.065749) (xy 40.359163 -478.046707) (xy 40.311333 -478.020593)
			(xy 40.267707 -477.987936) (xy 40.229173 -477.949404) (xy 40.196515 -477.905779) (xy 40.170399 -477.85795)
			(xy 40.151355 -477.806891) (xy 40.139773 -477.753641) (xy 40.135887 -477.699286) (xy 39.775027 -477.699286)
			(xy 39.771142 -477.753641) (xy 39.75956 -477.806891) (xy 39.740517 -477.85795) (xy 39.714402 -477.90578)
			(xy 39.681745 -477.949405) (xy 39.643212 -477.987939) (xy 39.599587 -478.020597) (xy 39.551758 -478.046713)
			(xy 39.500699 -478.065757) (xy 39.44745 -478.07734) (xy 39.393094 -478.081227) (xy 39.338739 -478.077339)
			(xy 39.28549 -478.065754) (xy 39.234432 -478.046709) (xy 39.186604 -478.020591) (xy 39.164514 -478.004632)
			(xy 39.145502 -477.991036) (xy 39.103619 -477.970304) (xy 39.058651 -477.957578) (xy 39.012114 -477.953288)
			(xy 38.965577 -477.957578) (xy 38.920609 -477.970304) (xy 38.878726 -477.991036) (xy 38.859714 -478.004632)
			(xy 38.837603 -478.020561) (xy 38.789778 -478.046681) (xy 38.738722 -478.065728) (xy 38.685475 -478.077315)
			(xy 38.631122 -478.081206) (xy 38.576767 -478.077321) (xy 38.523519 -478.06574) (xy 38.472461 -478.046699)
			(xy 38.424633 -478.020584) (xy 38.381009 -477.987929) (xy 38.342476 -477.949397) (xy 38.30982 -477.905773)
			(xy 38.283704 -477.857945) (xy 38.264662 -477.806888) (xy 38.25308 -477.75364) (xy 38.249194 -477.699286)
			(xy 36.237641 -477.699286) (xy 36.204933 -477.735165) (xy 36.140713 -477.793709) (xy 36.071366 -477.846078)
			(xy 35.997482 -477.891825) (xy 35.919693 -477.930559) (xy 35.838661 -477.961951) (xy 35.755079 -477.985732)
			(xy 35.669659 -478.0017) (xy 35.58313 -478.009718) (xy 35.49623 -478.009718) (xy 35.409701 -478.0017)
			(xy 35.324281 -477.985732) (xy 35.240699 -477.961951) (xy 35.159667 -477.930559) (xy 35.081878 -477.891825)
			(xy 35.007994 -477.846078) (xy 34.938647 -477.793709) (xy 34.874427 -477.735165) (xy 34.815883 -477.670945)
			(xy 34.763514 -477.601598) (xy 34.717767 -477.527714) (xy 34.679033 -477.449925) (xy 34.647641 -477.368893)
			(xy 34.62386 -477.285311) (xy 34.607892 -477.199891) (xy 34.599874 -477.113362) (xy 31.399486 -477.113362)
			(xy 31.391468 -477.199891) (xy 31.3755 -477.285311) (xy 31.351719 -477.368893) (xy 31.320327 -477.449925)
			(xy 31.281593 -477.527714) (xy 31.235846 -477.601598) (xy 31.183477 -477.670945) (xy 31.124933 -477.735165)
			(xy 31.060713 -477.793709) (xy 30.991366 -477.846078) (xy 30.917482 -477.891825) (xy 30.839693 -477.930559)
			(xy 30.758661 -477.961951) (xy 30.675079 -477.985732) (xy 30.589659 -478.0017) (xy 30.50313 -478.009718)
			(xy 30.41623 -478.009718) (xy 30.329701 -478.0017) (xy 30.244281 -477.985732) (xy 30.160699 -477.961951)
			(xy 30.079667 -477.930559) (xy 30.001878 -477.891825) (xy 29.927994 -477.846078) (xy 29.858647 -477.793709)
			(xy 29.794427 -477.735165) (xy 29.735883 -477.670945) (xy 29.683514 -477.601598) (xy 29.637767 -477.527714)
			(xy 29.599033 -477.449925) (xy 29.567641 -477.368893) (xy 29.54386 -477.285311) (xy 29.527892 -477.199891)
			(xy 29.519874 -477.113362) (xy 20.5945 -477.113362) (xy 20.55947 -477.15511) (xy 20.422513 -477.306034)
			(xy 20.279807 -477.451535) (xy 20.131566 -477.591393) (xy 19.978014 -477.725397) (xy 19.819381 -477.853347)
			(xy 19.655906 -477.97505) (xy 19.487835 -478.090322) (xy 19.315421 -478.19899) (xy 19.138923 -478.300892)
			(xy 18.958606 -478.395872) (xy 18.774742 -478.48379) (xy 18.587607 -478.564512) (xy 18.397483 -478.637917)
			(xy 18.204656 -478.703895) (xy 18.009415 -478.762346) (xy 17.812055 -478.813183) (xy 17.612871 -478.856329)
			(xy 17.412165 -478.891719) (xy 17.210237 -478.9193) (xy 17.007392 -478.93903) (xy 16.803934 -478.95088)
			(xy 16.60017 -478.954832) (xy 16.396406 -478.95088) (xy 16.192948 -478.93903) (xy 15.990103 -478.9193)
			(xy 15.788175 -478.891719) (xy 15.587469 -478.856329) (xy 15.388285 -478.813183) (xy 15.190925 -478.762346)
			(xy 14.995684 -478.703895) (xy 14.802857 -478.637917) (xy 14.612733 -478.564512) (xy 14.425598 -478.48379)
			(xy 14.241734 -478.395872) (xy 14.061417 -478.300892) (xy 13.884919 -478.19899) (xy 13.712505 -478.090322)
			(xy 13.544434 -477.97505) (xy 13.380959 -477.853347) (xy 13.222326 -477.725397) (xy 13.068774 -477.591393)
			(xy 12.920533 -477.451535) (xy 12.777827 -477.306034) (xy 12.64087 -477.15511) (xy 12.509869 -476.998988)
			(xy 12.385019 -476.837904) (xy 12.266509 -476.6721) (xy 12.154518 -476.501825) (xy 12.049213 -476.327336)
			(xy 11.950754 -476.148895) (xy 11.859287 -475.96677) (xy 11.774952 -475.781236) (xy 11.697874 -475.592571)
			(xy 11.628169 -475.401059) (xy 11.565943 -475.206989) (xy 11.511289 -475.010651) (xy 11.464288 -474.812342)
			(xy 11.425013 -474.61236) (xy 11.393522 -474.411005) (xy 11.369862 -474.20858) (xy 11.354069 -474.005391)
			(xy 11.346166 -473.801741) (xy 11.345672 -473.69984) (xy 6.578101 -473.69984) (xy 6.590836 -473.720407)
			(xy 6.629047 -473.797146) (xy 6.660015 -473.877083) (xy 6.683475 -473.959536) (xy 6.699227 -474.043803)
			(xy 6.707137 -474.129163) (xy 6.707632 -474.172026) (xy 6.707137 -474.214889) (xy 6.699227 -474.300249)
			(xy 6.683475 -474.384516) (xy 6.660015 -474.466969) (xy 6.629047 -474.546906) (xy 6.590836 -474.623645)
			(xy 6.545707 -474.696531) (xy 6.494046 -474.764942) (xy 6.436292 -474.828294) (xy 6.37294 -474.886048)
			(xy 6.304529 -474.937709) (xy 6.231643 -474.982838) (xy 6.154904 -475.021049) (xy 6.074967 -475.052017)
			(xy 5.992514 -475.075477) (xy 5.908247 -475.091229) (xy 5.822887 -475.099139) (xy 5.737161 -475.099139)
			(xy 5.651801 -475.091229) (xy 5.567534 -475.075477) (xy 5.485081 -475.052017) (xy 5.405144 -475.021049)
			(xy 5.328405 -474.982838) (xy 5.255519 -474.937709) (xy 5.187108 -474.886048) (xy 5.123756 -474.828294)
			(xy 5.066002 -474.764942) (xy 5.014341 -474.696531) (xy 4.969212 -474.623645) (xy 4.931001 -474.546906)
			(xy 4.900033 -474.466969) (xy 4.876573 -474.384516) (xy 4.860821 -474.300249) (xy 4.852911 -474.214889)
			(xy 1.27 -474.214889) (xy 1.27 -477.214883) (xy 4.852911 -477.214883) (xy 4.852911 -477.129157) (xy 4.860821 -477.043797)
			(xy 4.876573 -476.95953) (xy 4.900033 -476.877077) (xy 4.931001 -476.79714) (xy 4.969212 -476.720401)
			(xy 5.014341 -476.647515) (xy 5.066002 -476.579104) (xy 5.123756 -476.515752) (xy 5.187108 -476.457998)
			(xy 5.255519 -476.406337) (xy 5.328405 -476.361208) (xy 5.405144 -476.322997) (xy 5.485081 -476.292029)
			(xy 5.567534 -476.268569) (xy 5.651801 -476.252817) (xy 5.737161 -476.244907) (xy 5.822887 -476.244907)
			(xy 5.908247 -476.252817) (xy 5.992514 -476.268569) (xy 6.074967 -476.292029) (xy 6.154904 -476.322997)
			(xy 6.231643 -476.361208) (xy 6.304529 -476.406337) (xy 6.37294 -476.457998) (xy 6.436292 -476.515752)
			(xy 6.494046 -476.579104) (xy 6.545707 -476.647515) (xy 6.590836 -476.720401) (xy 6.629047 -476.79714)
			(xy 6.660015 -476.877077) (xy 6.683475 -476.95953) (xy 6.699227 -477.043797) (xy 6.707137 -477.129157)
			(xy 6.707632 -477.17202) (xy 6.707137 -477.214883) (xy 6.699227 -477.300243) (xy 6.683475 -477.38451)
			(xy 6.660015 -477.466963) (xy 6.629047 -477.5469) (xy 6.590836 -477.623639) (xy 6.545707 -477.696525)
			(xy 6.494046 -477.764936) (xy 6.436292 -477.828288) (xy 6.37294 -477.886042) (xy 6.304529 -477.937703)
			(xy 6.231643 -477.982832) (xy 6.154904 -478.021043) (xy 6.074967 -478.052011) (xy 5.992514 -478.075471)
			(xy 5.908247 -478.091223) (xy 5.822887 -478.099133) (xy 5.737161 -478.099133) (xy 5.651801 -478.091223)
			(xy 5.567534 -478.075471) (xy 5.485081 -478.052011) (xy 5.405144 -478.021043) (xy 5.328405 -477.982832)
			(xy 5.255519 -477.937703) (xy 5.187108 -477.886042) (xy 5.123756 -477.828288) (xy 5.066002 -477.764936)
			(xy 5.014341 -477.696525) (xy 4.969212 -477.623639) (xy 4.931001 -477.5469) (xy 4.900033 -477.466963)
			(xy 4.876573 -477.38451) (xy 4.860821 -477.300243) (xy 4.852911 -477.214883) (xy 1.27 -477.214883)
			(xy 1.27 -480.172014) (xy 6.671831 -480.172014) (xy 6.675786 -480.080177) (xy 6.687621 -479.98902)
			(xy 6.707248 -479.899217) (xy 6.734522 -479.811435) (xy 6.769242 -479.726321) (xy 6.81115 -479.644508)
			(xy 6.859936 -479.5666) (xy 6.915239 -479.493175) (xy 6.976649 -479.424775) (xy 7.043711 -479.361908)
			(xy 7.11593 -479.305038) (xy 7.19277 -479.254587) (xy 7.273663 -479.210928) (xy 7.358009 -479.174385)
			(xy 7.445185 -479.145228) (xy 7.534544 -479.123674) (xy 7.625425 -479.10988) (xy 7.717156 -479.10395)
			(xy 7.809057 -479.105928) (xy 7.900448 -479.115799) (xy 7.990652 -479.133489) (xy 8.079001 -479.158869)
			(xy 8.164841 -479.191749) (xy 8.247537 -479.231887) (xy 8.326477 -479.278986) (xy 8.401075 -479.332696)
			(xy 8.470781 -479.39262) (xy 8.535076 -479.458314) (xy 8.593487 -479.529292) (xy 8.645579 -479.605029)
			(xy 8.673024 -479.653362) (xy 29.519874 -479.653362) (xy 29.519874 -479.566462) (xy 29.527892 -479.479933)
			(xy 29.54386 -479.394513) (xy 29.567641 -479.310931) (xy 29.599033 -479.229899) (xy 29.637767 -479.15211)
			(xy 29.683514 -479.078226) (xy 29.735883 -479.008879) (xy 29.794427 -478.944659) (xy 29.858647 -478.886115)
			(xy 29.927994 -478.833746) (xy 30.001878 -478.787999) (xy 30.079667 -478.749265) (xy 30.160699 -478.717873)
			(xy 30.244281 -478.694092) (xy 30.329701 -478.678124) (xy 30.41623 -478.670106) (xy 30.50313 -478.670106)
			(xy 30.589659 -478.678124) (xy 30.675079 -478.694092) (xy 30.758661 -478.717873) (xy 30.839693 -478.749265)
			(xy 30.917482 -478.787999) (xy 30.991366 -478.833746) (xy 31.060713 -478.886115) (xy 31.124933 -478.944659)
			(xy 31.183477 -479.008879) (xy 31.235846 -479.078226) (xy 31.281593 -479.15211) (xy 31.320327 -479.229899)
			(xy 31.351719 -479.310931) (xy 31.3755 -479.394513) (xy 31.391468 -479.479933) (xy 31.399486 -479.566462)
			(xy 31.399988 -479.609912) (xy 31.399486 -479.653362) (xy 34.599874 -479.653362) (xy 34.599874 -479.566462)
			(xy 34.607892 -479.479933) (xy 34.62386 -479.394513) (xy 34.647641 -479.310931) (xy 34.679033 -479.229899)
			(xy 34.717767 -479.15211) (xy 34.763514 -479.078226) (xy 34.815883 -479.008879) (xy 34.874427 -478.944659)
			(xy 34.938647 -478.886115) (xy 35.007994 -478.833746) (xy 35.081878 -478.787999) (xy 35.159667 -478.749265)
			(xy 35.240699 -478.717873) (xy 35.324281 -478.694092) (xy 35.409701 -478.678124) (xy 35.49623 -478.670106)
			(xy 35.58313 -478.670106) (xy 35.669659 -478.678124) (xy 35.755079 -478.694092) (xy 35.838661 -478.717873)
			(xy 35.919693 -478.749265) (xy 35.997482 -478.787999) (xy 36.071366 -478.833746) (xy 36.140713 -478.886115)
			(xy 36.204933 -478.944659) (xy 36.263477 -479.008879) (xy 36.315846 -479.078226) (xy 36.361593 -479.15211)
			(xy 36.400327 -479.229899) (xy 36.431719 -479.310931) (xy 36.449814 -479.374528) (xy 38.249138 -479.374528)
			(xy 38.253023 -479.320165) (xy 38.264604 -479.266909) (xy 38.283648 -479.215844) (xy 38.309765 -479.168008)
			(xy 38.342425 -479.124377) (xy 38.380962 -479.085838) (xy 38.424592 -479.053176) (xy 38.472426 -479.027056)
			(xy 38.523491 -479.00801) (xy 38.576746 -478.996425) (xy 38.631108 -478.992538) (xy 38.68547 -478.996428)
			(xy 38.738725 -479.008015) (xy 38.789789 -479.027063) (xy 38.837622 -479.053185) (xy 38.859714 -479.069146)
			(xy 38.878726 -479.082742) (xy 38.920609 -479.103474) (xy 38.965577 -479.1162) (xy 39.012114 -479.12049)
			(xy 39.058651 -479.1162) (xy 39.103619 -479.103474) (xy 39.145502 -479.082742) (xy 39.164514 -479.069146)
			(xy 39.186645 -479.053249) (xy 39.234467 -479.027137) (xy 39.285518 -479.008096) (xy 39.33876 -478.996515)
			(xy 39.393108 -478.992629) (xy 39.447455 -478.996517) (xy 39.500696 -479.0081) (xy 39.551747 -479.027143)
			(xy 39.599568 -479.053257) (xy 39.643185 -479.085912) (xy 39.681711 -479.124441) (xy 39.714362 -479.168062)
			(xy 39.740472 -479.215885) (xy 39.75951 -479.266937) (xy 39.771088 -479.32018) (xy 39.774971 -479.374528)
			(xy 40.135831 -479.374528) (xy 40.139716 -479.320164) (xy 40.151298 -479.266906) (xy 40.170342 -479.215839)
			(xy 40.196461 -479.168002) (xy 40.229122 -479.12437) (xy 40.26766 -479.08583) (xy 40.311292 -479.053167)
			(xy 40.359128 -479.027047) (xy 40.410194 -479.008001) (xy 40.463451 -478.996417) (xy 40.517815 -478.992531)
			(xy 40.572179 -478.996422) (xy 40.625435 -479.00801) (xy 40.6765 -479.02706) (xy 40.724334 -479.053184)
			(xy 40.746426 -479.069146) (xy 40.765438 -479.082742) (xy 40.807321 -479.103474) (xy 40.852289 -479.1162)
			(xy 40.898826 -479.12049) (xy 40.945363 -479.1162) (xy 40.990331 -479.103474) (xy 41.032214 -479.082742)
			(xy 41.051226 -479.069146) (xy 41.073357 -479.05325) (xy 41.121178 -479.02714) (xy 41.172228 -479.008101)
			(xy 41.225468 -478.996521) (xy 41.279814 -478.992636) (xy 41.33416 -478.996525) (xy 41.3874 -479.008109)
			(xy 41.438448 -479.027152) (xy 41.486267 -479.053266) (xy 41.529883 -479.08592) (xy 41.568408 -479.124448)
			(xy 41.601057 -479.168068) (xy 41.627166 -479.21589) (xy 41.646203 -479.266941) (xy 41.657781 -479.320181)
			(xy 41.661664 -479.374528) (xy 42.376966 -479.374528) (xy 42.38085 -479.320172) (xy 42.39243 -479.266921)
			(xy 42.41147 -479.215861) (xy 42.437584 -479.168031) (xy 42.470238 -479.124404) (xy 42.50877 -479.085868)
			(xy 42.552393 -479.053208) (xy 42.60022 -479.027089) (xy 42.651278 -479.008042) (xy 42.704527 -478.996456)
			(xy 42.758882 -478.992566) (xy 42.813238 -478.996451) (xy 42.866488 -479.008032) (xy 42.917547 -479.027074)
			(xy 42.965377 -479.053189) (xy 42.987468 -479.069146) (xy 43.00648 -479.082742) (xy 43.048363 -479.103474)
			(xy 43.093331 -479.1162) (xy 43.139868 -479.12049) (xy 43.186405 -479.1162) (xy 43.231373 -479.103474)
			(xy 43.273256 -479.082742) (xy 43.292268 -479.069146) (xy 43.3144 -479.053245) (xy 43.362225 -479.027126)
			(xy 43.413281 -479.008078) (xy 43.466528 -478.996492) (xy 43.520881 -478.992601) (xy 43.575236 -478.996486)
			(xy 43.628484 -479.008068) (xy 43.679541 -479.02711) (xy 43.727369 -479.053225) (xy 43.770992 -479.085882)
			(xy 43.809524 -479.124414) (xy 43.84218 -479.168039) (xy 43.868294 -479.215867) (xy 43.887335 -479.266925)
			(xy 43.898915 -479.320173) (xy 43.902799 -479.374528) (xy 44.280975 -479.374528) (xy 44.284859 -479.320174)
			(xy 44.296438 -479.266926) (xy 44.315478 -479.215868) (xy 44.34159 -479.168039) (xy 44.374243 -479.124413)
			(xy 44.412772 -479.085878) (xy 44.456393 -479.053219) (xy 44.504218 -479.0271) (xy 44.555274 -479.008054)
			(xy 44.60852 -478.996467) (xy 44.662873 -478.992575) (xy 44.717227 -478.996459) (xy 44.770475 -479.008039)
			(xy 44.821533 -479.027078) (xy 44.869362 -479.05319) (xy 44.891452 -479.069146) (xy 44.910464 -479.082742)
			(xy 44.952347 -479.103474) (xy 44.997315 -479.1162) (xy 45.043852 -479.12049) (xy 45.090389 -479.1162)
			(xy 45.135357 -479.103474) (xy 45.17724 -479.082742) (xy 45.196252 -479.069146) (xy 45.218384 -479.053244)
			(xy 45.266211 -479.027122) (xy 45.317268 -479.008072) (xy 45.370516 -478.996483) (xy 45.424872 -478.992592)
			(xy 45.479229 -478.996476) (xy 45.532479 -479.008057) (xy 45.583539 -479.027099) (xy 45.631369 -479.053214)
			(xy 45.674995 -479.085871) (xy 45.713529 -479.124405) (xy 45.746186 -479.168031) (xy 45.772301 -479.215861)
			(xy 45.791343 -479.266921) (xy 45.802924 -479.320171) (xy 45.806808 -479.374528) (xy 45.802917 -479.428884)
			(xy 45.791328 -479.482132) (xy 45.772278 -479.533189) (xy 45.746156 -479.581015) (xy 45.713493 -479.624637)
			(xy 45.674953 -479.663165) (xy 45.631322 -479.695816) (xy 45.583489 -479.721924) (xy 45.532426 -479.740959)
			(xy 45.479174 -479.752532) (xy 45.424817 -479.756408) (xy 45.370462 -479.752509) (xy 45.317215 -479.740912)
			(xy 45.26616 -479.721855) (xy 45.218338 -479.695726) (xy 45.196252 -479.679762) (xy 45.17724 -479.666166)
			(xy 45.135357 -479.645434) (xy 45.090389 -479.632708) (xy 45.043852 -479.628418) (xy 44.997315 -479.632708)
			(xy 44.952347 -479.645434) (xy 44.910464 -479.666166) (xy 44.891452 -479.679762) (xy 44.869408 -479.69578)
			(xy 44.821583 -479.721899) (xy 44.770528 -479.740946) (xy 44.717282 -479.752533) (xy 44.662928 -479.756425)
			(xy 44.608574 -479.752541) (xy 44.555326 -479.740962) (xy 44.504268 -479.721923) (xy 44.45644 -479.695811)
			(xy 44.412814 -479.663158) (xy 44.374279 -479.624629) (xy 44.34162 -479.581007) (xy 44.315501 -479.533182)
			(xy 44.296454 -479.482127) (xy 44.284867 -479.428881) (xy 44.280975 -479.374528) (xy 43.902799 -479.374528)
			(xy 43.898907 -479.428881) (xy 43.887319 -479.482128) (xy 43.868271 -479.533183) (xy 43.84215 -479.581007)
			(xy 43.809488 -479.624627) (xy 43.770951 -479.663155) (xy 43.727322 -479.695805) (xy 43.679491 -479.721913)
			(xy 43.628431 -479.740948) (xy 43.575181 -479.752522) (xy 43.520826 -479.756399) (xy 43.466473 -479.752501)
			(xy 43.413228 -479.740906) (xy 43.362175 -479.721852) (xy 43.314354 -479.695725) (xy 43.292268 -479.679762)
			(xy 43.273256 -479.666166) (xy 43.231373 -479.645434) (xy 43.186405 -479.632708) (xy 43.139868 -479.628418)
			(xy 43.093331 -479.632708) (xy 43.048363 -479.645434) (xy 43.00648 -479.666166) (xy 42.987468 -479.679762)
			(xy 42.965424 -479.695781) (xy 42.917598 -479.721903) (xy 42.866541 -479.740952) (xy 42.813293 -479.752541)
			(xy 42.758937 -479.756434) (xy 42.704581 -479.752552) (xy 42.651331 -479.740973) (xy 42.60027 -479.721934)
			(xy 42.552439 -479.695822) (xy 42.508811 -479.663168) (xy 42.470274 -479.624638) (xy 42.437613 -479.581015)
			(xy 42.411493 -479.533189) (xy 42.392445 -479.482131) (xy 42.380857 -479.428883) (xy 42.376966 -479.374528)
			(xy 41.661664 -479.374528) (xy 41.657773 -479.428873) (xy 41.646187 -479.482112) (xy 41.627143 -479.53316)
			(xy 41.601027 -479.580979) (xy 41.568372 -479.624593) (xy 41.529841 -479.663116) (xy 41.486221 -479.695764)
			(xy 41.438398 -479.721871) (xy 41.387347 -479.740907) (xy 41.334106 -479.752483) (xy 41.279759 -479.756364)
			(xy 41.225413 -479.752471) (xy 41.172175 -479.740884) (xy 41.121127 -479.721837) (xy 41.07331 -479.69572)
			(xy 41.051226 -479.679762) (xy 41.032214 -479.666166) (xy 40.990331 -479.645434) (xy 40.945363 -479.632708)
			(xy 40.898826 -479.628418) (xy 40.852289 -479.632708) (xy 40.807321 -479.645434) (xy 40.765438 -479.666166)
			(xy 40.746426 -479.679762) (xy 40.72438 -479.695786) (xy 40.67655 -479.721917) (xy 40.625488 -479.740974)
			(xy 40.572233 -479.75257) (xy 40.51787 -479.756469) (xy 40.463506 -479.752591) (xy 40.410247 -479.741014)
			(xy 40.359178 -479.721976) (xy 40.311338 -479.695862) (xy 40.267702 -479.663206) (xy 40.229158 -479.624672)
			(xy 40.196491 -479.581044) (xy 40.170365 -479.533211) (xy 40.151313 -479.482147) (xy 40.139723 -479.428891)
			(xy 40.135831 -479.374528) (xy 39.774971 -479.374528) (xy 39.77108 -479.428875) (xy 39.759494 -479.482116)
			(xy 39.740449 -479.533165) (xy 39.714332 -479.580985) (xy 39.681675 -479.6246) (xy 39.643143 -479.663124)
			(xy 39.599521 -479.695772) (xy 39.551697 -479.72188) (xy 39.500643 -479.740915) (xy 39.447401 -479.752491)
			(xy 39.393052 -479.756371) (xy 39.338705 -479.752477) (xy 39.285465 -479.740888) (xy 39.234417 -479.72184)
			(xy 39.186599 -479.695721) (xy 39.164514 -479.679762) (xy 39.145502 -479.666166) (xy 39.103619 -479.645434)
			(xy 39.058651 -479.632708) (xy 39.012114 -479.628418) (xy 38.965577 -479.632708) (xy 38.920609 -479.645434)
			(xy 38.878726 -479.666166) (xy 38.859714 -479.679762) (xy 38.837669 -479.695785) (xy 38.789839 -479.721914)
			(xy 38.738778 -479.74097) (xy 38.685525 -479.752564) (xy 38.631164 -479.756462) (xy 38.576801 -479.752582)
			(xy 38.523544 -479.741006) (xy 38.472476 -479.721967) (xy 38.424638 -479.695854) (xy 38.381004 -479.663198)
			(xy 38.342461 -479.624665) (xy 38.309795 -479.581038) (xy 38.283671 -479.533207) (xy 38.26462 -479.482144)
			(xy 38.25303 -479.428889) (xy 38.249138 -479.374528) (xy 36.449814 -479.374528) (xy 36.4555 -479.394513)
			(xy 36.471468 -479.479933) (xy 36.479486 -479.566462) (xy 36.479988 -479.609912) (xy 36.479486 -479.653362)
			(xy 36.471468 -479.739891) (xy 36.4555 -479.825311) (xy 36.431719 -479.908893) (xy 36.400327 -479.989925)
			(xy 36.361593 -480.067714) (xy 36.315846 -480.141598) (xy 36.263477 -480.210945) (xy 36.204933 -480.275165)
			(xy 36.140713 -480.333709) (xy 36.071366 -480.386078) (xy 35.997482 -480.431825) (xy 35.919693 -480.470559)
			(xy 35.838661 -480.501951) (xy 35.755079 -480.525732) (xy 35.669659 -480.5417) (xy 35.58313 -480.549718)
			(xy 35.49623 -480.549718) (xy 35.409701 -480.5417) (xy 35.324281 -480.525732) (xy 35.240699 -480.501951)
			(xy 35.159667 -480.470559) (xy 35.081878 -480.431825) (xy 35.007994 -480.386078) (xy 34.938647 -480.333709)
			(xy 34.874427 -480.275165) (xy 34.815883 -480.210945) (xy 34.763514 -480.141598) (xy 34.717767 -480.067714)
			(xy 34.679033 -479.989925) (xy 34.647641 -479.908893) (xy 34.62386 -479.825311) (xy 34.607892 -479.739891)
			(xy 34.599874 -479.653362) (xy 31.399486 -479.653362) (xy 31.391468 -479.739891) (xy 31.3755 -479.825311)
			(xy 31.351719 -479.908893) (xy 31.320327 -479.989925) (xy 31.281593 -480.067714) (xy 31.235846 -480.141598)
			(xy 31.183477 -480.210945) (xy 31.124933 -480.275165) (xy 31.060713 -480.333709) (xy 30.991366 -480.386078)
			(xy 30.917482 -480.431825) (xy 30.839693 -480.470559) (xy 30.758661 -480.501951) (xy 30.675079 -480.525732)
			(xy 30.589659 -480.5417) (xy 30.50313 -480.549718) (xy 30.41623 -480.549718) (xy 30.329701 -480.5417)
			(xy 30.244281 -480.525732) (xy 30.160699 -480.501951) (xy 30.079667 -480.470559) (xy 30.001878 -480.431825)
			(xy 29.927994 -480.386078) (xy 29.858647 -480.333709) (xy 29.794427 -480.275165) (xy 29.735883 -480.210945)
			(xy 29.683514 -480.141598) (xy 29.637767 -480.067714) (xy 29.599033 -479.989925) (xy 29.567641 -479.908893)
			(xy 29.54386 -479.825311) (xy 29.527892 -479.739891) (xy 29.519874 -479.653362) (xy 8.673024 -479.653362)
			(xy 8.690968 -479.684964) (xy 8.729318 -479.768504) (xy 8.760343 -479.855032) (xy 8.783816 -479.943907)
			(xy 8.799562 -480.034471) (xy 8.807464 -480.126053) (xy 8.807958 -480.172014) (xy 8.807464 -480.217975)
			(xy 8.799562 -480.309557) (xy 8.783816 -480.400121) (xy 8.760343 -480.488996) (xy 8.729318 -480.575524)
			(xy 8.690968 -480.659064) (xy 8.645579 -480.738999) (xy 8.593487 -480.814736) (xy 8.535076 -480.885714)
			(xy 8.470781 -480.951408) (xy 8.401075 -481.011332) (xy 8.326477 -481.065042) (xy 8.247537 -481.112141)
			(xy 8.164841 -481.152279) (xy 8.079001 -481.185159) (xy 7.990652 -481.210539) (xy 7.900448 -481.228229)
			(xy 7.809057 -481.2381) (xy 7.717156 -481.240078) (xy 7.625425 -481.234148) (xy 7.534544 -481.220354)
			(xy 7.445185 -481.1988) (xy 7.358009 -481.169643) (xy 7.273663 -481.1331) (xy 7.19277 -481.089441)
			(xy 7.11593 -481.03899) (xy 7.043711 -480.98212) (xy 6.976649 -480.919253) (xy 6.915239 -480.850853)
			(xy 6.859936 -480.777428) (xy 6.81115 -480.69952) (xy 6.769242 -480.617707) (xy 6.734522 -480.532593)
			(xy 6.707248 -480.444811) (xy 6.687621 -480.355008) (xy 6.675786 -480.263851) (xy 6.671831 -480.172014)
			(xy 1.27 -480.172014) (xy 1.27 -482.193362) (xy 29.519874 -482.193362) (xy 29.519874 -482.106462)
			(xy 29.527892 -482.019933) (xy 29.54386 -481.934513) (xy 29.567641 -481.850931) (xy 29.599033 -481.769899)
			(xy 29.637767 -481.69211) (xy 29.683514 -481.618226) (xy 29.735883 -481.548879) (xy 29.794427 -481.484659)
			(xy 29.858647 -481.426115) (xy 29.927994 -481.373746) (xy 30.001878 -481.327999) (xy 30.079667 -481.289265)
			(xy 30.160699 -481.257873) (xy 30.244281 -481.234092) (xy 30.329701 -481.218124) (xy 30.41623 -481.210106)
			(xy 30.50313 -481.210106) (xy 30.589659 -481.218124) (xy 30.675079 -481.234092) (xy 30.758661 -481.257873)
			(xy 30.839693 -481.289265) (xy 30.917482 -481.327999) (xy 30.991366 -481.373746) (xy 31.060713 -481.426115)
			(xy 31.124933 -481.484659) (xy 31.183477 -481.548879) (xy 31.235846 -481.618226) (xy 31.281593 -481.69211)
			(xy 31.320327 -481.769899) (xy 31.351719 -481.850931) (xy 31.3755 -481.934513) (xy 31.391468 -482.019933)
			(xy 31.399486 -482.106462) (xy 31.399988 -482.149912) (xy 31.399486 -482.193362) (xy 34.599874 -482.193362)
			(xy 34.599874 -482.106462) (xy 34.607892 -482.019933) (xy 34.62386 -481.934513) (xy 34.647641 -481.850931)
			(xy 34.679033 -481.769899) (xy 34.717767 -481.69211) (xy 34.763514 -481.618226) (xy 34.815883 -481.548879)
			(xy 34.874427 -481.484659) (xy 34.938647 -481.426115) (xy 35.007994 -481.373746) (xy 35.081878 -481.327999)
			(xy 35.159667 -481.289265) (xy 35.240699 -481.257873) (xy 35.324281 -481.234092) (xy 35.409701 -481.218124)
			(xy 35.49623 -481.210106) (xy 35.58313 -481.210106) (xy 35.669659 -481.218124) (xy 35.755079 -481.234092)
			(xy 35.838661 -481.257873) (xy 35.919693 -481.289265) (xy 35.997482 -481.327999) (xy 36.071366 -481.373746)
			(xy 36.087042 -481.385584) (xy 38.205816 -481.385584) (xy 38.209706 -481.331235) (xy 38.221291 -481.277993)
			(xy 38.240335 -481.226941) (xy 38.266451 -481.17912) (xy 38.299107 -481.135502) (xy 38.337638 -481.096975)
			(xy 38.38126 -481.064325) (xy 38.429085 -481.038215) (xy 38.480139 -481.019177) (xy 38.533383 -481.007599)
			(xy 38.587732 -481.003716) (xy 38.642081 -481.007608) (xy 38.695323 -481.019195) (xy 38.746374 -481.038242)
			(xy 38.794194 -481.06436) (xy 38.81628 -481.080318) (xy 38.835292 -481.093914) (xy 38.877175 -481.114646)
			(xy 38.922143 -481.127372) (xy 38.96868 -481.131662) (xy 39.015217 -481.127372) (xy 39.060185 -481.114646)
			(xy 39.102068 -481.093914) (xy 39.12108 -481.080318) (xy 39.143144 -481.064321) (xy 39.190973 -481.038194)
			(xy 39.242033 -481.01914) (xy 39.295285 -481.007547) (xy 39.349645 -481.003651) (xy 39.404006 -481.007531)
			(xy 39.457262 -481.019109) (xy 39.508327 -481.038148) (xy 39.556163 -481.064262) (xy 39.599796 -481.096918)
			(xy 39.638336 -481.135451) (xy 39.671 -481.179077) (xy 39.697122 -481.226909) (xy 39.716171 -481.277971)
			(xy 39.727759 -481.331224) (xy 39.731649 -481.385584) (xy 40.092509 -481.385584) (xy 40.096399 -481.331234)
			(xy 40.107984 -481.27799) (xy 40.127029 -481.226937) (xy 40.153146 -481.179114) (xy 40.185803 -481.135495)
			(xy 40.224336 -481.096967) (xy 40.26796 -481.064316) (xy 40.315787 -481.038206) (xy 40.366842 -481.019169)
			(xy 40.420088 -481.007591) (xy 40.474439 -481.003709) (xy 40.52879 -481.007602) (xy 40.582033 -481.019191)
			(xy 40.633085 -481.038239) (xy 40.680906 -481.064359) (xy 40.702992 -481.080318) (xy 40.722004 -481.093914)
			(xy 40.763887 -481.114646) (xy 40.808855 -481.127372) (xy 40.855392 -481.131662) (xy 40.901929 -481.127372)
			(xy 40.946897 -481.114646) (xy 40.98878 -481.093914) (xy 41.007792 -481.080318) (xy 41.029856 -481.064322)
			(xy 41.077684 -481.038197) (xy 41.128743 -481.019144) (xy 41.181993 -481.007553) (xy 41.236352 -481.003658)
			(xy 41.290711 -481.007539) (xy 41.343965 -481.019117) (xy 41.395029 -481.038157) (xy 41.442863 -481.06427)
			(xy 41.486494 -481.096926) (xy 41.525033 -481.135458) (xy 41.557695 -481.179083) (xy 41.583817 -481.226913)
			(xy 41.602865 -481.277974) (xy 41.614452 -481.331226) (xy 41.618342 -481.385584) (xy 42.333484 -481.385584)
			(xy 42.337374 -481.331228) (xy 42.348961 -481.277979) (xy 42.368009 -481.22692) (xy 42.394129 -481.179093)
			(xy 42.426791 -481.13547) (xy 42.465329 -481.09694) (xy 42.508959 -481.064287) (xy 42.556792 -481.038176)
			(xy 42.607854 -481.019139) (xy 42.661106 -481.007563) (xy 42.715463 -481.003684) (xy 42.769819 -481.007581)
			(xy 42.823067 -481.019174) (xy 42.874123 -481.038228) (xy 42.921947 -481.064355) (xy 42.944034 -481.080318)
			(xy 42.963046 -481.093914) (xy 43.004929 -481.114646) (xy 43.049897 -481.127372) (xy 43.096434 -481.131662)
			(xy 43.142971 -481.127372) (xy 43.187939 -481.114646) (xy 43.229822 -481.093914) (xy 43.248834 -481.080318)
			(xy 43.270897 -481.064326) (xy 43.318722 -481.038207) (xy 43.369777 -481.019161) (xy 43.423023 -481.007574)
			(xy 43.477376 -481.003683) (xy 43.531729 -481.007567) (xy 43.584977 -481.019147) (xy 43.636034 -481.038187)
			(xy 43.683862 -481.0643) (xy 43.727487 -481.096953) (xy 43.766021 -481.135483) (xy 43.798679 -481.179104)
			(xy 43.824796 -481.22693) (xy 43.843842 -481.277985) (xy 43.855427 -481.331231) (xy 43.859317 -481.385584)
			(xy 44.237494 -481.385584) (xy 44.241383 -481.33123) (xy 44.25297 -481.277983) (xy 44.272016 -481.226927)
			(xy 44.298136 -481.179101) (xy 44.330796 -481.135479) (xy 44.369332 -481.09695) (xy 44.412959 -481.064298)
			(xy 44.46079 -481.038188) (xy 44.51185 -481.01915) (xy 44.565099 -481.007574) (xy 44.619454 -481.003694)
			(xy 44.673808 -481.007589) (xy 44.727054 -481.019181) (xy 44.778108 -481.038232) (xy 44.825931 -481.064356)
			(xy 44.848018 -481.080318) (xy 44.86703 -481.093914) (xy 44.908913 -481.114646) (xy 44.953881 -481.127372)
			(xy 45.000418 -481.131662) (xy 45.046955 -481.127372) (xy 45.091923 -481.114646) (xy 45.133806 -481.093914)
			(xy 45.152818 -481.080318) (xy 45.174881 -481.064325) (xy 45.222707 -481.038203) (xy 45.273764 -481.019154)
			(xy 45.327012 -481.007566) (xy 45.381367 -481.003673) (xy 45.435722 -481.007556) (xy 45.488972 -481.019136)
			(xy 45.540032 -481.038176) (xy 45.587862 -481.064288) (xy 45.63149 -481.096943) (xy 45.670025 -481.135473)
			(xy 45.702685 -481.179096) (xy 45.728804 -481.226923) (xy 45.747851 -481.277981) (xy 45.759437 -481.331229)
			(xy 45.763327 -481.385584) (xy 45.759441 -481.43994) (xy 45.747859 -481.493189) (xy 45.728817 -481.544248)
			(xy 45.702702 -481.592077) (xy 45.670046 -481.635703) (xy 45.631513 -481.674237) (xy 45.587889 -481.706895)
			(xy 45.54006 -481.733012) (xy 45.489002 -481.752056) (xy 45.435753 -481.763639) (xy 45.381398 -481.767527)
			(xy 45.327042 -481.763639) (xy 45.273794 -481.752054) (xy 45.222736 -481.73301) (xy 45.174908 -481.706892)
			(xy 45.152818 -481.690934) (xy 45.133806 -481.677338) (xy 45.091923 -481.656606) (xy 45.046955 -481.64388)
			(xy 45.000418 -481.63959) (xy 44.953881 -481.64388) (xy 44.908913 -481.656606) (xy 44.86703 -481.677338)
			(xy 44.848018 -481.690934) (xy 44.825905 -481.70686) (xy 44.77808 -481.732981) (xy 44.727024 -481.752028)
			(xy 44.673777 -481.763616) (xy 44.619423 -481.767506) (xy 44.565068 -481.763622) (xy 44.51182 -481.752041)
			(xy 44.460761 -481.732999) (xy 44.412933 -481.706885) (xy 44.369308 -481.674229) (xy 44.330776 -481.635697)
			(xy 44.298119 -481.592073) (xy 44.272003 -481.544245) (xy 44.252961 -481.493187) (xy 44.241379 -481.439939)
			(xy 44.237494 -481.385584) (xy 43.859317 -481.385584) (xy 43.855432 -481.439938) (xy 43.843851 -481.493185)
			(xy 43.824809 -481.544242) (xy 43.798696 -481.592069) (xy 43.766041 -481.635694) (xy 43.727511 -481.674226)
			(xy 43.683888 -481.706884) (xy 43.636062 -481.733) (xy 43.585007 -481.752044) (xy 43.53176 -481.763628)
			(xy 43.477407 -481.767517) (xy 43.423054 -481.76363) (xy 43.369807 -481.752048) (xy 43.31875 -481.733006)
			(xy 43.270923 -481.706891) (xy 43.248834 -481.690934) (xy 43.229822 -481.677338) (xy 43.187939 -481.656606)
			(xy 43.142971 -481.64388) (xy 43.096434 -481.63959) (xy 43.049897 -481.64388) (xy 43.004929 -481.656606)
			(xy 42.963046 -481.677338) (xy 42.944034 -481.690934) (xy 42.921921 -481.706862) (xy 42.874094 -481.732985)
			(xy 42.823037 -481.752034) (xy 42.769788 -481.763624) (xy 42.715432 -481.767516) (xy 42.661075 -481.763633)
			(xy 42.607824 -481.752052) (xy 42.556763 -481.733011) (xy 42.508933 -481.706896) (xy 42.465306 -481.67424)
			(xy 42.426771 -481.635706) (xy 42.394113 -481.592081) (xy 42.367996 -481.544251) (xy 42.348952 -481.493191)
			(xy 42.33737 -481.439941) (xy 42.333484 -481.385584) (xy 41.618342 -481.385584) (xy 41.614456 -481.439944)
			(xy 41.602874 -481.493196) (xy 41.58383 -481.544258) (xy 41.557712 -481.59209) (xy 41.525053 -481.635718)
			(xy 41.486517 -481.674254) (xy 41.442889 -481.706913) (xy 41.395057 -481.73303) (xy 41.343995 -481.752074)
			(xy 41.290742 -481.763657) (xy 41.236383 -481.767542) (xy 41.182024 -481.763652) (xy 41.128772 -481.752064)
			(xy 41.077712 -481.733016) (xy 41.029882 -481.706895) (xy 41.007792 -481.690934) (xy 40.98878 -481.677338)
			(xy 40.946897 -481.656606) (xy 40.901929 -481.64388) (xy 40.855392 -481.63959) (xy 40.808855 -481.64388)
			(xy 40.763887 -481.656606) (xy 40.722004 -481.677338) (xy 40.702992 -481.690934) (xy 40.68088 -481.706858)
			(xy 40.633056 -481.732974) (xy 40.582003 -481.752018) (xy 40.528759 -481.763602) (xy 40.474408 -481.767491)
			(xy 40.420057 -481.763605) (xy 40.366812 -481.752023) (xy 40.315758 -481.732981) (xy 40.267934 -481.706867)
			(xy 40.224313 -481.674212) (xy 40.185783 -481.635682) (xy 40.153129 -481.59206) (xy 40.127016 -481.544235)
			(xy 40.107975 -481.49318) (xy 40.096394 -481.439935) (xy 40.092509 -481.385584) (xy 39.731649 -481.385584)
			(xy 39.727763 -481.439945) (xy 39.71618 -481.493199) (xy 39.697135 -481.544263) (xy 39.671017 -481.592096)
			(xy 39.638357 -481.635725) (xy 39.599819 -481.674262) (xy 39.556189 -481.706921) (xy 39.508356 -481.733039)
			(xy 39.457292 -481.752082) (xy 39.404037 -481.763665) (xy 39.349676 -481.767549) (xy 39.295316 -481.763658)
			(xy 39.242063 -481.752069) (xy 39.191001 -481.733019) (xy 39.143171 -481.706896) (xy 39.12108 -481.690934)
			(xy 39.102068 -481.677338) (xy 39.060185 -481.656606) (xy 39.015217 -481.64388) (xy 38.96868 -481.63959)
			(xy 38.922143 -481.64388) (xy 38.877175 -481.656606) (xy 38.835292 -481.677338) (xy 38.81628 -481.690934)
			(xy 38.794168 -481.706857) (xy 38.746345 -481.732971) (xy 38.695293 -481.752014) (xy 38.64205 -481.763596)
			(xy 38.587701 -481.767484) (xy 38.533352 -481.763597) (xy 38.480109 -481.752014) (xy 38.429057 -481.732972)
			(xy 38.381234 -481.706858) (xy 38.337614 -481.674204) (xy 38.299086 -481.635675) (xy 38.266434 -481.592054)
			(xy 38.240322 -481.54423) (xy 38.221282 -481.493177) (xy 38.209701 -481.439934) (xy 38.205816 -481.385584)
			(xy 36.087042 -481.385584) (xy 36.140713 -481.426115) (xy 36.204933 -481.484659) (xy 36.263477 -481.548879)
			(xy 36.315846 -481.618226) (xy 36.361593 -481.69211) (xy 36.400327 -481.769899) (xy 36.431719 -481.850931)
			(xy 36.4555 -481.934513) (xy 36.471468 -482.019933) (xy 36.479486 -482.106462) (xy 36.479988 -482.149912)
			(xy 36.479486 -482.193362) (xy 36.471468 -482.279891) (xy 36.4555 -482.365311) (xy 36.431719 -482.448893)
			(xy 36.400327 -482.529925) (xy 36.361593 -482.607714) (xy 36.315846 -482.681598) (xy 36.266279 -482.747235)
			(xy 47.507896 -482.747235) (xy 47.507896 -482.666125) (xy 47.515846 -482.585406) (xy 47.531669 -482.505855)
			(xy 47.555214 -482.428239) (xy 47.586253 -482.353303) (xy 47.624488 -482.281771) (xy 47.66955 -482.214331)
			(xy 47.721005 -482.151632) (xy 47.778358 -482.094279) (xy 47.841057 -482.042824) (xy 47.908497 -481.997762)
			(xy 47.980029 -481.959527) (xy 48.054965 -481.928488) (xy 48.132581 -481.904943) (xy 48.212132 -481.88912)
			(xy 48.292851 -481.88117) (xy 48.373961 -481.88117) (xy 48.45468 -481.88912) (xy 48.534231 -481.904943)
			(xy 48.611847 -481.928488) (xy 48.686783 -481.959527) (xy 48.758315 -481.997762) (xy 48.825755 -482.042824)
			(xy 48.888454 -482.094279) (xy 48.945807 -482.151632) (xy 48.997262 -482.214331) (xy 49.042324 -482.281771)
			(xy 49.080559 -482.353303) (xy 49.111598 -482.428239) (xy 49.135143 -482.505855) (xy 49.150966 -482.585406)
			(xy 49.158916 -482.666125) (xy 49.159414 -482.70668) (xy 49.158916 -482.747235) (xy 51.008016 -482.747235)
			(xy 51.008016 -482.666125) (xy 51.015966 -482.585406) (xy 51.031789 -482.505855) (xy 51.055334 -482.428239)
			(xy 51.086373 -482.353303) (xy 51.124608 -482.281771) (xy 51.16967 -482.214331) (xy 51.221125 -482.151632)
			(xy 51.278478 -482.094279) (xy 51.341177 -482.042824) (xy 51.408617 -481.997762) (xy 51.480149 -481.959527)
			(xy 51.555085 -481.928488) (xy 51.632701 -481.904943) (xy 51.712252 -481.88912) (xy 51.792971 -481.88117)
			(xy 51.874081 -481.88117) (xy 51.9548 -481.88912) (xy 52.034351 -481.904943) (xy 52.111967 -481.928488)
			(xy 52.186903 -481.959527) (xy 52.258435 -481.997762) (xy 52.325875 -482.042824) (xy 52.388574 -482.094279)
			(xy 52.445927 -482.151632) (xy 52.465152 -482.175058) (xy 69.1675 -482.175058) (xy 69.171571 -482.119436)
			(xy 69.183697 -482.064999) (xy 69.20362 -482.012908) (xy 69.230916 -481.964273) (xy 69.265002 -481.92013)
			(xy 69.305151 -481.881421) (xy 69.350509 -481.84897) (xy 69.400109 -481.823469) (xy 69.452893 -481.805462)
			(xy 69.507736 -481.795332) (xy 69.56347 -481.793295) (xy 69.618907 -481.799395) (xy 69.672864 -481.813501)
			(xy 69.724193 -481.835313) (xy 69.771799 -481.864367) (xy 69.814667 -481.900042) (xy 69.851884 -481.941579)
			(xy 69.882657 -481.988092) (xy 69.906329 -482.038589) (xy 69.922397 -482.091996) (xy 69.930517 -482.147172)
			(xy 69.931026 -482.175058) (xy 70.29653 -482.175058) (xy 70.300601 -482.119436) (xy 70.312727 -482.064999)
			(xy 70.33265 -482.012908) (xy 70.359946 -481.964273) (xy 70.394032 -481.92013) (xy 70.434181 -481.881421)
			(xy 70.479539 -481.84897) (xy 70.529139 -481.823469) (xy 70.581923 -481.805462) (xy 70.636766 -481.795332)
			(xy 70.6925 -481.793295) (xy 70.747937 -481.799395) (xy 70.801894 -481.813501) (xy 70.853223 -481.835313)
			(xy 70.900829 -481.864367) (xy 70.943697 -481.900042) (xy 70.980914 -481.941579) (xy 71.011687 -481.988092)
			(xy 71.035359 -482.038589) (xy 71.051427 -482.091996) (xy 71.059547 -482.147172) (xy 71.060056 -482.175058)
			(xy 71.4281 -482.175058) (xy 71.432171 -482.119436) (xy 71.444297 -482.064999) (xy 71.46422 -482.012908)
			(xy 71.491516 -481.964273) (xy 71.525602 -481.92013) (xy 71.565751 -481.881421) (xy 71.611109 -481.84897)
			(xy 71.660709 -481.823469) (xy 71.713493 -481.805462) (xy 71.768336 -481.795332) (xy 71.82407 -481.793295)
			(xy 71.879507 -481.799395) (xy 71.933464 -481.813501) (xy 71.984793 -481.835313) (xy 72.032399 -481.864367)
			(xy 72.075267 -481.900042) (xy 72.112484 -481.941579) (xy 72.143257 -481.988092) (xy 72.166929 -482.038589)
			(xy 72.182997 -482.091996) (xy 72.191117 -482.147172) (xy 72.191626 -482.175058) (xy 72.546716 -482.175058)
			(xy 72.550787 -482.119436) (xy 72.562913 -482.064999) (xy 72.582836 -482.012908) (xy 72.610132 -481.964273)
			(xy 72.644218 -481.92013) (xy 72.684367 -481.881421) (xy 72.729725 -481.84897) (xy 72.779325 -481.823469)
			(xy 72.832109 -481.805462) (xy 72.886952 -481.795332) (xy 72.942686 -481.793295) (xy 72.998123 -481.799395)
			(xy 73.05208 -481.813501) (xy 73.103409 -481.835313) (xy 73.151015 -481.864367) (xy 73.193883 -481.900042)
			(xy 73.2311 -481.941579) (xy 73.261873 -481.988092) (xy 73.285545 -482.038589) (xy 73.301613 -482.091996)
			(xy 73.309733 -482.147172) (xy 73.310242 -482.175058) (xy 73.309733 -482.202944) (xy 73.301613 -482.25812)
			(xy 73.285545 -482.311527) (xy 73.261873 -482.362024) (xy 73.2311 -482.408537) (xy 73.193883 -482.450074)
			(xy 73.151015 -482.485749) (xy 73.103409 -482.514803) (xy 73.05208 -482.536615) (xy 72.998123 -482.550721)
			(xy 72.942686 -482.556821) (xy 72.886952 -482.554784) (xy 72.832109 -482.544654) (xy 72.779325 -482.526647)
			(xy 72.729725 -482.501146) (xy 72.684367 -482.468695) (xy 72.644218 -482.429986) (xy 72.610132 -482.385843)
			(xy 72.582836 -482.337208) (xy 72.562913 -482.285117) (xy 72.550787 -482.23068) (xy 72.546716 -482.175058)
			(xy 72.191626 -482.175058) (xy 72.191117 -482.202944) (xy 72.182997 -482.25812) (xy 72.166929 -482.311527)
			(xy 72.143257 -482.362024) (xy 72.112484 -482.408537) (xy 72.075267 -482.450074) (xy 72.032399 -482.485749)
			(xy 71.984793 -482.514803) (xy 71.933464 -482.536615) (xy 71.879507 -482.550721) (xy 71.82407 -482.556821)
			(xy 71.768336 -482.554784) (xy 71.713493 -482.544654) (xy 71.660709 -482.526647) (xy 71.611109 -482.501146)
			(xy 71.565751 -482.468695) (xy 71.525602 -482.429986) (xy 71.491516 -482.385843) (xy 71.46422 -482.337208)
			(xy 71.444297 -482.285117) (xy 71.432171 -482.23068) (xy 71.4281 -482.175058) (xy 71.060056 -482.175058)
			(xy 71.059547 -482.202944) (xy 71.051427 -482.25812) (xy 71.035359 -482.311527) (xy 71.011687 -482.362024)
			(xy 70.980914 -482.408537) (xy 70.943697 -482.450074) (xy 70.900829 -482.485749) (xy 70.853223 -482.514803)
			(xy 70.801894 -482.536615) (xy 70.747937 -482.550721) (xy 70.6925 -482.556821) (xy 70.636766 -482.554784)
			(xy 70.581923 -482.544654) (xy 70.529139 -482.526647) (xy 70.479539 -482.501146) (xy 70.434181 -482.468695)
			(xy 70.394032 -482.429986) (xy 70.359946 -482.385843) (xy 70.33265 -482.337208) (xy 70.312727 -482.285117)
			(xy 70.300601 -482.23068) (xy 70.29653 -482.175058) (xy 69.931026 -482.175058) (xy 69.930517 -482.202944)
			(xy 69.922397 -482.25812) (xy 69.906329 -482.311527) (xy 69.882657 -482.362024) (xy 69.851884 -482.408537)
			(xy 69.814667 -482.450074) (xy 69.771799 -482.485749) (xy 69.724193 -482.514803) (xy 69.672864 -482.536615)
			(xy 69.618907 -482.550721) (xy 69.56347 -482.556821) (xy 69.507736 -482.554784) (xy 69.452893 -482.544654)
			(xy 69.400109 -482.526647) (xy 69.350509 -482.501146) (xy 69.305151 -482.468695) (xy 69.265002 -482.429986)
			(xy 69.230916 -482.385843) (xy 69.20362 -482.337208) (xy 69.183697 -482.285117) (xy 69.171571 -482.23068)
			(xy 69.1675 -482.175058) (xy 52.465152 -482.175058) (xy 52.497382 -482.214331) (xy 52.542444 -482.281771)
			(xy 52.580679 -482.353303) (xy 52.611718 -482.428239) (xy 52.635263 -482.505855) (xy 52.651086 -482.585406)
			(xy 52.659036 -482.666125) (xy 52.659534 -482.70668) (xy 52.659036 -482.747235) (xy 52.651086 -482.827954)
			(xy 52.635263 -482.907505) (xy 52.611718 -482.985121) (xy 52.580679 -483.060057) (xy 52.542444 -483.131589)
			(xy 52.497382 -483.199029) (xy 52.445927 -483.261728) (xy 52.388574 -483.319081) (xy 52.325875 -483.370536)
			(xy 52.258435 -483.415598) (xy 52.186903 -483.453833) (xy 52.111967 -483.484872) (xy 52.034351 -483.508417)
			(xy 51.9548 -483.52424) (xy 51.874081 -483.53219) (xy 51.792971 -483.53219) (xy 51.712252 -483.52424)
			(xy 51.632701 -483.508417) (xy 51.555085 -483.484872) (xy 51.480149 -483.453833) (xy 51.408617 -483.415598)
			(xy 51.341177 -483.370536) (xy 51.278478 -483.319081) (xy 51.221125 -483.261728) (xy 51.16967 -483.199029)
			(xy 51.124608 -483.131589) (xy 51.086373 -483.060057) (xy 51.055334 -482.985121) (xy 51.031789 -482.907505)
			(xy 51.015966 -482.827954) (xy 51.008016 -482.747235) (xy 49.158916 -482.747235) (xy 49.150966 -482.827954)
			(xy 49.135143 -482.907505) (xy 49.111598 -482.985121) (xy 49.080559 -483.060057) (xy 49.042324 -483.131589)
			(xy 48.997262 -483.199029) (xy 48.945807 -483.261728) (xy 48.888454 -483.319081) (xy 48.825755 -483.370536)
			(xy 48.758315 -483.415598) (xy 48.686783 -483.453833) (xy 48.611847 -483.484872) (xy 48.534231 -483.508417)
			(xy 48.45468 -483.52424) (xy 48.373961 -483.53219) (xy 48.292851 -483.53219) (xy 48.212132 -483.52424)
			(xy 48.132581 -483.508417) (xy 48.054965 -483.484872) (xy 47.980029 -483.453833) (xy 47.908497 -483.415598)
			(xy 47.841057 -483.370536) (xy 47.778358 -483.319081) (xy 47.721005 -483.261728) (xy 47.66955 -483.199029)
			(xy 47.624488 -483.131589) (xy 47.586253 -483.060057) (xy 47.555214 -482.985121) (xy 47.531669 -482.907505)
			(xy 47.515846 -482.827954) (xy 47.507896 -482.747235) (xy 36.266279 -482.747235) (xy 36.263477 -482.750945)
			(xy 36.204933 -482.815165) (xy 36.140713 -482.873709) (xy 36.071366 -482.926078) (xy 35.997482 -482.971825)
			(xy 35.919693 -483.010559) (xy 35.838661 -483.041951) (xy 35.755079 -483.065732) (xy 35.669659 -483.0817)
			(xy 35.58313 -483.089718) (xy 35.49623 -483.089718) (xy 35.409701 -483.0817) (xy 35.324281 -483.065732)
			(xy 35.240699 -483.041951) (xy 35.159667 -483.010559) (xy 35.081878 -482.971825) (xy 35.007994 -482.926078)
			(xy 34.938647 -482.873709) (xy 34.874427 -482.815165) (xy 34.815883 -482.750945) (xy 34.763514 -482.681598)
			(xy 34.717767 -482.607714) (xy 34.679033 -482.529925) (xy 34.647641 -482.448893) (xy 34.62386 -482.365311)
			(xy 34.607892 -482.279891) (xy 34.599874 -482.193362) (xy 31.399486 -482.193362) (xy 31.391468 -482.279891)
			(xy 31.3755 -482.365311) (xy 31.351719 -482.448893) (xy 31.320327 -482.529925) (xy 31.281593 -482.607714)
			(xy 31.235846 -482.681598) (xy 31.183477 -482.750945) (xy 31.124933 -482.815165) (xy 31.060713 -482.873709)
			(xy 30.991366 -482.926078) (xy 30.917482 -482.971825) (xy 30.839693 -483.010559) (xy 30.758661 -483.041951)
			(xy 30.675079 -483.065732) (xy 30.589659 -483.0817) (xy 30.50313 -483.089718) (xy 30.41623 -483.089718)
			(xy 30.329701 -483.0817) (xy 30.244281 -483.065732) (xy 30.160699 -483.041951) (xy 30.079667 -483.010559)
			(xy 30.001878 -482.971825) (xy 29.927994 -482.926078) (xy 29.858647 -482.873709) (xy 29.794427 -482.815165)
			(xy 29.735883 -482.750945) (xy 29.683514 -482.681598) (xy 29.637767 -482.607714) (xy 29.599033 -482.529925)
			(xy 29.567641 -482.448893) (xy 29.54386 -482.365311) (xy 29.527892 -482.279891) (xy 29.519874 -482.193362)
			(xy 1.27 -482.193362) (xy 1.27 -483.276071) (xy 38.205834 -483.276071) (xy 38.209725 -483.221725)
			(xy 38.221311 -483.168485) (xy 38.240356 -483.117437) (xy 38.266473 -483.069618) (xy 38.299129 -483.026003)
			(xy 38.33766 -482.98748) (xy 38.381281 -482.954832) (xy 38.429104 -482.928725) (xy 38.480157 -482.90969)
			(xy 38.533398 -482.898114) (xy 38.587745 -482.894234) (xy 38.642092 -482.898127) (xy 38.695331 -482.909716)
			(xy 38.746378 -482.928763) (xy 38.794196 -482.954882) (xy 38.81628 -482.97084) (xy 38.835292 -482.984436)
			(xy 38.877175 -483.005168) (xy 38.922143 -483.017894) (xy 38.96868 -483.022184) (xy 39.015217 -483.017894)
			(xy 39.060185 -483.005168) (xy 39.102068 -482.984436) (xy 39.12108 -482.97084) (xy 39.143124 -482.954814)
			(xy 39.190953 -482.928683) (xy 39.242015 -482.909627) (xy 39.295269 -482.898031) (xy 39.349632 -482.894133)
			(xy 39.403996 -482.898012) (xy 39.457254 -482.909588) (xy 39.508323 -482.928627) (xy 39.556162 -482.95474)
			(xy 39.599797 -482.987396) (xy 39.638341 -483.02593) (xy 39.671008 -483.069557) (xy 39.697133 -483.117389)
			(xy 39.716184 -483.168453) (xy 39.727774 -483.221708) (xy 39.731667 -483.276071) (xy 40.092527 -483.276071)
			(xy 40.096418 -483.221723) (xy 40.108005 -483.168482) (xy 40.12705 -483.117432) (xy 40.153168 -483.069612)
			(xy 40.185825 -483.025996) (xy 40.224358 -482.987472) (xy 40.267981 -482.954824) (xy 40.315806 -482.928717)
			(xy 40.36686 -482.909682) (xy 40.420103 -482.898106) (xy 40.474452 -482.894227) (xy 40.5288 -482.898121)
			(xy 40.58204 -482.909711) (xy 40.633089 -482.92876) (xy 40.680907 -482.954881) (xy 40.702992 -482.97084)
			(xy 40.722004 -482.984436) (xy 40.763887 -483.005168) (xy 40.808855 -483.017894) (xy 40.855392 -483.022184)
			(xy 40.901929 -483.017894) (xy 40.946897 -483.005168) (xy 40.98878 -482.984436) (xy 41.007792 -482.97084)
			(xy 41.029835 -482.954815) (xy 41.077664 -482.928686) (xy 41.128725 -482.909631) (xy 41.181978 -482.898037)
			(xy 41.236339 -482.89414) (xy 41.290701 -482.89802) (xy 41.343957 -482.909597) (xy 41.395024 -482.928635)
			(xy 41.442861 -482.954748) (xy 41.486495 -482.987404) (xy 41.525037 -483.025937) (xy 41.557703 -483.069563)
			(xy 41.583827 -483.117394) (xy 41.602878 -483.168456) (xy 41.614467 -483.22171) (xy 41.61836 -483.276071)
			(xy 42.333502 -483.276071) (xy 42.337393 -483.221717) (xy 42.348982 -483.168471) (xy 42.36803 -483.117416)
			(xy 42.394151 -483.069591) (xy 42.426813 -483.025972) (xy 42.465351 -482.987445) (xy 42.50898 -482.954795)
			(xy 42.556811 -482.928687) (xy 42.607872 -482.909652) (xy 42.661121 -482.898078) (xy 42.715476 -482.894202)
			(xy 42.769829 -482.8981) (xy 42.823075 -482.909695) (xy 42.874127 -482.92875) (xy 42.921948 -482.954877)
			(xy 42.944034 -482.97084) (xy 42.963046 -482.984436) (xy 43.004929 -483.005168) (xy 43.049897 -483.017894)
			(xy 43.096434 -483.022184) (xy 43.142971 -483.017894) (xy 43.187939 -483.005168) (xy 43.229822 -482.984436)
			(xy 43.248834 -482.97084) (xy 43.270876 -482.954818) (xy 43.318702 -482.928697) (xy 43.369759 -482.909647)
			(xy 43.423007 -482.898058) (xy 43.477362 -482.894165) (xy 43.531719 -482.898048) (xy 43.584969 -482.909626)
			(xy 43.636029 -482.928665) (xy 43.683861 -482.954778) (xy 43.727489 -482.987431) (xy 43.766025 -483.025961)
			(xy 43.798687 -483.069584) (xy 43.824807 -483.11741) (xy 43.843855 -483.168467) (xy 43.855443 -483.221716)
			(xy 43.859335 -483.276071) (xy 44.237511 -483.276071) (xy 44.241403 -483.22172) (xy 44.25299 -483.168475)
			(xy 44.272038 -483.117422) (xy 44.298158 -483.069599) (xy 44.330818 -483.025981) (xy 44.369354 -482.987455)
			(xy 44.41298 -482.954806) (xy 44.460809 -482.928698) (xy 44.511867 -482.909663) (xy 44.565115 -482.898089)
			(xy 44.619467 -482.894211) (xy 44.673818 -482.898108) (xy 44.727062 -482.909701) (xy 44.778113 -482.928754)
			(xy 44.825933 -482.954878) (xy 44.848018 -482.97084) (xy 44.86703 -482.984436) (xy 44.908913 -483.005168)
			(xy 44.953881 -483.017894) (xy 45.000418 -483.022184) (xy 45.046955 -483.017894) (xy 45.091923 -483.005168)
			(xy 45.133806 -482.984436) (xy 45.152818 -482.97084) (xy 45.174861 -482.954817) (xy 45.222688 -482.928693)
			(xy 45.273746 -482.909641) (xy 45.326996 -482.89805) (xy 45.381353 -482.894156) (xy 45.435712 -482.898037)
			(xy 45.488964 -482.909615) (xy 45.540027 -482.928654) (xy 45.587861 -482.954766) (xy 45.631491 -482.987421)
			(xy 45.67003 -483.025952) (xy 45.702693 -483.069576) (xy 45.728815 -483.117404) (xy 45.747864 -483.168463)
			(xy 45.759452 -483.221714) (xy 45.763344 -483.276071) (xy 45.75946 -483.330429) (xy 45.74788 -483.383682)
			(xy 45.728839 -483.434744) (xy 45.702724 -483.482576) (xy 45.670068 -483.526205) (xy 45.631535 -483.564742)
			(xy 45.587909 -483.597402) (xy 45.54008 -483.623522) (xy 45.48902 -483.642569) (xy 45.435769 -483.654155)
			(xy 45.381411 -483.658044) (xy 45.327053 -483.654158) (xy 45.273801 -483.642575) (xy 45.22274 -483.623531)
			(xy 45.174909 -483.597414) (xy 45.152818 -483.581456) (xy 45.133806 -483.56786) (xy 45.091923 -483.547128)
			(xy 45.046955 -483.534402) (xy 45.000418 -483.530112) (xy 44.953881 -483.534402) (xy 44.908913 -483.547128)
			(xy 44.86703 -483.56786) (xy 44.848018 -483.581456) (xy 44.825884 -483.597353) (xy 44.77806 -483.62347)
			(xy 44.727006 -483.642515) (xy 44.673761 -483.6541) (xy 44.619409 -483.657989) (xy 44.565057 -483.654103)
			(xy 44.511812 -483.64252) (xy 44.460757 -483.623478) (xy 44.412932 -483.597363) (xy 44.36931 -483.564707)
			(xy 44.33078 -483.526175) (xy 44.298127 -483.482552) (xy 44.272014 -483.434726) (xy 44.252974 -483.38367)
			(xy 44.241395 -483.330423) (xy 44.237511 -483.276071) (xy 43.859335 -483.276071) (xy 43.855451 -483.330427)
			(xy 43.843871 -483.383677) (xy 43.824831 -483.434737) (xy 43.798718 -483.482568) (xy 43.766063 -483.526195)
			(xy 43.727532 -483.564731) (xy 43.683909 -483.597391) (xy 43.636082 -483.623511) (xy 43.585024 -483.642557)
			(xy 43.531776 -483.654144) (xy 43.47742 -483.658035) (xy 43.423064 -483.65415) (xy 43.369814 -483.642569)
			(xy 43.318755 -483.623527) (xy 43.270925 -483.597413) (xy 43.248834 -483.581456) (xy 43.229822 -483.56786)
			(xy 43.187939 -483.547128) (xy 43.142971 -483.534402) (xy 43.096434 -483.530112) (xy 43.049897 -483.534402)
			(xy 43.004929 -483.547128) (xy 42.963046 -483.56786) (xy 42.944034 -483.581456) (xy 42.9219 -483.597354)
			(xy 42.874075 -483.623474) (xy 42.823019 -483.642521) (xy 42.769772 -483.654108) (xy 42.715419 -483.657998)
			(xy 42.661064 -483.654113) (xy 42.607816 -483.642532) (xy 42.556759 -483.623489) (xy 42.508931 -483.597374)
			(xy 42.465307 -483.564718) (xy 42.426776 -483.526185) (xy 42.39412 -483.48256) (xy 42.368006 -483.434732)
			(xy 42.348965 -483.383674) (xy 42.337385 -483.330426) (xy 42.333502 -483.276071) (xy 41.61836 -483.276071)
			(xy 41.614476 -483.330433) (xy 41.602894 -483.383689) (xy 41.583851 -483.434754) (xy 41.557734 -483.482589)
			(xy 41.525075 -483.52622) (xy 41.486539 -483.564759) (xy 41.44291 -483.597421) (xy 41.395076 -483.623541)
			(xy 41.344013 -483.642587) (xy 41.290758 -483.654172) (xy 41.236396 -483.65806) (xy 41.182035 -483.654171)
			(xy 41.12878 -483.642585) (xy 41.077717 -483.623538) (xy 41.029884 -483.597417) (xy 41.007792 -483.581456)
			(xy 40.98878 -483.56786) (xy 40.946897 -483.547128) (xy 40.901929 -483.534402) (xy 40.855392 -483.530112)
			(xy 40.808855 -483.534402) (xy 40.763887 -483.547128) (xy 40.722004 -483.56786) (xy 40.702992 -483.581456)
			(xy 40.680859 -483.597351) (xy 40.633037 -483.623464) (xy 40.581985 -483.642505) (xy 40.528743 -483.654087)
			(xy 40.474395 -483.657973) (xy 40.420046 -483.654085) (xy 40.366805 -483.642502) (xy 40.315753 -483.623459)
			(xy 40.267932 -483.597345) (xy 40.224314 -483.56469) (xy 40.185788 -483.52616) (xy 40.153137 -483.482539)
			(xy 40.127027 -483.434716) (xy 40.107988 -483.383663) (xy 40.09641 -483.33042) (xy 40.092527 -483.276071)
			(xy 39.731667 -483.276071) (xy 39.727783 -483.330435) (xy 39.716201 -483.383692) (xy 39.697157 -483.434758)
			(xy 39.671039 -483.482595) (xy 39.638378 -483.526227) (xy 39.599841 -483.564767) (xy 39.55621 -483.597429)
			(xy 39.508375 -483.623549) (xy 39.457309 -483.642596) (xy 39.404053 -483.65418) (xy 39.349689 -483.658067)
			(xy 39.295326 -483.654177) (xy 39.24207 -483.64259) (xy 39.191006 -483.62354) (xy 39.143172 -483.597418)
			(xy 39.12108 -483.581456) (xy 39.102068 -483.56786) (xy 39.060185 -483.547128) (xy 39.015217 -483.534402)
			(xy 38.96868 -483.530112) (xy 38.922143 -483.534402) (xy 38.877175 -483.547128) (xy 38.835292 -483.56786)
			(xy 38.81628 -483.581456) (xy 38.794147 -483.59735) (xy 38.746326 -483.623461) (xy 38.695275 -483.6425)
			(xy 38.642035 -483.654081) (xy 38.587688 -483.657966) (xy 38.533341 -483.654077) (xy 38.480101 -483.642494)
			(xy 38.429052 -483.623451) (xy 38.381232 -483.597336) (xy 38.337616 -483.564682) (xy 38.299091 -483.526153)
			(xy 38.266441 -483.482533) (xy 38.240332 -483.434711) (xy 38.221295 -483.383659) (xy 38.209717 -483.330418)
			(xy 38.205834 -483.276071) (xy 1.27 -483.276071) (xy 1.27 -484.733362) (xy 29.519874 -484.733362)
			(xy 29.519874 -484.646462) (xy 29.527892 -484.559933) (xy 29.54386 -484.474513) (xy 29.567641 -484.390931)
			(xy 29.599033 -484.309899) (xy 29.637767 -484.23211) (xy 29.683514 -484.158226) (xy 29.735883 -484.088879)
			(xy 29.794427 -484.024659) (xy 29.858647 -483.966115) (xy 29.927994 -483.913746) (xy 30.001878 -483.867999)
			(xy 30.079667 -483.829265) (xy 30.160699 -483.797873) (xy 30.244281 -483.774092) (xy 30.329701 -483.758124)
			(xy 30.41623 -483.750106) (xy 30.50313 -483.750106) (xy 30.589659 -483.758124) (xy 30.675079 -483.774092)
			(xy 30.758661 -483.797873) (xy 30.839693 -483.829265) (xy 30.917482 -483.867999) (xy 30.991366 -483.913746)
			(xy 31.060713 -483.966115) (xy 31.124933 -484.024659) (xy 31.183477 -484.088879) (xy 31.235846 -484.158226)
			(xy 31.281593 -484.23211) (xy 31.320327 -484.309899) (xy 31.351719 -484.390931) (xy 31.3755 -484.474513)
			(xy 31.391468 -484.559933) (xy 31.399486 -484.646462) (xy 31.399988 -484.689912) (xy 31.399486 -484.733362)
			(xy 34.599874 -484.733362) (xy 34.599874 -484.646462) (xy 34.607892 -484.559933) (xy 34.62386 -484.474513)
			(xy 34.647641 -484.390931) (xy 34.679033 -484.309899) (xy 34.717767 -484.23211) (xy 34.763514 -484.158226)
			(xy 34.815883 -484.088879) (xy 34.874427 -484.024659) (xy 34.938647 -483.966115) (xy 35.007994 -483.913746)
			(xy 35.081878 -483.867999) (xy 35.159667 -483.829265) (xy 35.240699 -483.797873) (xy 35.324281 -483.774092)
			(xy 35.409701 -483.758124) (xy 35.49623 -483.750106) (xy 35.58313 -483.750106) (xy 35.669659 -483.758124)
			(xy 35.755079 -483.774092) (xy 35.838661 -483.797873) (xy 35.919693 -483.829265) (xy 35.997482 -483.867999)
			(xy 36.071366 -483.913746) (xy 36.140713 -483.966115) (xy 36.204933 -484.024659) (xy 36.263477 -484.088879)
			(xy 36.315846 -484.158226) (xy 36.361593 -484.23211) (xy 36.400327 -484.309899) (xy 36.431719 -484.390931)
			(xy 36.4555 -484.474513) (xy 36.471468 -484.559933) (xy 36.479486 -484.646462) (xy 36.479988 -484.689912)
			(xy 36.479486 -484.733362) (xy 36.471468 -484.819891) (xy 36.4555 -484.905311) (xy 36.431719 -484.988893)
			(xy 36.400327 -485.069925) (xy 36.361593 -485.147714) (xy 36.315846 -485.221598) (xy 36.263477 -485.290945)
			(xy 36.239447 -485.317305) (xy 38.205789 -485.317305) (xy 38.209676 -485.262952) (xy 38.221259 -485.209705)
			(xy 38.240301 -485.158649) (xy 38.266417 -485.110822) (xy 38.299073 -485.067199) (xy 38.337605 -485.028668)
			(xy 38.381228 -484.996013) (xy 38.429055 -484.969899) (xy 38.480112 -484.950857) (xy 38.533359 -484.939275)
			(xy 38.587712 -484.935389) (xy 38.642065 -484.939278) (xy 38.695311 -484.950863) (xy 38.746366 -484.969908)
			(xy 38.794192 -484.996026) (xy 38.81628 -485.011984) (xy 38.835292 -485.02558) (xy 38.877175 -485.046312)
			(xy 38.922143 -485.059038) (xy 38.96868 -485.063328) (xy 39.015217 -485.059038) (xy 39.060185 -485.046312)
			(xy 39.102068 -485.02558) (xy 39.12108 -485.011984) (xy 39.143176 -484.996033) (xy 39.191003 -484.96991)
			(xy 39.24206 -484.95086) (xy 39.295309 -484.939271) (xy 39.349665 -484.935378) (xy 39.404022 -484.939261)
			(xy 39.457274 -484.950841) (xy 39.508334 -484.969882) (xy 39.556166 -484.995996) (xy 39.599793 -485.028652)
			(xy 39.638329 -485.067184) (xy 39.670988 -485.110809) (xy 39.697106 -485.158638) (xy 39.716151 -485.209698)
			(xy 39.727735 -485.262948) (xy 39.731622 -485.317305) (xy 40.092482 -485.317305) (xy 40.096369 -485.26295)
			(xy 40.107952 -485.209702) (xy 40.126996 -485.158644) (xy 40.153112 -485.110816) (xy 40.185769 -485.067192)
			(xy 40.224303 -485.02866) (xy 40.267928 -484.996005) (xy 40.315757 -484.96989) (xy 40.366815 -484.950848)
			(xy 40.420064 -484.939267) (xy 40.474419 -484.935382) (xy 40.528773 -484.939272) (xy 40.582021 -484.950859)
			(xy 40.633077 -484.969905) (xy 40.680903 -484.996025) (xy 40.702992 -485.011984) (xy 40.722004 -485.02558)
			(xy 40.763887 -485.046312) (xy 40.808855 -485.059038) (xy 40.855392 -485.063328) (xy 40.901929 -485.059038)
			(xy 40.946897 -485.046312) (xy 40.98878 -485.02558) (xy 41.007792 -485.011984) (xy 41.029888 -484.996034)
			(xy 41.077713 -484.969913) (xy 41.12877 -484.950865) (xy 41.182017 -484.939277) (xy 41.236372 -484.935385)
			(xy 41.290728 -484.939269) (xy 41.343977 -484.950849) (xy 41.395036 -484.96989) (xy 41.442865 -484.996004)
			(xy 41.486491 -485.028659) (xy 41.525025 -485.067191) (xy 41.557683 -485.110815) (xy 41.5838 -485.158643)
			(xy 41.602844 -485.209701) (xy 41.614428 -485.26295) (xy 41.618315 -485.317305) (xy 42.333457 -485.317305)
			(xy 42.337344 -485.262944) (xy 42.348929 -485.20969) (xy 42.367976 -485.158628) (xy 42.394096 -485.110795)
			(xy 42.426757 -485.067168) (xy 42.465296 -485.028633) (xy 42.508927 -484.995975) (xy 42.556762 -484.96986)
			(xy 42.607827 -484.950819) (xy 42.661082 -484.939239) (xy 42.715443 -484.935357) (xy 42.769803 -484.939251)
			(xy 42.823055 -484.950843) (xy 42.874115 -484.969895) (xy 42.921944 -484.996021) (xy 42.944034 -485.011984)
			(xy 42.963046 -485.02558) (xy 43.004929 -485.046312) (xy 43.049897 -485.059038) (xy 43.096434 -485.063328)
			(xy 43.142971 -485.059038) (xy 43.187939 -485.046312) (xy 43.229822 -485.02558) (xy 43.248834 -485.011984)
			(xy 43.270929 -484.996038) (xy 43.318752 -484.969923) (xy 43.369804 -484.950881) (xy 43.423047 -484.939298)
			(xy 43.477396 -484.93541) (xy 43.531745 -484.939297) (xy 43.584989 -484.950879) (xy 43.636041 -484.96992)
			(xy 43.683865 -484.996034) (xy 43.727485 -485.028687) (xy 43.766014 -485.067216) (xy 43.798667 -485.110836)
			(xy 43.82478 -485.158659) (xy 43.843821 -485.209712) (xy 43.855403 -485.262955) (xy 43.85929 -485.317305)
			(xy 44.237466 -485.317305) (xy 44.241354 -485.262946) (xy 44.252938 -485.209695) (xy 44.271983 -485.158634)
			(xy 44.298102 -485.110803) (xy 44.330762 -485.067177) (xy 44.369299 -485.028643) (xy 44.412928 -484.995986)
			(xy 44.46076 -484.969871) (xy 44.511822 -484.95083) (xy 44.565075 -484.93925) (xy 44.619433 -484.935366)
			(xy 44.673791 -484.939259) (xy 44.727042 -484.950849) (xy 44.778101 -484.969899) (xy 44.825929 -484.996023)
			(xy 44.848018 -485.011984) (xy 44.86703 -485.02558) (xy 44.908913 -485.046312) (xy 44.953881 -485.059038)
			(xy 45.000418 -485.063328) (xy 45.046955 -485.059038) (xy 45.091923 -485.046312) (xy 45.133806 -485.02558)
			(xy 45.152818 -485.011984) (xy 45.174913 -484.996036) (xy 45.222737 -484.96992) (xy 45.273791 -484.950875)
			(xy 45.327036 -484.93929) (xy 45.381387 -484.935401) (xy 45.435739 -484.939286) (xy 45.488984 -484.950868)
			(xy 45.540039 -484.969909) (xy 45.587865 -484.996022) (xy 45.631487 -485.028677) (xy 45.670018 -485.067207)
			(xy 45.702673 -485.110828) (xy 45.728788 -485.158653) (xy 45.74783 -485.209708) (xy 45.759413 -485.262953)
			(xy 45.763299 -485.317305) (xy 45.759411 -485.371656) (xy 45.747827 -485.424901) (xy 45.728784 -485.475955)
			(xy 45.702668 -485.52378) (xy 45.670012 -485.567401) (xy 45.63148 -485.60593) (xy 45.587857 -485.638583)
			(xy 45.540031 -485.664695) (xy 45.488975 -485.683735) (xy 45.435729 -485.695315) (xy 45.381377 -485.699199)
			(xy 45.327026 -485.695309) (xy 45.273782 -485.683722) (xy 45.222728 -485.664676) (xy 45.174905 -485.638558)
			(xy 45.152818 -485.6226) (xy 45.133806 -485.609004) (xy 45.091923 -485.588272) (xy 45.046955 -485.575546)
			(xy 45.000418 -485.571256) (xy 44.953881 -485.575546) (xy 44.908913 -485.588272) (xy 44.86703 -485.609004)
			(xy 44.848018 -485.6226) (xy 44.825937 -485.638572) (xy 44.77811 -485.664697) (xy 44.727051 -485.683749)
			(xy 44.673801 -485.69534) (xy 44.619443 -485.699234) (xy 44.565084 -485.695352) (xy 44.511831 -485.683773)
			(xy 44.460769 -485.664733) (xy 44.412936 -485.638619) (xy 44.369306 -485.605963) (xy 44.330768 -485.56743)
			(xy 44.298107 -485.523805) (xy 44.271987 -485.475975) (xy 44.252941 -485.424914) (xy 44.241355 -485.371663)
			(xy 44.237466 -485.317305) (xy 43.85929 -485.317305) (xy 43.855402 -485.371654) (xy 43.843819 -485.424897)
			(xy 43.824776 -485.475949) (xy 43.798662 -485.523772) (xy 43.766007 -485.567391) (xy 43.727477 -485.605919)
			(xy 43.683856 -485.638572) (xy 43.636033 -485.664684) (xy 43.584979 -485.683724) (xy 43.531736 -485.695304)
			(xy 43.477386 -485.69919) (xy 43.423037 -485.695301) (xy 43.369795 -485.683716) (xy 43.318743 -485.664673)
			(xy 43.270921 -485.638557) (xy 43.248834 -485.6226) (xy 43.229822 -485.609004) (xy 43.187939 -485.588272)
			(xy 43.142971 -485.575546) (xy 43.096434 -485.571256) (xy 43.049897 -485.575546) (xy 43.004929 -485.588272)
			(xy 42.963046 -485.609004) (xy 42.944034 -485.6226) (xy 42.921953 -485.638574) (xy 42.874124 -485.664701)
			(xy 42.823064 -485.683755) (xy 42.769812 -485.695348) (xy 42.715452 -485.699243) (xy 42.661091 -485.695362)
			(xy 42.607836 -485.683784) (xy 42.556771 -485.664744) (xy 42.508935 -485.63863) (xy 42.465303 -485.605974)
			(xy 42.426764 -485.56744) (xy 42.394101 -485.523813) (xy 42.36798 -485.475981) (xy 42.348932 -485.424919)
			(xy 42.337346 -485.371665) (xy 42.333457 -485.317305) (xy 41.618315 -485.317305) (xy 41.614426 -485.37166)
			(xy 41.602842 -485.424908) (xy 41.583796 -485.475966) (xy 41.557678 -485.523793) (xy 41.525019 -485.567416)
			(xy 41.486484 -485.605947) (xy 41.442857 -485.638601) (xy 41.395027 -485.664714) (xy 41.343968 -485.683754)
			(xy 41.290718 -485.695332) (xy 41.236363 -485.699215) (xy 41.182008 -485.695322) (xy 41.128761 -485.683732)
			(xy 41.077705 -485.664683) (xy 41.02988 -485.638561) (xy 41.007792 -485.6226) (xy 40.98878 -485.609004)
			(xy 40.946897 -485.588272) (xy 40.901929 -485.575546) (xy 40.855392 -485.571256) (xy 40.808855 -485.575546)
			(xy 40.763887 -485.588272) (xy 40.722004 -485.609004) (xy 40.702992 -485.6226) (xy 40.680912 -485.63857)
			(xy 40.633086 -485.664691) (xy 40.58203 -485.683739) (xy 40.528783 -485.695326) (xy 40.474428 -485.699218)
			(xy 40.420073 -485.695334) (xy 40.366824 -485.683755) (xy 40.315765 -485.664714) (xy 40.267936 -485.638601)
			(xy 40.22431 -485.605946) (xy 40.185776 -485.567415) (xy 40.153117 -485.523792) (xy 40.127 -485.475965)
			(xy 40.107955 -485.424907) (xy 40.09637 -485.371659) (xy 40.092482 -485.317305) (xy 39.731622 -485.317305)
			(xy 39.727733 -485.371661) (xy 39.716148 -485.424911) (xy 39.697102 -485.47597) (xy 39.670983 -485.523799)
			(xy 39.638323 -485.567423) (xy 39.599786 -485.605955) (xy 39.556158 -485.638609) (xy 39.508326 -485.664722)
			(xy 39.457264 -485.683762) (xy 39.404013 -485.69534) (xy 39.349656 -485.699222) (xy 39.295299 -485.695328)
			(xy 39.242051 -485.683737) (xy 39.190994 -485.664686) (xy 39.143168 -485.638562) (xy 39.12108 -485.6226)
			(xy 39.102068 -485.609004) (xy 39.060185 -485.588272) (xy 39.015217 -485.575546) (xy 38.96868 -485.571256)
			(xy 38.922143 -485.575546) (xy 38.877175 -485.588272) (xy 38.835292 -485.609004) (xy 38.81628 -485.6226)
			(xy 38.7942 -485.638569) (xy 38.746375 -485.664688) (xy 38.69532 -485.683734) (xy 38.642074 -485.69532)
			(xy 38.587721 -485.699211) (xy 38.533368 -485.695326) (xy 38.480121 -485.683746) (xy 38.429064 -485.664705)
			(xy 38.381236 -485.638592) (xy 38.337612 -485.605938) (xy 38.299079 -485.567408) (xy 38.266422 -485.523786)
			(xy 38.240305 -485.47596) (xy 38.221261 -485.424904) (xy 38.209677 -485.371658) (xy 38.205789 -485.317305)
			(xy 36.239447 -485.317305) (xy 36.204933 -485.355165) (xy 36.140713 -485.413709) (xy 36.071366 -485.466078)
			(xy 35.997482 -485.511825) (xy 35.919693 -485.550559) (xy 35.838661 -485.581951) (xy 35.755079 -485.605732)
			(xy 35.669659 -485.6217) (xy 35.58313 -485.629718) (xy 35.49623 -485.629718) (xy 35.409701 -485.6217)
			(xy 35.324281 -485.605732) (xy 35.240699 -485.581951) (xy 35.159667 -485.550559) (xy 35.081878 -485.511825)
			(xy 35.007994 -485.466078) (xy 34.938647 -485.413709) (xy 34.874427 -485.355165) (xy 34.815883 -485.290945)
			(xy 34.763514 -485.221598) (xy 34.717767 -485.147714) (xy 34.679033 -485.069925) (xy 34.647641 -484.988893)
			(xy 34.62386 -484.905311) (xy 34.607892 -484.819891) (xy 34.599874 -484.733362) (xy 31.399486 -484.733362)
			(xy 31.391468 -484.819891) (xy 31.3755 -484.905311) (xy 31.351719 -484.988893) (xy 31.320327 -485.069925)
			(xy 31.281593 -485.147714) (xy 31.235846 -485.221598) (xy 31.183477 -485.290945) (xy 31.124933 -485.355165)
			(xy 31.060713 -485.413709) (xy 30.991366 -485.466078) (xy 30.917482 -485.511825) (xy 30.839693 -485.550559)
			(xy 30.758661 -485.581951) (xy 30.675079 -485.605732) (xy 30.589659 -485.6217) (xy 30.50313 -485.629718)
			(xy 30.41623 -485.629718) (xy 30.329701 -485.6217) (xy 30.244281 -485.605732) (xy 30.160699 -485.581951)
			(xy 30.079667 -485.550559) (xy 30.001878 -485.511825) (xy 29.927994 -485.466078) (xy 29.858647 -485.413709)
			(xy 29.794427 -485.355165) (xy 29.735883 -485.290945) (xy 29.683514 -485.221598) (xy 29.637767 -485.147714)
			(xy 29.599033 -485.069925) (xy 29.567641 -484.988893) (xy 29.54386 -484.905311) (xy 29.527892 -484.819891)
			(xy 29.519874 -484.733362) (xy 1.27 -484.733362) (xy 1.27 -487.273362) (xy 29.519874 -487.273362)
			(xy 29.519874 -487.186462) (xy 29.527892 -487.099933) (xy 29.54386 -487.014513) (xy 29.567641 -486.930931)
			(xy 29.599033 -486.849899) (xy 29.637767 -486.77211) (xy 29.683514 -486.698226) (xy 29.735883 -486.628879)
			(xy 29.794427 -486.564659) (xy 29.858647 -486.506115) (xy 29.927994 -486.453746) (xy 30.001878 -486.407999)
			(xy 30.079667 -486.369265) (xy 30.160699 -486.337873) (xy 30.244281 -486.314092) (xy 30.329701 -486.298124)
			(xy 30.41623 -486.290106) (xy 30.50313 -486.290106) (xy 30.589659 -486.298124) (xy 30.675079 -486.314092)
			(xy 30.758661 -486.337873) (xy 30.839693 -486.369265) (xy 30.917482 -486.407999) (xy 30.991366 -486.453746)
			(xy 31.060713 -486.506115) (xy 31.124933 -486.564659) (xy 31.183477 -486.628879) (xy 31.235846 -486.698226)
			(xy 31.281593 -486.77211) (xy 31.320327 -486.849899) (xy 31.351719 -486.930931) (xy 31.3755 -487.014513)
			(xy 31.391468 -487.099933) (xy 31.399486 -487.186462) (xy 31.399988 -487.229912) (xy 31.399486 -487.273362)
			(xy 34.599874 -487.273362) (xy 34.599874 -487.186462) (xy 34.607892 -487.099933) (xy 34.62386 -487.014513)
			(xy 34.647641 -486.930931) (xy 34.679033 -486.849899) (xy 34.717767 -486.77211) (xy 34.763514 -486.698226)
			(xy 34.815883 -486.628879) (xy 34.874427 -486.564659) (xy 34.938647 -486.506115) (xy 35.007994 -486.453746)
			(xy 35.081878 -486.407999) (xy 35.159667 -486.369265) (xy 35.240699 -486.337873) (xy 35.324281 -486.314092)
			(xy 35.409701 -486.298124) (xy 35.49623 -486.290106) (xy 35.58313 -486.290106) (xy 35.669659 -486.298124)
			(xy 35.755079 -486.314092) (xy 35.838661 -486.337873) (xy 35.919693 -486.369265) (xy 35.997482 -486.407999)
			(xy 36.071366 -486.453746) (xy 36.140713 -486.506115) (xy 36.204933 -486.564659) (xy 36.263477 -486.628879)
			(xy 36.315846 -486.698226) (xy 36.361593 -486.77211) (xy 36.400327 -486.849899) (xy 36.431719 -486.930931)
			(xy 36.4555 -487.014513) (xy 36.471468 -487.099933) (xy 36.479486 -487.186462) (xy 36.479955 -487.227089)
			(xy 38.20581 -487.227089) (xy 38.209699 -487.172739) (xy 38.221283 -487.119496) (xy 38.240327 -487.068443)
			(xy 38.266443 -487.02062) (xy 38.299099 -486.977001) (xy 38.33763 -486.938474) (xy 38.381253 -486.905822)
			(xy 38.429078 -486.879711) (xy 38.480133 -486.860672) (xy 38.533377 -486.849093) (xy 38.587727 -486.84521)
			(xy 38.642077 -486.849101) (xy 38.69532 -486.860688) (xy 38.746372 -486.879734) (xy 38.794194 -486.905852)
			(xy 38.81628 -486.92181) (xy 38.835292 -486.935406) (xy 38.877175 -486.956138) (xy 38.922143 -486.968864)
			(xy 38.96868 -486.973154) (xy 39.015217 -486.968864) (xy 39.060185 -486.956138) (xy 39.102068 -486.935406)
			(xy 39.12108 -486.92181) (xy 39.143152 -486.905824) (xy 39.19098 -486.879698) (xy 39.242039 -486.860645)
			(xy 39.295291 -486.849052) (xy 39.34965 -486.845157) (xy 39.40401 -486.849038) (xy 39.457264 -486.860616)
			(xy 39.508329 -486.879656) (xy 39.556164 -486.90577) (xy 39.599795 -486.938426) (xy 39.638334 -486.976959)
			(xy 39.670997 -487.020585) (xy 39.697119 -487.068416) (xy 39.716166 -487.119477) (xy 39.727753 -487.17273)
			(xy 39.731643 -487.227089) (xy 40.092503 -487.227089) (xy 40.096392 -487.172738) (xy 40.107976 -487.119493)
			(xy 40.127021 -487.068438) (xy 40.153138 -487.020614) (xy 40.185795 -486.976994) (xy 40.224328 -486.938466)
			(xy 40.267952 -486.905814) (xy 40.315779 -486.879702) (xy 40.366836 -486.860664) (xy 40.420082 -486.849085)
			(xy 40.474434 -486.845203) (xy 40.528786 -486.849095) (xy 40.58203 -486.860683) (xy 40.633083 -486.879731)
			(xy 40.680905 -486.905851) (xy 40.702992 -486.92181) (xy 40.722004 -486.935406) (xy 40.763887 -486.956138)
			(xy 40.808855 -486.968864) (xy 40.855392 -486.973154) (xy 40.901929 -486.968864) (xy 40.946897 -486.956138)
			(xy 40.98878 -486.935406) (xy 41.007792 -486.92181) (xy 41.029863 -486.905825) (xy 41.077691 -486.879701)
			(xy 41.128749 -486.860649) (xy 41.181999 -486.849058) (xy 41.236357 -486.845164) (xy 41.290715 -486.849046)
			(xy 41.343968 -486.860625) (xy 41.39503 -486.879665) (xy 41.442864 -486.905778) (xy 41.486493 -486.938434)
			(xy 41.525031 -486.976966) (xy 41.557693 -487.020591) (xy 41.583813 -487.06842) (xy 41.60286 -487.11948)
			(xy 41.614446 -487.172731) (xy 41.618336 -487.227089) (xy 42.333478 -487.227089) (xy 42.337367 -487.172732)
			(xy 42.348954 -487.119481) (xy 42.368001 -487.068422) (xy 42.394122 -487.020594) (xy 42.426783 -486.97697)
			(xy 42.465322 -486.938438) (xy 42.508952 -486.905784) (xy 42.556785 -486.879672) (xy 42.607848 -486.860634)
			(xy 42.6611 -486.849057) (xy 42.715458 -486.845178) (xy 42.769815 -486.849074) (xy 42.823064 -486.860667)
			(xy 42.874121 -486.879721) (xy 42.921946 -486.905847) (xy 42.944034 -486.92181) (xy 42.963046 -486.935406)
			(xy 43.004929 -486.956138) (xy 43.049897 -486.968864) (xy 43.096434 -486.973154) (xy 43.142971 -486.968864)
			(xy 43.187939 -486.956138) (xy 43.229822 -486.935406) (xy 43.248834 -486.92181) (xy 43.270904 -486.905829)
			(xy 43.318729 -486.879711) (xy 43.369783 -486.860665) (xy 43.423028 -486.84908) (xy 43.47738 -486.845189)
			(xy 43.531733 -486.849074) (xy 43.584979 -486.860654) (xy 43.636036 -486.879695) (xy 43.683863 -486.905808)
			(xy 43.727486 -486.938461) (xy 43.766019 -486.976991) (xy 43.798676 -487.020612) (xy 43.824793 -487.068437)
			(xy 43.843837 -487.119491) (xy 43.855422 -487.172737) (xy 43.859311 -487.227089) (xy 44.237487 -487.227089)
			(xy 44.241376 -487.172734) (xy 44.252962 -487.119486) (xy 44.272009 -487.068428) (xy 44.298128 -487.020601)
			(xy 44.330788 -486.976979) (xy 44.369324 -486.938449) (xy 44.412952 -486.905795) (xy 44.460783 -486.879684)
			(xy 44.511843 -486.860645) (xy 44.565093 -486.849068) (xy 44.619449 -486.845187) (xy 44.673804 -486.849082)
			(xy 44.727051 -486.860673) (xy 44.778106 -486.879725) (xy 44.825931 -486.905848) (xy 44.848018 -486.92181)
			(xy 44.86703 -486.935406) (xy 44.908913 -486.956138) (xy 44.953881 -486.968864) (xy 45.000418 -486.973154)
			(xy 45.046955 -486.968864) (xy 45.091923 -486.956138) (xy 45.133806 -486.935406) (xy 45.152818 -486.92181)
			(xy 45.174889 -486.905827) (xy 45.222714 -486.879707) (xy 45.27377 -486.860659) (xy 45.327017 -486.849072)
			(xy 45.381371 -486.84518) (xy 45.435726 -486.849063) (xy 45.488975 -486.860643) (xy 45.540034 -486.879683)
			(xy 45.587863 -486.905796) (xy 45.631489 -486.938451) (xy 45.670024 -486.976981) (xy 45.702682 -487.020604)
			(xy 45.7288 -487.06843) (xy 45.747846 -487.119487) (xy 45.759431 -487.172735) (xy 45.76332 -487.227089)
			(xy 45.759434 -487.281444) (xy 45.747852 -487.334692) (xy 45.728809 -487.38575) (xy 45.702694 -487.433578)
			(xy 45.670038 -487.477202) (xy 45.631505 -487.515735) (xy 45.587881 -487.548392) (xy 45.540053 -487.574508)
			(xy 45.488996 -487.593551) (xy 45.435748 -487.605134) (xy 45.381393 -487.60902) (xy 45.327039 -487.605132)
			(xy 45.273791 -487.593547) (xy 45.222734 -487.574502) (xy 45.174907 -487.548384) (xy 45.152818 -487.532426)
			(xy 45.133806 -487.51883) (xy 45.091923 -487.498098) (xy 45.046955 -487.485372) (xy 45.000418 -487.481082)
			(xy 44.953881 -487.485372) (xy 44.908913 -487.498098) (xy 44.86703 -487.51883) (xy 44.848018 -487.532426)
			(xy 44.825913 -487.548363) (xy 44.778087 -487.574484) (xy 44.72703 -487.593533) (xy 44.673783 -487.605121)
			(xy 44.619427 -487.609013) (xy 44.565072 -487.605129) (xy 44.511822 -487.593549) (xy 44.460763 -487.574507)
			(xy 44.412934 -487.548393) (xy 44.369308 -487.515737) (xy 44.330774 -487.477205) (xy 44.298116 -487.43358)
			(xy 44.272 -487.385752) (xy 44.252956 -487.334694) (xy 44.241373 -487.281445) (xy 44.237487 -487.227089)
			(xy 43.859311 -487.227089) (xy 43.855425 -487.281442) (xy 43.843843 -487.334688) (xy 43.824802 -487.385744)
			(xy 43.798688 -487.43357) (xy 43.766033 -487.477193) (xy 43.727503 -487.515725) (xy 43.683881 -487.548381)
			(xy 43.636055 -487.574496) (xy 43.585 -487.593539) (xy 43.531754 -487.605123) (xy 43.477402 -487.609011)
			(xy 43.42305 -487.605123) (xy 43.369804 -487.593541) (xy 43.318748 -487.574498) (xy 43.270923 -487.548383)
			(xy 43.248834 -487.532426) (xy 43.229822 -487.51883) (xy 43.187939 -487.498098) (xy 43.142971 -487.485372)
			(xy 43.096434 -487.481082) (xy 43.049897 -487.485372) (xy 43.004929 -487.498098) (xy 42.963046 -487.51883)
			(xy 42.944034 -487.532426) (xy 42.921928 -487.548365) (xy 42.874101 -487.574488) (xy 42.823043 -487.593539)
			(xy 42.769794 -487.605129) (xy 42.715437 -487.609022) (xy 42.661079 -487.60514) (xy 42.607827 -487.59356)
			(xy 42.556765 -487.574519) (xy 42.508933 -487.548404) (xy 42.465305 -487.515748) (xy 42.426769 -487.477214)
			(xy 42.39411 -487.433588) (xy 42.367992 -487.385758) (xy 42.348947 -487.334698) (xy 42.337364 -487.281447)
			(xy 42.333478 -487.227089) (xy 41.618336 -487.227089) (xy 41.614449 -487.281447) (xy 41.602866 -487.334699)
			(xy 41.583822 -487.38576) (xy 41.557704 -487.433591) (xy 41.525045 -487.477218) (xy 41.486509 -487.515752)
			(xy 41.442882 -487.54841) (xy 41.39505 -487.574526) (xy 41.343989 -487.593569) (xy 41.290736 -487.605151)
			(xy 41.236378 -487.609036) (xy 41.18202 -487.605145) (xy 41.12877 -487.593557) (xy 41.07771 -487.574508)
			(xy 41.029882 -487.548387) (xy 41.007792 -487.532426) (xy 40.98878 -487.51883) (xy 40.946897 -487.498098)
			(xy 40.901929 -487.485372) (xy 40.855392 -487.481082) (xy 40.808855 -487.485372) (xy 40.763887 -487.498098)
			(xy 40.722004 -487.51883) (xy 40.702992 -487.532426) (xy 40.680887 -487.548361) (xy 40.633063 -487.574478)
			(xy 40.582009 -487.593523) (xy 40.528764 -487.605108) (xy 40.474413 -487.608997) (xy 40.420061 -487.605112)
			(xy 40.366815 -487.59353) (xy 40.31576 -487.574489) (xy 40.267934 -487.548375) (xy 40.224312 -487.51572)
			(xy 40.185781 -487.477189) (xy 40.153126 -487.433567) (xy 40.127012 -487.385742) (xy 40.10797 -487.334687)
			(xy 40.096389 -487.281441) (xy 40.092503 -487.227089) (xy 39.731643 -487.227089) (xy 39.727756 -487.281449)
			(xy 39.716173 -487.334702) (xy 39.697128 -487.385765) (xy 39.671009 -487.433597) (xy 39.638349 -487.477225)
			(xy 39.599811 -487.51576) (xy 39.556182 -487.548419) (xy 39.508349 -487.574535) (xy 39.457285 -487.593578)
			(xy 39.404031 -487.605159) (xy 39.349671 -487.609043) (xy 39.295312 -487.605151) (xy 39.24206 -487.593561)
			(xy 39.190999 -487.574511) (xy 39.14317 -487.548388) (xy 39.12108 -487.532426) (xy 39.102068 -487.51883)
			(xy 39.060185 -487.498098) (xy 39.015217 -487.485372) (xy 38.96868 -487.481082) (xy 38.922143 -487.485372)
			(xy 38.877175 -487.498098) (xy 38.835292 -487.51883) (xy 38.81628 -487.532426) (xy 38.794175 -487.54836)
			(xy 38.746352 -487.574475) (xy 38.695299 -487.593518) (xy 38.642056 -487.605102) (xy 38.587706 -487.60899)
			(xy 38.533356 -487.605104) (xy 38.480112 -487.593522) (xy 38.429058 -487.57448) (xy 38.381234 -487.548366)
			(xy 38.337614 -487.515712) (xy 38.299085 -487.477182) (xy 38.266431 -487.433561) (xy 38.240318 -487.385737)
			(xy 38.221277 -487.334683) (xy 38.209696 -487.281439) (xy 38.20581 -487.227089) (xy 36.479955 -487.227089)
			(xy 36.479988 -487.229912) (xy 36.479486 -487.273362) (xy 36.471468 -487.359891) (xy 36.4555 -487.445311)
			(xy 36.431719 -487.528893) (xy 36.400327 -487.609925) (xy 36.361593 -487.687714) (xy 36.315846 -487.761598)
			(xy 36.263477 -487.830945) (xy 36.204933 -487.895165) (xy 36.140713 -487.953709) (xy 36.071366 -488.006078)
			(xy 35.997482 -488.051825) (xy 35.919693 -488.090559) (xy 35.838661 -488.121951) (xy 35.755079 -488.145732)
			(xy 35.669659 -488.1617) (xy 35.58313 -488.169718) (xy 35.49623 -488.169718) (xy 35.409701 -488.1617)
			(xy 35.324281 -488.145732) (xy 35.240699 -488.121951) (xy 35.159667 -488.090559) (xy 35.081878 -488.051825)
			(xy 35.007994 -488.006078) (xy 34.938647 -487.953709) (xy 34.874427 -487.895165) (xy 34.815883 -487.830945)
			(xy 34.763514 -487.761598) (xy 34.717767 -487.687714) (xy 34.679033 -487.609925) (xy 34.647641 -487.528893)
			(xy 34.62386 -487.445311) (xy 34.607892 -487.359891) (xy 34.599874 -487.273362) (xy 31.399486 -487.273362)
			(xy 31.391468 -487.359891) (xy 31.3755 -487.445311) (xy 31.351719 -487.528893) (xy 31.320327 -487.609925)
			(xy 31.281593 -487.687714) (xy 31.235846 -487.761598) (xy 31.183477 -487.830945) (xy 31.124933 -487.895165)
			(xy 31.060713 -487.953709) (xy 30.991366 -488.006078) (xy 30.917482 -488.051825) (xy 30.839693 -488.090559)
			(xy 30.758661 -488.121951) (xy 30.675079 -488.145732) (xy 30.589659 -488.1617) (xy 30.50313 -488.169718)
			(xy 30.41623 -488.169718) (xy 30.329701 -488.1617) (xy 30.244281 -488.145732) (xy 30.160699 -488.121951)
			(xy 30.079667 -488.090559) (xy 30.001878 -488.051825) (xy 29.927994 -488.006078) (xy 29.858647 -487.953709)
			(xy 29.794427 -487.895165) (xy 29.735883 -487.830945) (xy 29.683514 -487.761598) (xy 29.637767 -487.687714)
			(xy 29.599033 -487.609925) (xy 29.567641 -487.528893) (xy 29.54386 -487.445311) (xy 29.527892 -487.359891)
			(xy 29.519874 -487.273362) (xy 1.27 -487.273362) (xy 1.27 -489.813362) (xy 29.519874 -489.813362)
			(xy 29.519874 -489.726462) (xy 29.527892 -489.639933) (xy 29.54386 -489.554513) (xy 29.567641 -489.470931)
			(xy 29.599033 -489.389899) (xy 29.637767 -489.31211) (xy 29.683514 -489.238226) (xy 29.735883 -489.168879)
			(xy 29.794427 -489.104659) (xy 29.858647 -489.046115) (xy 29.927994 -488.993746) (xy 30.001878 -488.947999)
			(xy 30.079667 -488.909265) (xy 30.160699 -488.877873) (xy 30.244281 -488.854092) (xy 30.329701 -488.838124)
			(xy 30.41623 -488.830106) (xy 30.50313 -488.830106) (xy 30.589659 -488.838124) (xy 30.675079 -488.854092)
			(xy 30.758661 -488.877873) (xy 30.839693 -488.909265) (xy 30.917482 -488.947999) (xy 30.991366 -488.993746)
			(xy 31.060713 -489.046115) (xy 31.124933 -489.104659) (xy 31.183477 -489.168879) (xy 31.235846 -489.238226)
			(xy 31.281593 -489.31211) (xy 31.320327 -489.389899) (xy 31.351719 -489.470931) (xy 31.3755 -489.554513)
			(xy 31.391468 -489.639933) (xy 31.399486 -489.726462) (xy 31.399988 -489.769912) (xy 31.399486 -489.813362)
			(xy 34.599874 -489.813362) (xy 34.599874 -489.726462) (xy 34.607892 -489.639933) (xy 34.62386 -489.554513)
			(xy 34.647641 -489.470931) (xy 34.679033 -489.389899) (xy 34.717767 -489.31211) (xy 34.763514 -489.238226)
			(xy 34.815883 -489.168879) (xy 34.874427 -489.104659) (xy 34.938647 -489.046115) (xy 35.007994 -488.993746)
			(xy 35.081878 -488.947999) (xy 35.159667 -488.909265) (xy 35.240699 -488.877873) (xy 35.324281 -488.854092)
			(xy 35.409701 -488.838124) (xy 35.49623 -488.830106) (xy 35.58313 -488.830106) (xy 35.669659 -488.838124)
			(xy 35.755079 -488.854092) (xy 35.838661 -488.877873) (xy 35.919693 -488.909265) (xy 35.997482 -488.947999)
			(xy 36.071366 -488.993746) (xy 36.140713 -489.046115) (xy 36.204933 -489.104659) (xy 36.263477 -489.168879)
			(xy 36.315846 -489.238226) (xy 36.361593 -489.31211) (xy 36.400327 -489.389899) (xy 36.431719 -489.470931)
			(xy 36.4555 -489.554513) (xy 36.471468 -489.639933) (xy 36.479486 -489.726462) (xy 36.479988 -489.769912)
			(xy 36.479486 -489.813362) (xy 36.471468 -489.899891) (xy 36.4555 -489.985311) (xy 36.431719 -490.068893)
			(xy 36.400327 -490.149925) (xy 36.361593 -490.227714) (xy 36.315846 -490.301598) (xy 36.263477 -490.370945)
			(xy 36.204933 -490.435165) (xy 36.140713 -490.493709) (xy 36.071366 -490.546078) (xy 35.997482 -490.591825)
			(xy 35.919693 -490.630559) (xy 35.838661 -490.661951) (xy 35.755079 -490.685732) (xy 35.669659 -490.7017)
			(xy 35.58313 -490.709718) (xy 35.49623 -490.709718) (xy 35.409701 -490.7017) (xy 35.324281 -490.685732)
			(xy 35.240699 -490.661951) (xy 35.159667 -490.630559) (xy 35.081878 -490.591825) (xy 35.007994 -490.546078)
			(xy 34.938647 -490.493709) (xy 34.874427 -490.435165) (xy 34.815883 -490.370945) (xy 34.763514 -490.301598)
			(xy 34.717767 -490.227714) (xy 34.679033 -490.149925) (xy 34.647641 -490.068893) (xy 34.62386 -489.985311)
			(xy 34.607892 -489.899891) (xy 34.599874 -489.813362) (xy 31.399486 -489.813362) (xy 31.391468 -489.899891)
			(xy 31.3755 -489.985311) (xy 31.351719 -490.068893) (xy 31.320327 -490.149925) (xy 31.281593 -490.227714)
			(xy 31.235846 -490.301598) (xy 31.183477 -490.370945) (xy 31.124933 -490.435165) (xy 31.060713 -490.493709)
			(xy 30.991366 -490.546078) (xy 30.917482 -490.591825) (xy 30.839693 -490.630559) (xy 30.758661 -490.661951)
			(xy 30.675079 -490.685732) (xy 30.589659 -490.7017) (xy 30.50313 -490.709718) (xy 30.41623 -490.709718)
			(xy 30.329701 -490.7017) (xy 30.244281 -490.685732) (xy 30.160699 -490.661951) (xy 30.079667 -490.630559)
			(xy 30.001878 -490.591825) (xy 29.927994 -490.546078) (xy 29.858647 -490.493709) (xy 29.794427 -490.435165)
			(xy 29.735883 -490.370945) (xy 29.683514 -490.301598) (xy 29.637767 -490.227714) (xy 29.599033 -490.149925)
			(xy 29.567641 -490.068893) (xy 29.54386 -489.985311) (xy 29.527892 -489.899891) (xy 29.519874 -489.813362)
			(xy 1.27 -489.813362) (xy 1.27 -491.999778) (xy 6.671831 -491.999778) (xy 6.675786 -491.907941) (xy 6.687621 -491.816784)
			(xy 6.707248 -491.726981) (xy 6.734522 -491.639199) (xy 6.769242 -491.554085) (xy 6.81115 -491.472272)
			(xy 6.859936 -491.394364) (xy 6.915239 -491.320939) (xy 6.976649 -491.252539) (xy 7.043711 -491.189672)
			(xy 7.11593 -491.132802) (xy 7.19277 -491.082351) (xy 7.273663 -491.038692) (xy 7.358009 -491.002149)
			(xy 7.445185 -490.972992) (xy 7.534544 -490.951438) (xy 7.625425 -490.937644) (xy 7.717156 -490.931714)
			(xy 7.809057 -490.933692) (xy 7.900448 -490.943563) (xy 7.990652 -490.961253) (xy 8.079001 -490.986633)
			(xy 8.164841 -491.019513) (xy 8.247537 -491.059651) (xy 8.326477 -491.10675) (xy 8.401075 -491.16046)
			(xy 8.470781 -491.220384) (xy 8.535076 -491.286078) (xy 8.593487 -491.357056) (xy 8.645579 -491.432793)
			(xy 8.690968 -491.512728) (xy 8.729318 -491.596268) (xy 8.760343 -491.682796) (xy 8.783816 -491.771671)
			(xy 8.799562 -491.862235) (xy 8.807464 -491.953817) (xy 8.807958 -491.999778) (xy 8.807464 -492.045739)
			(xy 8.799562 -492.137321) (xy 8.783816 -492.227885) (xy 8.760343 -492.31676) (xy 8.747219 -492.353362)
			(xy 29.519874 -492.353362) (xy 29.519874 -492.266462) (xy 29.527892 -492.179933) (xy 29.54386 -492.094513)
			(xy 29.567641 -492.010931) (xy 29.599033 -491.929899) (xy 29.637767 -491.85211) (xy 29.683514 -491.778226)
			(xy 29.735883 -491.708879) (xy 29.794427 -491.644659) (xy 29.858647 -491.586115) (xy 29.927994 -491.533746)
			(xy 30.001878 -491.487999) (xy 30.079667 -491.449265) (xy 30.160699 -491.417873) (xy 30.244281 -491.394092)
			(xy 30.329701 -491.378124) (xy 30.41623 -491.370106) (xy 30.50313 -491.370106) (xy 30.589659 -491.378124)
			(xy 30.675079 -491.394092) (xy 30.758661 -491.417873) (xy 30.839693 -491.449265) (xy 30.917482 -491.487999)
			(xy 30.991366 -491.533746) (xy 31.060713 -491.586115) (xy 31.124933 -491.644659) (xy 31.183477 -491.708879)
			(xy 31.235846 -491.778226) (xy 31.281593 -491.85211) (xy 31.320327 -491.929899) (xy 31.351719 -492.010931)
			(xy 31.3755 -492.094513) (xy 31.391468 -492.179933) (xy 31.399486 -492.266462) (xy 31.399988 -492.309912)
			(xy 31.399486 -492.353362) (xy 34.599874 -492.353362) (xy 34.599874 -492.266462) (xy 34.607892 -492.179933)
			(xy 34.62386 -492.094513) (xy 34.647641 -492.010931) (xy 34.679033 -491.929899) (xy 34.717767 -491.85211)
			(xy 34.763514 -491.778226) (xy 34.815883 -491.708879) (xy 34.874427 -491.644659) (xy 34.938647 -491.586115)
			(xy 35.007994 -491.533746) (xy 35.081878 -491.487999) (xy 35.159667 -491.449265) (xy 35.240699 -491.417873)
			(xy 35.324281 -491.394092) (xy 35.409701 -491.378124) (xy 35.49623 -491.370106) (xy 35.58313 -491.370106)
			(xy 35.669659 -491.378124) (xy 35.755079 -491.394092) (xy 35.838661 -491.417873) (xy 35.919693 -491.449265)
			(xy 35.997482 -491.487999) (xy 36.071366 -491.533746) (xy 36.140713 -491.586115) (xy 36.204933 -491.644659)
			(xy 36.263477 -491.708879) (xy 36.315846 -491.778226) (xy 36.361593 -491.85211) (xy 36.400327 -491.929899)
			(xy 36.431719 -492.010931) (xy 36.4555 -492.094513) (xy 36.471468 -492.179933) (xy 36.479486 -492.266462)
			(xy 36.479988 -492.309912) (xy 36.479486 -492.353362) (xy 36.471468 -492.439891) (xy 36.4555 -492.525311)
			(xy 36.431719 -492.608893) (xy 36.400327 -492.689925) (xy 36.361593 -492.767714) (xy 36.315846 -492.841598)
			(xy 36.263477 -492.910945) (xy 36.204933 -492.975165) (xy 36.140713 -493.033709) (xy 36.071366 -493.086078)
			(xy 35.997482 -493.131825) (xy 35.919693 -493.170559) (xy 35.838661 -493.201951) (xy 35.755079 -493.225732)
			(xy 35.669659 -493.2417) (xy 35.58313 -493.249718) (xy 35.49623 -493.249718) (xy 35.409701 -493.2417)
			(xy 35.324281 -493.225732) (xy 35.240699 -493.201951) (xy 35.159667 -493.170559) (xy 35.081878 -493.131825)
			(xy 35.007994 -493.086078) (xy 34.938647 -493.033709) (xy 34.874427 -492.975165) (xy 34.815883 -492.910945)
			(xy 34.763514 -492.841598) (xy 34.717767 -492.767714) (xy 34.679033 -492.689925) (xy 34.647641 -492.608893)
			(xy 34.62386 -492.525311) (xy 34.607892 -492.439891) (xy 34.599874 -492.353362) (xy 31.399486 -492.353362)
			(xy 31.391468 -492.439891) (xy 31.3755 -492.525311) (xy 31.351719 -492.608893) (xy 31.320327 -492.689925)
			(xy 31.281593 -492.767714) (xy 31.235846 -492.841598) (xy 31.183477 -492.910945) (xy 31.124933 -492.975165)
			(xy 31.060713 -493.033709) (xy 30.991366 -493.086078) (xy 30.917482 -493.131825) (xy 30.839693 -493.170559)
			(xy 30.758661 -493.201951) (xy 30.675079 -493.225732) (xy 30.589659 -493.2417) (xy 30.50313 -493.249718)
			(xy 30.41623 -493.249718) (xy 30.329701 -493.2417) (xy 30.244281 -493.225732) (xy 30.160699 -493.201951)
			(xy 30.079667 -493.170559) (xy 30.001878 -493.131825) (xy 29.927994 -493.086078) (xy 29.858647 -493.033709)
			(xy 29.794427 -492.975165) (xy 29.735883 -492.910945) (xy 29.683514 -492.841598) (xy 29.637767 -492.767714)
			(xy 29.599033 -492.689925) (xy 29.567641 -492.608893) (xy 29.54386 -492.525311) (xy 29.527892 -492.439891)
			(xy 29.519874 -492.353362) (xy 8.747219 -492.353362) (xy 8.729318 -492.403288) (xy 8.690968 -492.486828)
			(xy 8.645579 -492.566763) (xy 8.593487 -492.6425) (xy 8.535076 -492.713478) (xy 8.470781 -492.779172)
			(xy 8.401075 -492.839096) (xy 8.326477 -492.892806) (xy 8.247537 -492.939905) (xy 8.164841 -492.980043)
			(xy 8.079001 -493.012923) (xy 7.990652 -493.038303) (xy 7.900448 -493.055993) (xy 7.809057 -493.065864)
			(xy 7.717156 -493.067842) (xy 7.625425 -493.061912) (xy 7.534544 -493.048118) (xy 7.445185 -493.026564)
			(xy 7.358009 -492.997407) (xy 7.273663 -492.960864) (xy 7.19277 -492.917205) (xy 7.11593 -492.866754)
			(xy 7.043711 -492.809884) (xy 6.976649 -492.747017) (xy 6.915239 -492.678617) (xy 6.859936 -492.605192)
			(xy 6.81115 -492.527284) (xy 6.769242 -492.445471) (xy 6.734522 -492.360357) (xy 6.707248 -492.272575)
			(xy 6.687621 -492.182772) (xy 6.675786 -492.091615) (xy 6.671831 -491.999778) (xy 1.27 -491.999778)
			(xy 1.27 -495.042635) (xy 4.852911 -495.042635) (xy 4.852911 -494.956909) (xy 4.860821 -494.871549)
			(xy 4.876573 -494.787282) (xy 4.900033 -494.704829) (xy 4.931001 -494.624892) (xy 4.969212 -494.548153)
			(xy 5.014341 -494.475267) (xy 5.066002 -494.406856) (xy 5.123756 -494.343504) (xy 5.187108 -494.28575)
			(xy 5.255519 -494.234089) (xy 5.328405 -494.18896) (xy 5.405144 -494.150749) (xy 5.485081 -494.119781)
			(xy 5.567534 -494.096321) (xy 5.651801 -494.080569) (xy 5.737161 -494.072659) (xy 5.822887 -494.072659)
			(xy 5.908247 -494.080569) (xy 5.992514 -494.096321) (xy 6.074967 -494.119781) (xy 6.154904 -494.150749)
			(xy 6.231643 -494.18896) (xy 6.304529 -494.234089) (xy 6.37294 -494.28575) (xy 6.436292 -494.343504)
			(xy 6.494046 -494.406856) (xy 6.545707 -494.475267) (xy 6.590836 -494.548153) (xy 6.629047 -494.624892)
			(xy 6.660015 -494.704829) (xy 6.683475 -494.787282) (xy 6.699227 -494.871549) (xy 6.701248 -494.893362)
			(xy 29.519874 -494.893362) (xy 29.519874 -494.806462) (xy 29.527892 -494.719933) (xy 29.54386 -494.634513)
			(xy 29.567641 -494.550931) (xy 29.599033 -494.469899) (xy 29.637767 -494.39211) (xy 29.683514 -494.318226)
			(xy 29.735883 -494.248879) (xy 29.794427 -494.184659) (xy 29.858647 -494.126115) (xy 29.927994 -494.073746)
			(xy 30.001878 -494.027999) (xy 30.079667 -493.989265) (xy 30.160699 -493.957873) (xy 30.244281 -493.934092)
			(xy 30.329701 -493.918124) (xy 30.41623 -493.910106) (xy 30.50313 -493.910106) (xy 30.589659 -493.918124)
			(xy 30.675079 -493.934092) (xy 30.758661 -493.957873) (xy 30.839693 -493.989265) (xy 30.917482 -494.027999)
			(xy 30.991366 -494.073746) (xy 31.060713 -494.126115) (xy 31.124933 -494.184659) (xy 31.183477 -494.248879)
			(xy 31.235846 -494.318226) (xy 31.281593 -494.39211) (xy 31.320327 -494.469899) (xy 31.351719 -494.550931)
			(xy 31.3755 -494.634513) (xy 31.391468 -494.719933) (xy 31.399486 -494.806462) (xy 31.399988 -494.849912)
			(xy 31.399486 -494.893362) (xy 34.599874 -494.893362) (xy 34.599874 -494.806462) (xy 34.607892 -494.719933)
			(xy 34.62386 -494.634513) (xy 34.647641 -494.550931) (xy 34.679033 -494.469899) (xy 34.717767 -494.39211)
			(xy 34.763514 -494.318226) (xy 34.815883 -494.248879) (xy 34.874427 -494.184659) (xy 34.938647 -494.126115)
			(xy 35.007994 -494.073746) (xy 35.081878 -494.027999) (xy 35.159667 -493.989265) (xy 35.240699 -493.957873)
			(xy 35.324281 -493.934092) (xy 35.409701 -493.918124) (xy 35.49623 -493.910106) (xy 35.58313 -493.910106)
			(xy 35.669659 -493.918124) (xy 35.755079 -493.934092) (xy 35.838661 -493.957873) (xy 35.919693 -493.989265)
			(xy 35.997482 -494.027999) (xy 36.071366 -494.073746) (xy 36.140713 -494.126115) (xy 36.204933 -494.184659)
			(xy 36.263477 -494.248879) (xy 36.315846 -494.318226) (xy 36.361593 -494.39211) (xy 36.400327 -494.469899)
			(xy 36.431719 -494.550931) (xy 36.4555 -494.634513) (xy 36.471468 -494.719933) (xy 36.479486 -494.806462)
			(xy 36.479988 -494.849912) (xy 36.479486 -494.893362) (xy 36.471468 -494.979891) (xy 36.4555 -495.065311)
			(xy 36.431719 -495.148893) (xy 36.400327 -495.229925) (xy 36.361593 -495.307714) (xy 36.315846 -495.381598)
			(xy 36.263477 -495.450945) (xy 36.204933 -495.515165) (xy 36.140713 -495.573709) (xy 36.071366 -495.626078)
			(xy 35.997482 -495.671825) (xy 35.919693 -495.710559) (xy 35.838661 -495.741951) (xy 35.755079 -495.765732)
			(xy 35.669659 -495.7817) (xy 35.58313 -495.789718) (xy 35.49623 -495.789718) (xy 35.409701 -495.7817)
			(xy 35.324281 -495.765732) (xy 35.240699 -495.741951) (xy 35.159667 -495.710559) (xy 35.081878 -495.671825)
			(xy 35.007994 -495.626078) (xy 34.938647 -495.573709) (xy 34.874427 -495.515165) (xy 34.815883 -495.450945)
			(xy 34.763514 -495.381598) (xy 34.717767 -495.307714) (xy 34.679033 -495.229925) (xy 34.647641 -495.148893)
			(xy 34.62386 -495.065311) (xy 34.607892 -494.979891) (xy 34.599874 -494.893362) (xy 31.399486 -494.893362)
			(xy 31.391468 -494.979891) (xy 31.3755 -495.065311) (xy 31.351719 -495.148893) (xy 31.320327 -495.229925)
			(xy 31.281593 -495.307714) (xy 31.235846 -495.381598) (xy 31.183477 -495.450945) (xy 31.124933 -495.515165)
			(xy 31.060713 -495.573709) (xy 30.991366 -495.626078) (xy 30.917482 -495.671825) (xy 30.839693 -495.710559)
			(xy 30.758661 -495.741951) (xy 30.675079 -495.765732) (xy 30.589659 -495.7817) (xy 30.50313 -495.789718)
			(xy 30.41623 -495.789718) (xy 30.329701 -495.7817) (xy 30.244281 -495.765732) (xy 30.160699 -495.741951)
			(xy 30.079667 -495.710559) (xy 30.001878 -495.671825) (xy 29.927994 -495.626078) (xy 29.858647 -495.573709)
			(xy 29.794427 -495.515165) (xy 29.735883 -495.450945) (xy 29.683514 -495.381598) (xy 29.637767 -495.307714)
			(xy 29.599033 -495.229925) (xy 29.567641 -495.148893) (xy 29.54386 -495.065311) (xy 29.527892 -494.979891)
			(xy 29.519874 -494.893362) (xy 6.701248 -494.893362) (xy 6.707137 -494.956909) (xy 6.707632 -494.999772)
			(xy 6.707137 -495.042635) (xy 6.699227 -495.127995) (xy 6.683475 -495.212262) (xy 6.660015 -495.294715)
			(xy 6.629047 -495.374652) (xy 6.590836 -495.451391) (xy 6.545707 -495.524277) (xy 6.494046 -495.592688)
			(xy 6.436292 -495.65604) (xy 6.37294 -495.713794) (xy 6.304529 -495.765455) (xy 6.231643 -495.810584)
			(xy 6.154904 -495.848795) (xy 6.1258 -495.86007) (xy 39.818564 -495.86007) (xy 39.819058 -495.802661)
			(xy 39.826902 -495.688113) (xy 39.842544 -495.574366) (xy 39.865911 -495.461952) (xy 39.896896 -495.351394)
			(xy 39.935352 -495.243209) (xy 39.981101 -495.1379) (xy 40.03393 -495.035958) (xy 40.093592 -494.937859)
			(xy 40.159809 -494.84406) (xy 40.232272 -494.754998) (xy 40.310645 -494.671089) (xy 40.39456 -494.592723)
			(xy 40.483627 -494.520266) (xy 40.577431 -494.454056) (xy 40.675535 -494.394402) (xy 40.777481 -494.341581)
			(xy 40.882793 -494.295839) (xy 40.990981 -494.257391) (xy 41.101541 -494.226415) (xy 41.213957 -494.203056)
			(xy 41.327705 -494.187423) (xy 41.442254 -494.179588) (xy 41.557072 -494.179588) (xy 41.671621 -494.187423)
			(xy 41.785369 -494.203056) (xy 41.897785 -494.226415) (xy 42.008345 -494.257391) (xy 42.116533 -494.295839)
			(xy 42.221845 -494.341581) (xy 42.323791 -494.394402) (xy 42.421895 -494.454056) (xy 42.501239 -494.51006)
			(xy 43.327577 -494.51006) (xy 43.331612 -494.434356) (xy 43.343671 -494.359511) (xy 43.363617 -494.28637)
			(xy 43.391224 -494.215765) (xy 43.42618 -494.148494) (xy 43.468088 -494.085319) (xy 43.516474 -494.026957)
			(xy 43.57079 -493.974069) (xy 43.630419 -493.927254) (xy 43.694687 -493.887042) (xy 43.762864 -493.85389)
			(xy 43.83418 -493.828172) (xy 43.907825 -493.81018) (xy 43.982965 -493.800118) (xy 44.058749 -493.798099)
			(xy 44.134319 -493.804148) (xy 44.208817 -493.818195) (xy 44.2814 -493.840081) (xy 44.351246 -493.869558)
			(xy 44.417563 -493.906293) (xy 44.479599 -493.949868) (xy 44.536652 -493.99979) (xy 44.588076 -494.055494)
			(xy 44.633287 -494.116349) (xy 44.671774 -494.181664) (xy 44.7031 -494.2507) (xy 44.72691 -494.322675)
			(xy 44.742935 -494.396773) (xy 44.750994 -494.472154) (xy 44.751498 -494.51006) (xy 45.867577 -494.51006)
			(xy 45.871612 -494.434356) (xy 45.883671 -494.359511) (xy 45.903617 -494.28637) (xy 45.931224 -494.215765)
			(xy 45.96618 -494.148494) (xy 46.008088 -494.085319) (xy 46.056474 -494.026957) (xy 46.11079 -493.974069)
			(xy 46.170419 -493.927254) (xy 46.234687 -493.887042) (xy 46.302864 -493.85389) (xy 46.37418 -493.828172)
			(xy 46.447825 -493.81018) (xy 46.522965 -493.800118) (xy 46.598749 -493.798099) (xy 46.674319 -493.804148)
			(xy 46.748817 -493.818195) (xy 46.8214 -493.840081) (xy 46.891246 -493.869558) (xy 46.957563 -493.906293)
			(xy 47.019599 -493.949868) (xy 47.076652 -493.99979) (xy 47.128076 -494.055494) (xy 47.173287 -494.116349)
			(xy 47.211774 -494.181664) (xy 47.2431 -494.2507) (xy 47.26691 -494.322675) (xy 47.282935 -494.396773)
			(xy 47.290994 -494.472154) (xy 47.291498 -494.51006) (xy 48.407577 -494.51006) (xy 48.411612 -494.434356)
			(xy 48.423671 -494.359511) (xy 48.443617 -494.28637) (xy 48.471224 -494.215765) (xy 48.50618 -494.148494)
			(xy 48.548088 -494.085319) (xy 48.596474 -494.026957) (xy 48.65079 -493.974069) (xy 48.710419 -493.927254)
			(xy 48.774687 -493.887042) (xy 48.842864 -493.85389) (xy 48.91418 -493.828172) (xy 48.987825 -493.81018)
			(xy 49.062965 -493.800118) (xy 49.138749 -493.798099) (xy 49.214319 -493.804148) (xy 49.288817 -493.818195)
			(xy 49.3614 -493.840081) (xy 49.431246 -493.869558) (xy 49.497563 -493.906293) (xy 49.559599 -493.949868)
			(xy 49.616652 -493.99979) (xy 49.668076 -494.055494) (xy 49.713287 -494.116349) (xy 49.751774 -494.181664)
			(xy 49.7831 -494.2507) (xy 49.80691 -494.322675) (xy 49.822935 -494.396773) (xy 49.830994 -494.472154)
			(xy 49.831498 -494.51006) (xy 50.947577 -494.51006) (xy 50.951612 -494.434356) (xy 50.963671 -494.359511)
			(xy 50.983617 -494.28637) (xy 51.011224 -494.215765) (xy 51.04618 -494.148494) (xy 51.088088 -494.085319)
			(xy 51.136474 -494.026957) (xy 51.19079 -493.974069) (xy 51.250419 -493.927254) (xy 51.314687 -493.887042)
			(xy 51.382864 -493.85389) (xy 51.45418 -493.828172) (xy 51.527825 -493.81018) (xy 51.602965 -493.800118)
			(xy 51.678749 -493.798099) (xy 51.754319 -493.804148) (xy 51.828817 -493.818195) (xy 51.9014 -493.840081)
			(xy 51.971246 -493.869558) (xy 52.037563 -493.906293) (xy 52.099599 -493.949868) (xy 52.156652 -493.99979)
			(xy 52.208076 -494.055494) (xy 52.253287 -494.116349) (xy 52.291774 -494.181664) (xy 52.3231 -494.2507)
			(xy 52.34691 -494.322675) (xy 52.362935 -494.396773) (xy 52.370994 -494.472154) (xy 52.371498 -494.51006)
			(xy 53.487577 -494.51006) (xy 53.491612 -494.434356) (xy 53.503671 -494.359511) (xy 53.523617 -494.28637)
			(xy 53.551224 -494.215765) (xy 53.58618 -494.148494) (xy 53.628088 -494.085319) (xy 53.676474 -494.026957)
			(xy 53.73079 -493.974069) (xy 53.790419 -493.927254) (xy 53.854687 -493.887042) (xy 53.922864 -493.85389)
			(xy 53.99418 -493.828172) (xy 54.067825 -493.81018) (xy 54.142965 -493.800118) (xy 54.218749 -493.798099)
			(xy 54.294319 -493.804148) (xy 54.368817 -493.818195) (xy 54.4414 -493.840081) (xy 54.511246 -493.869558)
			(xy 54.577563 -493.906293) (xy 54.639599 -493.949868) (xy 54.696652 -493.99979) (xy 54.748076 -494.055494)
			(xy 54.793287 -494.116349) (xy 54.831774 -494.181664) (xy 54.8631 -494.2507) (xy 54.88691 -494.322675)
			(xy 54.902935 -494.396773) (xy 54.910994 -494.472154) (xy 54.911498 -494.51006) (xy 56.027577 -494.51006)
			(xy 56.031612 -494.434356) (xy 56.043671 -494.359511) (xy 56.063617 -494.28637) (xy 56.091224 -494.215765)
			(xy 56.12618 -494.148494) (xy 56.168088 -494.085319) (xy 56.216474 -494.026957) (xy 56.27079 -493.974069)
			(xy 56.330419 -493.927254) (xy 56.394687 -493.887042) (xy 56.462864 -493.85389) (xy 56.53418 -493.828172)
			(xy 56.607825 -493.81018) (xy 56.682965 -493.800118) (xy 56.758749 -493.798099) (xy 56.834319 -493.804148)
			(xy 56.908817 -493.818195) (xy 56.9814 -493.840081) (xy 57.051246 -493.869558) (xy 57.117563 -493.906293)
			(xy 57.179599 -493.949868) (xy 57.236652 -493.99979) (xy 57.288076 -494.055494) (xy 57.333287 -494.116349)
			(xy 57.371774 -494.181664) (xy 57.4031 -494.2507) (xy 57.42691 -494.322675) (xy 57.442935 -494.396773)
			(xy 57.450994 -494.472154) (xy 57.451498 -494.51006) (xy 58.567577 -494.51006) (xy 58.571612 -494.434356)
			(xy 58.583671 -494.359511) (xy 58.603617 -494.28637) (xy 58.631224 -494.215765) (xy 58.66618 -494.148494)
			(xy 58.708088 -494.085319) (xy 58.756474 -494.026957) (xy 58.81079 -493.974069) (xy 58.870419 -493.927254)
			(xy 58.934687 -493.887042) (xy 59.002864 -493.85389) (xy 59.07418 -493.828172) (xy 59.147825 -493.81018)
			(xy 59.222965 -493.800118) (xy 59.298749 -493.798099) (xy 59.374319 -493.804148) (xy 59.448817 -493.818195)
			(xy 59.5214 -493.840081) (xy 59.591246 -493.869558) (xy 59.657563 -493.906293) (xy 59.719599 -493.949868)
			(xy 59.776652 -493.99979) (xy 59.828076 -494.055494) (xy 59.873287 -494.116349) (xy 59.911774 -494.181664)
			(xy 59.9431 -494.2507) (xy 59.96691 -494.322675) (xy 59.982935 -494.396773) (xy 59.990994 -494.472154)
			(xy 59.991498 -494.51006) (xy 61.107577 -494.51006) (xy 61.111612 -494.434356) (xy 61.123671 -494.359511)
			(xy 61.143617 -494.28637) (xy 61.171224 -494.215765) (xy 61.20618 -494.148494) (xy 61.248088 -494.085319)
			(xy 61.296474 -494.026957) (xy 61.35079 -493.974069) (xy 61.410419 -493.927254) (xy 61.474687 -493.887042)
			(xy 61.542864 -493.85389) (xy 61.61418 -493.828172) (xy 61.687825 -493.81018) (xy 61.762965 -493.800118)
			(xy 61.838749 -493.798099) (xy 61.914319 -493.804148) (xy 61.988817 -493.818195) (xy 62.0614 -493.840081)
			(xy 62.131246 -493.869558) (xy 62.197563 -493.906293) (xy 62.259599 -493.949868) (xy 62.316652 -493.99979)
			(xy 62.368076 -494.055494) (xy 62.413287 -494.116349) (xy 62.451774 -494.181664) (xy 62.4831 -494.2507)
			(xy 62.50691 -494.322675) (xy 62.522935 -494.396773) (xy 62.530994 -494.472154) (xy 62.531498 -494.51006)
			(xy 62.530994 -494.547966) (xy 62.522935 -494.623347) (xy 62.50691 -494.697445) (xy 62.4831 -494.76942)
			(xy 62.451774 -494.838456) (xy 62.413287 -494.903771) (xy 62.368076 -494.964626) (xy 62.316652 -495.02033)
			(xy 62.259599 -495.070252) (xy 62.197563 -495.113827) (xy 62.131246 -495.150562) (xy 62.0614 -495.180039)
			(xy 61.988817 -495.201925) (xy 61.914319 -495.215972) (xy 61.838749 -495.222021) (xy 61.762965 -495.220002)
			(xy 61.687825 -495.20994) (xy 61.61418 -495.191948) (xy 61.542864 -495.16623) (xy 61.474687 -495.133078)
			(xy 61.410419 -495.092866) (xy 61.35079 -495.046051) (xy 61.296474 -494.993163) (xy 61.248088 -494.934801)
			(xy 61.20618 -494.871626) (xy 61.171224 -494.804355) (xy 61.143617 -494.73375) (xy 61.123671 -494.660609)
			(xy 61.111612 -494.585764) (xy 61.107577 -494.51006) (xy 59.991498 -494.51006) (xy 59.990994 -494.547966)
			(xy 59.982935 -494.623347) (xy 59.96691 -494.697445) (xy 59.9431 -494.76942) (xy 59.911774 -494.838456)
			(xy 59.873287 -494.903771) (xy 59.828076 -494.964626) (xy 59.776652 -495.02033) (xy 59.719599 -495.070252)
			(xy 59.657563 -495.113827) (xy 59.591246 -495.150562) (xy 59.5214 -495.180039) (xy 59.448817 -495.201925)
			(xy 59.374319 -495.215972) (xy 59.298749 -495.222021) (xy 59.222965 -495.220002) (xy 59.147825 -495.20994)
			(xy 59.07418 -495.191948) (xy 59.002864 -495.16623) (xy 58.934687 -495.133078) (xy 58.870419 -495.092866)
			(xy 58.81079 -495.046051) (xy 58.756474 -494.993163) (xy 58.708088 -494.934801) (xy 58.66618 -494.871626)
			(xy 58.631224 -494.804355) (xy 58.603617 -494.73375) (xy 58.583671 -494.660609) (xy 58.571612 -494.585764)
			(xy 58.567577 -494.51006) (xy 57.451498 -494.51006) (xy 57.450994 -494.547966) (xy 57.442935 -494.623347)
			(xy 57.42691 -494.697445) (xy 57.4031 -494.76942) (xy 57.371774 -494.838456) (xy 57.333287 -494.903771)
			(xy 57.288076 -494.964626) (xy 57.236652 -495.02033) (xy 57.179599 -495.070252) (xy 57.117563 -495.113827)
			(xy 57.051246 -495.150562) (xy 56.9814 -495.180039) (xy 56.908817 -495.201925) (xy 56.834319 -495.215972)
			(xy 56.758749 -495.222021) (xy 56.682965 -495.220002) (xy 56.607825 -495.20994) (xy 56.53418 -495.191948)
			(xy 56.462864 -495.16623) (xy 56.394687 -495.133078) (xy 56.330419 -495.092866) (xy 56.27079 -495.046051)
			(xy 56.216474 -494.993163) (xy 56.168088 -494.934801) (xy 56.12618 -494.871626) (xy 56.091224 -494.804355)
			(xy 56.063617 -494.73375) (xy 56.043671 -494.660609) (xy 56.031612 -494.585764) (xy 56.027577 -494.51006)
			(xy 54.911498 -494.51006) (xy 54.910994 -494.547966) (xy 54.902935 -494.623347) (xy 54.88691 -494.697445)
			(xy 54.8631 -494.76942) (xy 54.831774 -494.838456) (xy 54.793287 -494.903771) (xy 54.748076 -494.964626)
			(xy 54.696652 -495.02033) (xy 54.639599 -495.070252) (xy 54.577563 -495.113827) (xy 54.511246 -495.150562)
			(xy 54.4414 -495.180039) (xy 54.368817 -495.201925) (xy 54.294319 -495.215972) (xy 54.218749 -495.222021)
			(xy 54.142965 -495.220002) (xy 54.067825 -495.20994) (xy 53.99418 -495.191948) (xy 53.922864 -495.16623)
			(xy 53.854687 -495.133078) (xy 53.790419 -495.092866) (xy 53.73079 -495.046051) (xy 53.676474 -494.993163)
			(xy 53.628088 -494.934801) (xy 53.58618 -494.871626) (xy 53.551224 -494.804355) (xy 53.523617 -494.73375)
			(xy 53.503671 -494.660609) (xy 53.491612 -494.585764) (xy 53.487577 -494.51006) (xy 52.371498 -494.51006)
			(xy 52.370994 -494.547966) (xy 52.362935 -494.623347) (xy 52.34691 -494.697445) (xy 52.3231 -494.76942)
			(xy 52.291774 -494.838456) (xy 52.253287 -494.903771) (xy 52.208076 -494.964626) (xy 52.156652 -495.02033)
			(xy 52.099599 -495.070252) (xy 52.037563 -495.113827) (xy 51.971246 -495.150562) (xy 51.9014 -495.180039)
			(xy 51.828817 -495.201925) (xy 51.754319 -495.215972) (xy 51.678749 -495.222021) (xy 51.602965 -495.220002)
			(xy 51.527825 -495.20994) (xy 51.45418 -495.191948) (xy 51.382864 -495.16623) (xy 51.314687 -495.133078)
			(xy 51.250419 -495.092866) (xy 51.19079 -495.046051) (xy 51.136474 -494.993163) (xy 51.088088 -494.934801)
			(xy 51.04618 -494.871626) (xy 51.011224 -494.804355) (xy 50.983617 -494.73375) (xy 50.963671 -494.660609)
			(xy 50.951612 -494.585764) (xy 50.947577 -494.51006) (xy 49.831498 -494.51006) (xy 49.830994 -494.547966)
			(xy 49.822935 -494.623347) (xy 49.80691 -494.697445) (xy 49.7831 -494.76942) (xy 49.751774 -494.838456)
			(xy 49.713287 -494.903771) (xy 49.668076 -494.964626) (xy 49.616652 -495.02033) (xy 49.559599 -495.070252)
			(xy 49.497563 -495.113827) (xy 49.431246 -495.150562) (xy 49.3614 -495.180039) (xy 49.288817 -495.201925)
			(xy 49.214319 -495.215972) (xy 49.138749 -495.222021) (xy 49.062965 -495.220002) (xy 48.987825 -495.20994)
			(xy 48.91418 -495.191948) (xy 48.842864 -495.16623) (xy 48.774687 -495.133078) (xy 48.710419 -495.092866)
			(xy 48.65079 -495.046051) (xy 48.596474 -494.993163) (xy 48.548088 -494.934801) (xy 48.50618 -494.871626)
			(xy 48.471224 -494.804355) (xy 48.443617 -494.73375) (xy 48.423671 -494.660609) (xy 48.411612 -494.585764)
			(xy 48.407577 -494.51006) (xy 47.291498 -494.51006) (xy 47.290994 -494.547966) (xy 47.282935 -494.623347)
			(xy 47.26691 -494.697445) (xy 47.2431 -494.76942) (xy 47.211774 -494.838456) (xy 47.173287 -494.903771)
			(xy 47.128076 -494.964626) (xy 47.076652 -495.02033) (xy 47.019599 -495.070252) (xy 46.957563 -495.113827)
			(xy 46.891246 -495.150562) (xy 46.8214 -495.180039) (xy 46.748817 -495.201925) (xy 46.674319 -495.215972)
			(xy 46.598749 -495.222021) (xy 46.522965 -495.220002) (xy 46.447825 -495.20994) (xy 46.37418 -495.191948)
			(xy 46.302864 -495.16623) (xy 46.234687 -495.133078) (xy 46.170419 -495.092866) (xy 46.11079 -495.046051)
			(xy 46.056474 -494.993163) (xy 46.008088 -494.934801) (xy 45.96618 -494.871626) (xy 45.931224 -494.804355)
			(xy 45.903617 -494.73375) (xy 45.883671 -494.660609) (xy 45.871612 -494.585764) (xy 45.867577 -494.51006)
			(xy 44.751498 -494.51006) (xy 44.750994 -494.547966) (xy 44.742935 -494.623347) (xy 44.72691 -494.697445)
			(xy 44.7031 -494.76942) (xy 44.671774 -494.838456) (xy 44.633287 -494.903771) (xy 44.588076 -494.964626)
			(xy 44.536652 -495.02033) (xy 44.479599 -495.070252) (xy 44.417563 -495.113827) (xy 44.351246 -495.150562)
			(xy 44.2814 -495.180039) (xy 44.208817 -495.201925) (xy 44.134319 -495.215972) (xy 44.058749 -495.222021)
			(xy 43.982965 -495.220002) (xy 43.907825 -495.20994) (xy 43.83418 -495.191948) (xy 43.762864 -495.16623)
			(xy 43.694687 -495.133078) (xy 43.630419 -495.092866) (xy 43.57079 -495.046051) (xy 43.516474 -494.993163)
			(xy 43.468088 -494.934801) (xy 43.42618 -494.871626) (xy 43.391224 -494.804355) (xy 43.363617 -494.73375)
			(xy 43.343671 -494.660609) (xy 43.331612 -494.585764) (xy 43.327577 -494.51006) (xy 42.501239 -494.51006)
			(xy 42.515699 -494.520266) (xy 42.604766 -494.592723) (xy 42.688681 -494.671089) (xy 42.767054 -494.754998)
			(xy 42.839517 -494.84406) (xy 42.905734 -494.937859) (xy 42.965396 -495.035958) (xy 43.018225 -495.1379)
			(xy 43.063974 -495.243209) (xy 43.10243 -495.351394) (xy 43.133415 -495.461952) (xy 43.156782 -495.574366)
			(xy 43.172424 -495.688113) (xy 43.180268 -495.802661) (xy 43.180762 -495.86007) (xy 43.180576 -495.893253)
			(xy 43.177909 -495.959567) (xy 43.175428 -495.992658) (xy 43.170272 -496.050942) (xy 43.152948 -496.166671)
			(xy 43.127616 -496.280914) (xy 43.094401 -496.393119) (xy 43.053462 -496.502742) (xy 43.004999 -496.609253)
			(xy 42.949245 -496.712135) (xy 42.886471 -496.810891) (xy 42.816981 -496.905042) (xy 42.741111 -496.994132)
			(xy 42.659229 -497.077729) (xy 42.571732 -497.15543) (xy 42.500813 -497.21008) (xy 43.327577 -497.21008)
			(xy 43.331612 -497.134376) (xy 43.343671 -497.059531) (xy 43.363617 -496.98639) (xy 43.391224 -496.915785)
			(xy 43.42618 -496.848514) (xy 43.468088 -496.785339) (xy 43.516474 -496.726977) (xy 43.57079 -496.674089)
			(xy 43.630419 -496.627274) (xy 43.694687 -496.587062) (xy 43.762864 -496.55391) (xy 43.83418 -496.528192)
			(xy 43.907825 -496.5102) (xy 43.982965 -496.500138) (xy 44.058749 -496.498119) (xy 44.134319 -496.504168)
			(xy 44.208817 -496.518215) (xy 44.2814 -496.540101) (xy 44.351246 -496.569578) (xy 44.417563 -496.606313)
			(xy 44.479599 -496.649888) (xy 44.536652 -496.69981) (xy 44.588076 -496.755514) (xy 44.633287 -496.816369)
			(xy 44.671774 -496.881684) (xy 44.7031 -496.95072) (xy 44.72691 -497.022695) (xy 44.742935 -497.096793)
			(xy 44.750994 -497.172174) (xy 44.751498 -497.21008) (xy 45.867577 -497.21008) (xy 45.871612 -497.134376)
			(xy 45.883671 -497.059531) (xy 45.903617 -496.98639) (xy 45.931224 -496.915785) (xy 45.96618 -496.848514)
			(xy 46.008088 -496.785339) (xy 46.056474 -496.726977) (xy 46.11079 -496.674089) (xy 46.170419 -496.627274)
			(xy 46.234687 -496.587062) (xy 46.302864 -496.55391) (xy 46.37418 -496.528192) (xy 46.447825 -496.5102)
			(xy 46.522965 -496.500138) (xy 46.598749 -496.498119) (xy 46.674319 -496.504168) (xy 46.748817 -496.518215)
			(xy 46.8214 -496.540101) (xy 46.891246 -496.569578) (xy 46.957563 -496.606313) (xy 47.019599 -496.649888)
			(xy 47.076652 -496.69981) (xy 47.128076 -496.755514) (xy 47.173287 -496.816369) (xy 47.211774 -496.881684)
			(xy 47.2431 -496.95072) (xy 47.26691 -497.022695) (xy 47.282935 -497.096793) (xy 47.290994 -497.172174)
			(xy 47.291498 -497.21008) (xy 48.407577 -497.21008) (xy 48.411612 -497.134376) (xy 48.423671 -497.059531)
			(xy 48.443617 -496.98639) (xy 48.471224 -496.915785) (xy 48.50618 -496.848514) (xy 48.548088 -496.785339)
			(xy 48.596474 -496.726977) (xy 48.65079 -496.674089) (xy 48.710419 -496.627274) (xy 48.774687 -496.587062)
			(xy 48.842864 -496.55391) (xy 48.91418 -496.528192) (xy 48.987825 -496.5102) (xy 49.062965 -496.500138)
			(xy 49.138749 -496.498119) (xy 49.214319 -496.504168) (xy 49.288817 -496.518215) (xy 49.3614 -496.540101)
			(xy 49.431246 -496.569578) (xy 49.497563 -496.606313) (xy 49.559599 -496.649888) (xy 49.616652 -496.69981)
			(xy 49.668076 -496.755514) (xy 49.713287 -496.816369) (xy 49.751774 -496.881684) (xy 49.7831 -496.95072)
			(xy 49.80691 -497.022695) (xy 49.822935 -497.096793) (xy 49.830994 -497.172174) (xy 49.831498 -497.21008)
			(xy 50.947577 -497.21008) (xy 50.951612 -497.134376) (xy 50.963671 -497.059531) (xy 50.983617 -496.98639)
			(xy 51.011224 -496.915785) (xy 51.04618 -496.848514) (xy 51.088088 -496.785339) (xy 51.136474 -496.726977)
			(xy 51.19079 -496.674089) (xy 51.250419 -496.627274) (xy 51.314687 -496.587062) (xy 51.382864 -496.55391)
			(xy 51.45418 -496.528192) (xy 51.527825 -496.5102) (xy 51.602965 -496.500138) (xy 51.678749 -496.498119)
			(xy 51.754319 -496.504168) (xy 51.828817 -496.518215) (xy 51.9014 -496.540101) (xy 51.971246 -496.569578)
			(xy 52.037563 -496.606313) (xy 52.099599 -496.649888) (xy 52.156652 -496.69981) (xy 52.208076 -496.755514)
			(xy 52.253287 -496.816369) (xy 52.291774 -496.881684) (xy 52.3231 -496.95072) (xy 52.34691 -497.022695)
			(xy 52.362935 -497.096793) (xy 52.370994 -497.172174) (xy 52.371498 -497.21008) (xy 53.487577 -497.21008)
			(xy 53.491612 -497.134376) (xy 53.503671 -497.059531) (xy 53.523617 -496.98639) (xy 53.551224 -496.915785)
			(xy 53.58618 -496.848514) (xy 53.628088 -496.785339) (xy 53.676474 -496.726977) (xy 53.73079 -496.674089)
			(xy 53.790419 -496.627274) (xy 53.854687 -496.587062) (xy 53.922864 -496.55391) (xy 53.99418 -496.528192)
			(xy 54.067825 -496.5102) (xy 54.142965 -496.500138) (xy 54.218749 -496.498119) (xy 54.294319 -496.504168)
			(xy 54.368817 -496.518215) (xy 54.4414 -496.540101) (xy 54.511246 -496.569578) (xy 54.577563 -496.606313)
			(xy 54.639599 -496.649888) (xy 54.696652 -496.69981) (xy 54.748076 -496.755514) (xy 54.793287 -496.816369)
			(xy 54.831774 -496.881684) (xy 54.8631 -496.95072) (xy 54.88691 -497.022695) (xy 54.902935 -497.096793)
			(xy 54.910994 -497.172174) (xy 54.911498 -497.21008) (xy 56.027577 -497.21008) (xy 56.031612 -497.134376)
			(xy 56.043671 -497.059531) (xy 56.063617 -496.98639) (xy 56.091224 -496.915785) (xy 56.12618 -496.848514)
			(xy 56.168088 -496.785339) (xy 56.216474 -496.726977) (xy 56.27079 -496.674089) (xy 56.330419 -496.627274)
			(xy 56.394687 -496.587062) (xy 56.462864 -496.55391) (xy 56.53418 -496.528192) (xy 56.607825 -496.5102)
			(xy 56.682965 -496.500138) (xy 56.758749 -496.498119) (xy 56.834319 -496.504168) (xy 56.908817 -496.518215)
			(xy 56.9814 -496.540101) (xy 57.051246 -496.569578) (xy 57.117563 -496.606313) (xy 57.179599 -496.649888)
			(xy 57.236652 -496.69981) (xy 57.288076 -496.755514) (xy 57.333287 -496.816369) (xy 57.371774 -496.881684)
			(xy 57.4031 -496.95072) (xy 57.42691 -497.022695) (xy 57.442935 -497.096793) (xy 57.450994 -497.172174)
			(xy 57.451498 -497.21008) (xy 58.567577 -497.21008) (xy 58.571612 -497.134376) (xy 58.583671 -497.059531)
			(xy 58.603617 -496.98639) (xy 58.631224 -496.915785) (xy 58.66618 -496.848514) (xy 58.708088 -496.785339)
			(xy 58.756474 -496.726977) (xy 58.81079 -496.674089) (xy 58.870419 -496.627274) (xy 58.934687 -496.587062)
			(xy 59.002864 -496.55391) (xy 59.07418 -496.528192) (xy 59.147825 -496.5102) (xy 59.222965 -496.500138)
			(xy 59.298749 -496.498119) (xy 59.374319 -496.504168) (xy 59.448817 -496.518215) (xy 59.5214 -496.540101)
			(xy 59.591246 -496.569578) (xy 59.657563 -496.606313) (xy 59.719599 -496.649888) (xy 59.776652 -496.69981)
			(xy 59.828076 -496.755514) (xy 59.873287 -496.816369) (xy 59.911774 -496.881684) (xy 59.9431 -496.95072)
			(xy 59.96691 -497.022695) (xy 59.982935 -497.096793) (xy 59.990994 -497.172174) (xy 59.991498 -497.21008)
			(xy 61.107577 -497.21008) (xy 61.111612 -497.134376) (xy 61.123671 -497.059531) (xy 61.143617 -496.98639)
			(xy 61.171224 -496.915785) (xy 61.20618 -496.848514) (xy 61.248088 -496.785339) (xy 61.296474 -496.726977)
			(xy 61.35079 -496.674089) (xy 61.410419 -496.627274) (xy 61.474687 -496.587062) (xy 61.542864 -496.55391)
			(xy 61.61418 -496.528192) (xy 61.687825 -496.5102) (xy 61.762965 -496.500138) (xy 61.838749 -496.498119)
			(xy 61.914319 -496.504168) (xy 61.988817 -496.518215) (xy 62.0614 -496.540101) (xy 62.131246 -496.569578)
			(xy 62.197563 -496.606313) (xy 62.259599 -496.649888) (xy 62.316652 -496.69981) (xy 62.368076 -496.755514)
			(xy 62.413287 -496.816369) (xy 62.451774 -496.881684) (xy 62.4831 -496.95072) (xy 62.50691 -497.022695)
			(xy 62.522935 -497.096793) (xy 62.530994 -497.172174) (xy 62.531498 -497.21008) (xy 62.530994 -497.247986)
			(xy 62.522935 -497.323367) (xy 62.50691 -497.397465) (xy 62.4831 -497.46944) (xy 62.451774 -497.538476)
			(xy 62.413287 -497.603791) (xy 62.368076 -497.664646) (xy 62.316652 -497.72035) (xy 62.259599 -497.770272)
			(xy 62.197563 -497.813847) (xy 62.131246 -497.850582) (xy 62.0614 -497.880059) (xy 61.988817 -497.901945)
			(xy 61.914319 -497.915992) (xy 61.838749 -497.922041) (xy 61.762965 -497.920022) (xy 61.687825 -497.90996)
			(xy 61.61418 -497.891968) (xy 61.542864 -497.86625) (xy 61.474687 -497.833098) (xy 61.410419 -497.792886)
			(xy 61.35079 -497.746071) (xy 61.296474 -497.693183) (xy 61.248088 -497.634821) (xy 61.20618 -497.571646)
			(xy 61.171224 -497.504375) (xy 61.143617 -497.43377) (xy 61.123671 -497.360629) (xy 61.111612 -497.285784)
			(xy 61.107577 -497.21008) (xy 59.991498 -497.21008) (xy 59.990994 -497.247986) (xy 59.982935 -497.323367)
			(xy 59.96691 -497.397465) (xy 59.9431 -497.46944) (xy 59.911774 -497.538476) (xy 59.873287 -497.603791)
			(xy 59.828076 -497.664646) (xy 59.776652 -497.72035) (xy 59.719599 -497.770272) (xy 59.657563 -497.813847)
			(xy 59.591246 -497.850582) (xy 59.5214 -497.880059) (xy 59.448817 -497.901945) (xy 59.374319 -497.915992)
			(xy 59.298749 -497.922041) (xy 59.222965 -497.920022) (xy 59.147825 -497.90996) (xy 59.07418 -497.891968)
			(xy 59.002864 -497.86625) (xy 58.934687 -497.833098) (xy 58.870419 -497.792886) (xy 58.81079 -497.746071)
			(xy 58.756474 -497.693183) (xy 58.708088 -497.634821) (xy 58.66618 -497.571646) (xy 58.631224 -497.504375)
			(xy 58.603617 -497.43377) (xy 58.583671 -497.360629) (xy 58.571612 -497.285784) (xy 58.567577 -497.21008)
			(xy 57.451498 -497.21008) (xy 57.450994 -497.247986) (xy 57.442935 -497.323367) (xy 57.42691 -497.397465)
			(xy 57.4031 -497.46944) (xy 57.371774 -497.538476) (xy 57.333287 -497.603791) (xy 57.288076 -497.664646)
			(xy 57.236652 -497.72035) (xy 57.179599 -497.770272) (xy 57.117563 -497.813847) (xy 57.051246 -497.850582)
			(xy 56.9814 -497.880059) (xy 56.908817 -497.901945) (xy 56.834319 -497.915992) (xy 56.758749 -497.922041)
			(xy 56.682965 -497.920022) (xy 56.607825 -497.90996) (xy 56.53418 -497.891968) (xy 56.462864 -497.86625)
			(xy 56.394687 -497.833098) (xy 56.330419 -497.792886) (xy 56.27079 -497.746071) (xy 56.216474 -497.693183)
			(xy 56.168088 -497.634821) (xy 56.12618 -497.571646) (xy 56.091224 -497.504375) (xy 56.063617 -497.43377)
			(xy 56.043671 -497.360629) (xy 56.031612 -497.285784) (xy 56.027577 -497.21008) (xy 54.911498 -497.21008)
			(xy 54.910994 -497.247986) (xy 54.902935 -497.323367) (xy 54.88691 -497.397465) (xy 54.8631 -497.46944)
			(xy 54.831774 -497.538476) (xy 54.793287 -497.603791) (xy 54.748076 -497.664646) (xy 54.696652 -497.72035)
			(xy 54.639599 -497.770272) (xy 54.577563 -497.813847) (xy 54.511246 -497.850582) (xy 54.4414 -497.880059)
			(xy 54.368817 -497.901945) (xy 54.294319 -497.915992) (xy 54.218749 -497.922041) (xy 54.142965 -497.920022)
			(xy 54.067825 -497.90996) (xy 53.99418 -497.891968) (xy 53.922864 -497.86625) (xy 53.854687 -497.833098)
			(xy 53.790419 -497.792886) (xy 53.73079 -497.746071) (xy 53.676474 -497.693183) (xy 53.628088 -497.634821)
			(xy 53.58618 -497.571646) (xy 53.551224 -497.504375) (xy 53.523617 -497.43377) (xy 53.503671 -497.360629)
			(xy 53.491612 -497.285784) (xy 53.487577 -497.21008) (xy 52.371498 -497.21008) (xy 52.370994 -497.247986)
			(xy 52.362935 -497.323367) (xy 52.34691 -497.397465) (xy 52.3231 -497.46944) (xy 52.291774 -497.538476)
			(xy 52.253287 -497.603791) (xy 52.208076 -497.664646) (xy 52.156652 -497.72035) (xy 52.099599 -497.770272)
			(xy 52.037563 -497.813847) (xy 51.971246 -497.850582) (xy 51.9014 -497.880059) (xy 51.828817 -497.901945)
			(xy 51.754319 -497.915992) (xy 51.678749 -497.922041) (xy 51.602965 -497.920022) (xy 51.527825 -497.90996)
			(xy 51.45418 -497.891968) (xy 51.382864 -497.86625) (xy 51.314687 -497.833098) (xy 51.250419 -497.792886)
			(xy 51.19079 -497.746071) (xy 51.136474 -497.693183) (xy 51.088088 -497.634821) (xy 51.04618 -497.571646)
			(xy 51.011224 -497.504375) (xy 50.983617 -497.43377) (xy 50.963671 -497.360629) (xy 50.951612 -497.285784)
			(xy 50.947577 -497.21008) (xy 49.831498 -497.21008) (xy 49.830994 -497.247986) (xy 49.822935 -497.323367)
			(xy 49.80691 -497.397465) (xy 49.7831 -497.46944) (xy 49.751774 -497.538476) (xy 49.713287 -497.603791)
			(xy 49.668076 -497.664646) (xy 49.616652 -497.72035) (xy 49.559599 -497.770272) (xy 49.497563 -497.813847)
			(xy 49.431246 -497.850582) (xy 49.3614 -497.880059) (xy 49.288817 -497.901945) (xy 49.214319 -497.915992)
			(xy 49.138749 -497.922041) (xy 49.062965 -497.920022) (xy 48.987825 -497.90996) (xy 48.91418 -497.891968)
			(xy 48.842864 -497.86625) (xy 48.774687 -497.833098) (xy 48.710419 -497.792886) (xy 48.65079 -497.746071)
			(xy 48.596474 -497.693183) (xy 48.548088 -497.634821) (xy 48.50618 -497.571646) (xy 48.471224 -497.504375)
			(xy 48.443617 -497.43377) (xy 48.423671 -497.360629) (xy 48.411612 -497.285784) (xy 48.407577 -497.21008)
			(xy 47.291498 -497.21008) (xy 47.290994 -497.247986) (xy 47.282935 -497.323367) (xy 47.26691 -497.397465)
			(xy 47.2431 -497.46944) (xy 47.211774 -497.538476) (xy 47.173287 -497.603791) (xy 47.128076 -497.664646)
			(xy 47.076652 -497.72035) (xy 47.019599 -497.770272) (xy 46.957563 -497.813847) (xy 46.891246 -497.850582)
			(xy 46.8214 -497.880059) (xy 46.748817 -497.901945) (xy 46.674319 -497.915992) (xy 46.598749 -497.922041)
			(xy 46.522965 -497.920022) (xy 46.447825 -497.90996) (xy 46.37418 -497.891968) (xy 46.302864 -497.86625)
			(xy 46.234687 -497.833098) (xy 46.170419 -497.792886) (xy 46.11079 -497.746071) (xy 46.056474 -497.693183)
			(xy 46.008088 -497.634821) (xy 45.96618 -497.571646) (xy 45.931224 -497.504375) (xy 45.903617 -497.43377)
			(xy 45.883671 -497.360629) (xy 45.871612 -497.285784) (xy 45.867577 -497.21008) (xy 44.751498 -497.21008)
			(xy 44.750994 -497.247986) (xy 44.742935 -497.323367) (xy 44.72691 -497.397465) (xy 44.7031 -497.46944)
			(xy 44.671774 -497.538476) (xy 44.633287 -497.603791) (xy 44.588076 -497.664646) (xy 44.536652 -497.72035)
			(xy 44.479599 -497.770272) (xy 44.417563 -497.813847) (xy 44.351246 -497.850582) (xy 44.2814 -497.880059)
			(xy 44.208817 -497.901945) (xy 44.134319 -497.915992) (xy 44.058749 -497.922041) (xy 43.982965 -497.920022)
			(xy 43.907825 -497.90996) (xy 43.83418 -497.891968) (xy 43.762864 -497.86625) (xy 43.694687 -497.833098)
			(xy 43.630419 -497.792886) (xy 43.57079 -497.746071) (xy 43.516474 -497.693183) (xy 43.468088 -497.634821)
			(xy 43.42618 -497.571646) (xy 43.391224 -497.504375) (xy 43.363617 -497.43377) (xy 43.343671 -497.360629)
			(xy 43.331612 -497.285784) (xy 43.327577 -497.21008) (xy 42.500813 -497.21008) (xy 42.479042 -497.226857)
			(xy 42.381609 -497.291665) (xy 42.279905 -497.34954) (xy 42.174422 -497.400202) (xy 42.065671 -497.443404)
			(xy 41.954179 -497.478939) (xy 41.840485 -497.506634) (xy 41.725141 -497.526354) (xy 41.608704 -497.538005)
			(xy 41.491739 -497.54153) (xy 41.374812 -497.536912) (xy 41.258489 -497.524173) (xy 41.143334 -497.503375)
			(xy 41.029905 -497.474618) (xy 40.91875 -497.438042) (xy 40.810407 -497.393825) (xy 40.705403 -497.342179)
			(xy 40.604244 -497.283356) (xy 40.507421 -497.21764) (xy 40.415403 -497.145349) (xy 40.328636 -497.066834)
			(xy 40.247539 -496.982474) (xy 40.172506 -496.892679) (xy 40.103899 -496.797883) (xy 40.042051 -496.698544)
			(xy 39.987262 -496.595145) (xy 39.939796 -496.488186) (xy 39.899884 -496.378185) (xy 39.86772 -496.265674)
			(xy 39.843457 -496.151199) (xy 39.827215 -496.035313) (xy 39.819072 -495.918579) (xy 39.818564 -495.86007)
			(xy 6.1258 -495.86007) (xy 6.074967 -495.879763) (xy 5.992514 -495.903223) (xy 5.908247 -495.918975)
			(xy 5.822887 -495.926885) (xy 5.737161 -495.926885) (xy 5.651801 -495.918975) (xy 5.567534 -495.903223)
			(xy 5.485081 -495.879763) (xy 5.405144 -495.848795) (xy 5.328405 -495.810584) (xy 5.255519 -495.765455)
			(xy 5.187108 -495.713794) (xy 5.123756 -495.65604) (xy 5.066002 -495.592688) (xy 5.014341 -495.524277)
			(xy 4.969212 -495.451391) (xy 4.931001 -495.374652) (xy 4.900033 -495.294715) (xy 4.876573 -495.212262)
			(xy 4.860821 -495.127995) (xy 4.852911 -495.042635) (xy 1.27 -495.042635) (xy 1.27 -498.042629) (xy 4.852911 -498.042629)
			(xy 4.852911 -497.956903) (xy 4.860821 -497.871543) (xy 4.876573 -497.787276) (xy 4.900033 -497.704823)
			(xy 4.931001 -497.624886) (xy 4.969212 -497.548147) (xy 5.014341 -497.475261) (xy 5.066002 -497.40685)
			(xy 5.123756 -497.343498) (xy 5.187108 -497.285744) (xy 5.255519 -497.234083) (xy 5.328405 -497.188954)
			(xy 5.405144 -497.150743) (xy 5.485081 -497.119775) (xy 5.567534 -497.096315) (xy 5.651801 -497.080563)
			(xy 5.737161 -497.072653) (xy 5.822887 -497.072653) (xy 5.908247 -497.080563) (xy 5.992514 -497.096315)
			(xy 6.074967 -497.119775) (xy 6.154904 -497.150743) (xy 6.231643 -497.188954) (xy 6.304529 -497.234083)
			(xy 6.37294 -497.285744) (xy 6.436292 -497.343498) (xy 6.494046 -497.40685) (xy 6.545707 -497.475261)
			(xy 6.590836 -497.548147) (xy 6.629047 -497.624886) (xy 6.660015 -497.704823) (xy 6.683475 -497.787276)
			(xy 6.699227 -497.871543) (xy 6.707137 -497.956903) (xy 6.707632 -497.999766) (xy 6.707137 -498.042629)
			(xy 6.699227 -498.127989) (xy 6.683475 -498.212256) (xy 6.660015 -498.294709) (xy 6.629047 -498.374646)
			(xy 6.590836 -498.451385) (xy 6.545707 -498.524271) (xy 6.494046 -498.592682) (xy 6.436292 -498.656034)
			(xy 6.37294 -498.713788) (xy 6.304529 -498.765449) (xy 6.231643 -498.810578) (xy 6.154904 -498.848789)
			(xy 6.074967 -498.879757) (xy 5.992514 -498.903217) (xy 5.908247 -498.918969) (xy 5.822887 -498.926879)
			(xy 5.737161 -498.926879) (xy 5.651801 -498.918969) (xy 5.567534 -498.903217) (xy 5.485081 -498.879757)
			(xy 5.405144 -498.848789) (xy 5.328405 -498.810578) (xy 5.255519 -498.765449) (xy 5.187108 -498.713788)
			(xy 5.123756 -498.656034) (xy 5.066002 -498.592682) (xy 5.014341 -498.524271) (xy 4.969212 -498.451385)
			(xy 4.931001 -498.374646) (xy 4.900033 -498.294709) (xy 4.876573 -498.212256) (xy 4.860821 -498.127989)
			(xy 4.852911 -498.042629) (xy 1.27 -498.042629) (xy 1.27 -500.99976) (xy 6.671831 -500.99976) (xy 6.675786 -500.907923)
			(xy 6.687621 -500.816766) (xy 6.707248 -500.726963) (xy 6.734522 -500.639181) (xy 6.769242 -500.554067)
			(xy 6.81115 -500.472254) (xy 6.859936 -500.394346) (xy 6.915239 -500.320921) (xy 6.976649 -500.252521)
			(xy 7.043711 -500.189654) (xy 7.11593 -500.132784) (xy 7.19277 -500.082333) (xy 7.273663 -500.038674)
			(xy 7.358009 -500.002131) (xy 7.445185 -499.972974) (xy 7.534544 -499.95142) (xy 7.625425 -499.937626)
			(xy 7.717156 -499.931696) (xy 7.809057 -499.933674) (xy 7.900448 -499.943545) (xy 7.990652 -499.961235)
			(xy 8.079001 -499.986615) (xy 8.164841 -500.019495) (xy 8.247537 -500.059633) (xy 8.326477 -500.106732)
			(xy 8.401075 -500.160442) (xy 8.470781 -500.220366) (xy 8.535076 -500.28606) (xy 8.593487 -500.357038)
			(xy 8.645579 -500.432775) (xy 8.690968 -500.51271) (xy 8.729318 -500.59625) (xy 8.760343 -500.682778)
			(xy 8.783816 -500.771653) (xy 8.799562 -500.862217) (xy 8.807464 -500.953799) (xy 8.807958 -500.99976)
			(xy 8.807464 -501.045721) (xy 8.799562 -501.137303) (xy 8.783816 -501.227867) (xy 8.760343 -501.316742)
			(xy 8.729318 -501.40327) (xy 8.690968 -501.48681) (xy 8.645579 -501.566745) (xy 8.593487 -501.642482)
			(xy 8.535076 -501.71346) (xy 8.470781 -501.779154) (xy 8.401075 -501.839078) (xy 8.326477 -501.892788)
			(xy 8.247537 -501.939887) (xy 8.164841 -501.980025) (xy 8.079001 -502.012905) (xy 7.990652 -502.038285)
			(xy 7.900448 -502.055975) (xy 7.809057 -502.065846) (xy 7.717156 -502.067824) (xy 7.625425 -502.061894)
			(xy 7.534544 -502.0481) (xy 7.445185 -502.026546) (xy 7.358009 -501.997389) (xy 7.273663 -501.960846)
			(xy 7.19277 -501.917187) (xy 7.11593 -501.866736) (xy 7.043711 -501.809866) (xy 6.976649 -501.746999)
			(xy 6.915239 -501.678599) (xy 6.859936 -501.605174) (xy 6.81115 -501.527266) (xy 6.769242 -501.445453)
			(xy 6.734522 -501.360339) (xy 6.707248 -501.272557) (xy 6.687621 -501.182754) (xy 6.675786 -501.091597)
			(xy 6.671831 -500.99976) (xy 1.27 -500.99976) (xy 1.27 -507.717975) (xy 47.97424 -507.717975) (xy 47.97424 -507.636865)
			(xy 47.98219 -507.556146) (xy 47.998013 -507.476595) (xy 48.021558 -507.398979) (xy 48.052597 -507.324043)
			(xy 48.090832 -507.252511) (xy 48.135894 -507.185071) (xy 48.187349 -507.122372) (xy 48.244702 -507.065019)
			(xy 48.307401 -507.013564) (xy 48.374841 -506.968502) (xy 48.446373 -506.930267) (xy 48.521309 -506.899228)
			(xy 48.598925 -506.875683) (xy 48.678476 -506.85986) (xy 48.759195 -506.85191) (xy 48.840305 -506.85191)
			(xy 48.921024 -506.85986) (xy 49.000575 -506.875683) (xy 49.078191 -506.899228) (xy 49.153127 -506.930267)
			(xy 49.224659 -506.968502) (xy 49.292099 -507.013564) (xy 49.354798 -507.065019) (xy 49.412151 -507.122372)
			(xy 49.463606 -507.185071) (xy 49.508668 -507.252511) (xy 49.546903 -507.324043) (xy 49.577942 -507.398979)
			(xy 49.601487 -507.476595) (xy 49.61731 -507.556146) (xy 49.62526 -507.636865) (xy 49.625758 -507.67742)
			(xy 49.62526 -507.717975) (xy 51.47436 -507.717975) (xy 51.47436 -507.636865) (xy 51.48231 -507.556146)
			(xy 51.498133 -507.476595) (xy 51.521678 -507.398979) (xy 51.552717 -507.324043) (xy 51.590952 -507.252511)
			(xy 51.636014 -507.185071) (xy 51.687469 -507.122372) (xy 51.744822 -507.065019) (xy 51.807521 -507.013564)
			(xy 51.874961 -506.968502) (xy 51.946493 -506.930267) (xy 52.021429 -506.899228) (xy 52.099045 -506.875683)
			(xy 52.178596 -506.85986) (xy 52.259315 -506.85191) (xy 52.340425 -506.85191) (xy 52.421144 -506.85986)
			(xy 52.500695 -506.875683) (xy 52.578311 -506.899228) (xy 52.653247 -506.930267) (xy 52.724779 -506.968502)
			(xy 52.792219 -507.013564) (xy 52.854918 -507.065019) (xy 52.912271 -507.122372) (xy 52.963726 -507.185071)
			(xy 53.008788 -507.252511) (xy 53.047023 -507.324043) (xy 53.078062 -507.398979) (xy 53.101607 -507.476595)
			(xy 53.11743 -507.556146) (xy 53.12538 -507.636865) (xy 53.125878 -507.67742) (xy 53.12538 -507.717975)
			(xy 53.11743 -507.798694) (xy 53.101607 -507.878245) (xy 53.078062 -507.955861) (xy 53.047023 -508.030797)
			(xy 53.008788 -508.102329) (xy 52.963726 -508.169769) (xy 52.912271 -508.232468) (xy 52.854918 -508.289821)
			(xy 52.792219 -508.341276) (xy 52.724779 -508.386338) (xy 52.653247 -508.424573) (xy 52.578311 -508.455612)
			(xy 52.500695 -508.479157) (xy 52.421144 -508.49498) (xy 52.340425 -508.50293) (xy 52.259315 -508.50293)
			(xy 52.178596 -508.49498) (xy 52.099045 -508.479157) (xy 52.021429 -508.455612) (xy 51.946493 -508.424573)
			(xy 51.874961 -508.386338) (xy 51.807521 -508.341276) (xy 51.744822 -508.289821) (xy 51.687469 -508.232468)
			(xy 51.636014 -508.169769) (xy 51.590952 -508.102329) (xy 51.552717 -508.030797) (xy 51.521678 -507.955861)
			(xy 51.498133 -507.878245) (xy 51.48231 -507.798694) (xy 51.47436 -507.717975) (xy 49.62526 -507.717975)
			(xy 49.61731 -507.798694) (xy 49.601487 -507.878245) (xy 49.577942 -507.955861) (xy 49.546903 -508.030797)
			(xy 49.508668 -508.102329) (xy 49.463606 -508.169769) (xy 49.412151 -508.232468) (xy 49.354798 -508.289821)
			(xy 49.292099 -508.341276) (xy 49.224659 -508.386338) (xy 49.153127 -508.424573) (xy 49.078191 -508.455612)
			(xy 49.000575 -508.479157) (xy 48.921024 -508.49498) (xy 48.840305 -508.50293) (xy 48.759195 -508.50293)
			(xy 48.678476 -508.49498) (xy 48.598925 -508.479157) (xy 48.521309 -508.455612) (xy 48.446373 -508.424573)
			(xy 48.374841 -508.386338) (xy 48.307401 -508.341276) (xy 48.244702 -508.289821) (xy 48.187349 -508.232468)
			(xy 48.135894 -508.169769) (xy 48.090832 -508.102329) (xy 48.052597 -508.030797) (xy 48.021558 -507.955861)
			(xy 47.998013 -507.878245) (xy 47.98219 -507.798694) (xy 47.97424 -507.717975) (xy 1.27 -507.717975)
			(xy 1.27 -509.32461) (xy 80.909412 -509.32461) (xy 80.913483 -509.268988) (xy 80.925609 -509.214551)
			(xy 80.945532 -509.16246) (xy 80.972828 -509.113825) (xy 81.006914 -509.069682) (xy 81.047063 -509.030973)
			(xy 81.092421 -508.998522) (xy 81.142021 -508.973021) (xy 81.194805 -508.955014) (xy 81.249648 -508.944884)
			(xy 81.305382 -508.942847) (xy 81.360819 -508.948947) (xy 81.414776 -508.963053) (xy 81.466105 -508.984865)
			(xy 81.513711 -509.013919) (xy 81.556579 -509.049594) (xy 81.593796 -509.091131) (xy 81.624569 -509.137644)
			(xy 81.648241 -509.188141) (xy 81.664309 -509.241548) (xy 81.672429 -509.296724) (xy 81.672938 -509.32461)
			(xy 81.672674 -509.339088) (xy 82.117944 -509.339088) (xy 82.122015 -509.283466) (xy 82.134141 -509.229029)
			(xy 82.154064 -509.176938) (xy 82.18136 -509.128303) (xy 82.215446 -509.08416) (xy 82.255595 -509.045451)
			(xy 82.300953 -509.013) (xy 82.350553 -508.987499) (xy 82.403337 -508.969492) (xy 82.45818 -508.959362)
			(xy 82.513914 -508.957325) (xy 82.539315 -508.96012) (xy 86.877404 -508.96012) (xy 86.881424 -508.769469)
			(xy 86.893478 -508.579156) (xy 86.913544 -508.389521) (xy 86.941587 -508.2009) (xy 86.977556 -508.01363)
			(xy 87.021388 -507.828042) (xy 87.073005 -507.644467) (xy 87.132315 -507.463231) (xy 87.199213 -507.284656)
			(xy 87.273579 -507.109061) (xy 87.355281 -506.936756) (xy 87.444175 -506.768049) (xy 87.540101 -506.603239)
			(xy 87.64289 -506.44262) (xy 87.752359 -506.286477) (xy 87.868313 -506.135088) (xy 87.990547 -505.988721)
			(xy 88.118841 -505.847637) (xy 88.252969 -505.712088) (xy 88.392693 -505.582313) (xy 88.537763 -505.458543)
			(xy 88.687921 -505.341) (xy 88.842902 -505.229891) (xy 89.002429 -505.125414) (xy 89.166218 -505.027755)
			(xy 89.333978 -504.937088) (xy 89.505412 -504.853574) (xy 89.680214 -504.777361) (xy 89.858073 -504.708585)
			(xy 90.038674 -504.647367) (xy 90.221694 -504.593818) (xy 90.40681 -504.548032) (xy 90.593691 -504.51009)
			(xy 90.782006 -504.480061) (xy 90.971419 -504.457996) (xy 91.161593 -504.443937) (xy 91.352192 -504.437907)
			(xy 91.542875 -504.439917) (xy 91.733304 -504.449964) (xy 91.92314 -504.46803) (xy 92.112046 -504.494083)
			(xy 92.299685 -504.528076) (xy 92.485725 -504.569949) (xy 92.669834 -504.619628) (xy 92.851685 -504.677024)
			(xy 93.030955 -504.742035) (xy 93.207325 -504.814546) (xy 93.380481 -504.894427) (xy 93.550116 -504.981537)
			(xy 93.715928 -505.075721) (xy 93.877622 -505.176812) (xy 94.03491 -505.284628) (xy 94.187513 -505.39898)
			(xy 94.335161 -505.519663) (xy 94.477589 -505.646464) (xy 94.614545 -505.779155) (xy 94.745786 -505.917503)
			(xy 94.871078 -506.06126) (xy 94.990198 -506.210171) (xy 95.102934 -506.363972) (xy 95.209087 -506.522388)
			(xy 95.308467 -506.685139) (xy 95.400897 -506.851934) (xy 95.486214 -507.022478) (xy 95.564266 -507.196466)
			(xy 95.634913 -507.373591) (xy 95.698031 -507.553536) (xy 95.753507 -507.735982) (xy 95.801242 -507.920605)
			(xy 95.841152 -508.107075) (xy 95.873165 -508.295063) (xy 95.897225 -508.484233) (xy 95.913288 -508.674249)
			(xy 95.921327 -508.864773) (xy 95.92183 -508.96012) (xy 95.921327 -509.055467) (xy 95.913288 -509.245991)
			(xy 95.897225 -509.436007) (xy 95.873165 -509.625177) (xy 95.841152 -509.813165) (xy 95.801242 -509.999635)
			(xy 95.753507 -510.184258) (xy 95.698031 -510.366704) (xy 95.634913 -510.546649) (xy 95.564266 -510.723774)
			(xy 95.486214 -510.897762) (xy 95.400897 -511.068306) (xy 95.308467 -511.235101) (xy 95.209087 -511.397852)
			(xy 95.102934 -511.556268) (xy 94.990198 -511.710069) (xy 94.871078 -511.85898) (xy 94.745786 -512.002737)
			(xy 94.614545 -512.141085) (xy 94.477589 -512.273776) (xy 94.335161 -512.400577) (xy 94.187513 -512.52126)
			(xy 94.03491 -512.635612) (xy 93.877622 -512.743428) (xy 93.715928 -512.844519) (xy 93.550116 -512.938703)
			(xy 93.380481 -513.025813) (xy 93.207325 -513.105694) (xy 93.030955 -513.178205) (xy 92.851685 -513.243216)
			(xy 92.669834 -513.300612) (xy 92.485725 -513.350291) (xy 92.299685 -513.392164) (xy 92.112046 -513.426157)
			(xy 91.92314 -513.45221) (xy 91.733304 -513.470276) (xy 91.542875 -513.480323) (xy 91.352192 -513.482333)
			(xy 91.161593 -513.476303) (xy 90.971419 -513.462244) (xy 90.782006 -513.440179) (xy 90.593691 -513.41015)
			(xy 90.40681 -513.372208) (xy 90.221694 -513.326422) (xy 90.038674 -513.272873) (xy 89.858073 -513.211655)
			(xy 89.680214 -513.142879) (xy 89.505412 -513.066666) (xy 89.333978 -512.983152) (xy 89.166218 -512.892485)
			(xy 89.002429 -512.794826) (xy 88.842902 -512.690349) (xy 88.687921 -512.57924) (xy 88.537763 -512.461697)
			(xy 88.392693 -512.337927) (xy 88.252969 -512.208152) (xy 88.118841 -512.072603) (xy 87.990547 -511.931519)
			(xy 87.868313 -511.785152) (xy 87.752359 -511.633763) (xy 87.64289 -511.47762) (xy 87.540101 -511.317001)
			(xy 87.444175 -511.152191) (xy 87.355281 -510.983484) (xy 87.273579 -510.811179) (xy 87.199213 -510.635584)
			(xy 87.132315 -510.457009) (xy 87.073005 -510.275773) (xy 87.021388 -510.092198) (xy 86.977556 -509.90661)
			(xy 86.941587 -509.71934) (xy 86.913544 -509.530719) (xy 86.893478 -509.341084) (xy 86.881424 -509.150771)
			(xy 86.877404 -508.96012) (xy 82.539315 -508.96012) (xy 82.569351 -508.963425) (xy 82.623308 -508.977531)
			(xy 82.674637 -508.999343) (xy 82.722243 -509.028397) (xy 82.765111 -509.064072) (xy 82.802328 -509.105609)
			(xy 82.833101 -509.152122) (xy 82.856773 -509.202619) (xy 82.872841 -509.256026) (xy 82.880961 -509.311202)
			(xy 82.88147 -509.339088) (xy 82.880961 -509.366974) (xy 82.872841 -509.42215) (xy 82.856773 -509.475557)
			(xy 82.833101 -509.526054) (xy 82.802328 -509.572567) (xy 82.765111 -509.614104) (xy 82.722243 -509.649779)
			(xy 82.674637 -509.678833) (xy 82.623308 -509.700645) (xy 82.569351 -509.714751) (xy 82.513914 -509.720851)
			(xy 82.45818 -509.718814) (xy 82.403337 -509.708684) (xy 82.350553 -509.690677) (xy 82.300953 -509.665176)
			(xy 82.255595 -509.632725) (xy 82.215446 -509.594016) (xy 82.18136 -509.549873) (xy 82.154064 -509.501238)
			(xy 82.134141 -509.449147) (xy 82.122015 -509.39471) (xy 82.117944 -509.339088) (xy 81.672674 -509.339088)
			(xy 81.672429 -509.352496) (xy 81.664309 -509.407672) (xy 81.648241 -509.461079) (xy 81.624569 -509.511576)
			(xy 81.593796 -509.558089) (xy 81.556579 -509.599626) (xy 81.513711 -509.635301) (xy 81.466105 -509.664355)
			(xy 81.414776 -509.686167) (xy 81.360819 -509.700273) (xy 81.305382 -509.706373) (xy 81.249648 -509.704336)
			(xy 81.194805 -509.694206) (xy 81.142021 -509.676199) (xy 81.092421 -509.650698) (xy 81.047063 -509.618247)
			(xy 81.006914 -509.579538) (xy 80.972828 -509.535395) (xy 80.945532 -509.48676) (xy 80.925609 -509.434669)
			(xy 80.913483 -509.380232) (xy 80.909412 -509.32461) (xy 1.27 -509.32461) (xy 1.27 -511.049778) (xy 6.671831 -511.049778)
			(xy 6.675786 -510.957941) (xy 6.687621 -510.866784) (xy 6.707248 -510.776981) (xy 6.734522 -510.689199)
			(xy 6.769242 -510.604085) (xy 6.81115 -510.522272) (xy 6.859936 -510.444364) (xy 6.915239 -510.370939)
			(xy 6.976649 -510.302539) (xy 7.043711 -510.239672) (xy 7.11593 -510.182802) (xy 7.19277 -510.132351)
			(xy 7.273663 -510.088692) (xy 7.358009 -510.052149) (xy 7.445185 -510.022992) (xy 7.534544 -510.001438)
			(xy 7.625425 -509.987644) (xy 7.717156 -509.981714) (xy 7.809057 -509.983692) (xy 7.900448 -509.993563)
			(xy 7.990652 -510.011253) (xy 8.079001 -510.036633) (xy 8.164841 -510.069513) (xy 8.247537 -510.109651)
			(xy 8.326477 -510.15675) (xy 8.401075 -510.21046) (xy 8.470781 -510.270384) (xy 8.507692 -510.308098)
			(xy 79.51673 -510.308098) (xy 79.520801 -510.252476) (xy 79.532927 -510.198039) (xy 79.55285 -510.145948)
			(xy 79.580146 -510.097313) (xy 79.614232 -510.05317) (xy 79.654381 -510.014461) (xy 79.699739 -509.98201)
			(xy 79.749339 -509.956509) (xy 79.802123 -509.938502) (xy 79.856966 -509.928372) (xy 79.9127 -509.926335)
			(xy 79.968137 -509.932435) (xy 80.022094 -509.946541) (xy 80.073423 -509.968353) (xy 80.121029 -509.997407)
			(xy 80.163897 -510.033082) (xy 80.201114 -510.074619) (xy 80.231887 -510.121132) (xy 80.255559 -510.171629)
			(xy 80.271627 -510.225036) (xy 80.279747 -510.280212) (xy 80.280256 -510.308098) (xy 80.279747 -510.335984)
			(xy 80.271627 -510.39116) (xy 80.255559 -510.444567) (xy 80.231887 -510.495064) (xy 80.201114 -510.541577)
			(xy 80.163897 -510.583114) (xy 80.121029 -510.618789) (xy 80.073423 -510.647843) (xy 80.022094 -510.669655)
			(xy 79.968137 -510.683761) (xy 79.9127 -510.689861) (xy 79.856966 -510.687824) (xy 79.802123 -510.677694)
			(xy 79.749339 -510.659687) (xy 79.699739 -510.634186) (xy 79.654381 -510.601735) (xy 79.614232 -510.563026)
			(xy 79.580146 -510.518883) (xy 79.55285 -510.470248) (xy 79.532927 -510.418157) (xy 79.520801 -510.36372)
			(xy 79.51673 -510.308098) (xy 8.507692 -510.308098) (xy 8.535076 -510.336078) (xy 8.593487 -510.407056)
			(xy 8.645579 -510.482793) (xy 8.690968 -510.562728) (xy 8.729318 -510.646268) (xy 8.760343 -510.732796)
			(xy 8.783816 -510.821671) (xy 8.799562 -510.912235) (xy 8.807464 -511.003817) (xy 8.807958 -511.049778)
			(xy 8.807464 -511.095739) (xy 8.799562 -511.187321) (xy 8.783816 -511.277885) (xy 8.760343 -511.36676)
			(xy 8.729318 -511.453288) (xy 8.690968 -511.536828) (xy 8.645579 -511.616763) (xy 8.593487 -511.6925)
			(xy 8.535076 -511.763478) (xy 8.470781 -511.829172) (xy 8.401075 -511.889096) (xy 8.326477 -511.942806)
			(xy 8.247537 -511.989905) (xy 8.164841 -512.030043) (xy 8.079001 -512.062923) (xy 7.990652 -512.088303)
			(xy 7.900448 -512.105993) (xy 7.809057 -512.115864) (xy 7.717156 -512.117842) (xy 7.625425 -512.111912)
			(xy 7.534544 -512.098118) (xy 7.445185 -512.076564) (xy 7.358009 -512.047407) (xy 7.273663 -512.010864)
			(xy 7.19277 -511.967205) (xy 7.11593 -511.916754) (xy 7.043711 -511.859884) (xy 6.976649 -511.797017)
			(xy 6.915239 -511.728617) (xy 6.859936 -511.655192) (xy 6.81115 -511.577284) (xy 6.769242 -511.495471)
			(xy 6.734522 -511.410357) (xy 6.707248 -511.322575) (xy 6.687621 -511.232772) (xy 6.675786 -511.141615)
			(xy 6.671831 -511.049778) (xy 1.27 -511.049778) (xy 1.27 -514.092635) (xy 4.852911 -514.092635) (xy 4.852911 -514.006909)
			(xy 4.860821 -513.921549) (xy 4.876573 -513.837282) (xy 4.900033 -513.754829) (xy 4.931001 -513.674892)
			(xy 4.969212 -513.598153) (xy 5.014341 -513.525267) (xy 5.066002 -513.456856) (xy 5.123756 -513.393504)
			(xy 5.187108 -513.33575) (xy 5.255519 -513.284089) (xy 5.328405 -513.23896) (xy 5.405144 -513.200749)
			(xy 5.485081 -513.169781) (xy 5.567534 -513.146321) (xy 5.651801 -513.130569) (xy 5.737161 -513.122659)
			(xy 5.822887 -513.122659) (xy 5.908247 -513.130569) (xy 5.992514 -513.146321) (xy 6.074967 -513.169781)
			(xy 6.154904 -513.200749) (xy 6.231643 -513.23896) (xy 6.304529 -513.284089) (xy 6.37294 -513.33575)
			(xy 6.436292 -513.393504) (xy 6.494046 -513.456856) (xy 6.545707 -513.525267) (xy 6.590836 -513.598153)
			(xy 6.629047 -513.674892) (xy 6.660015 -513.754829) (xy 6.683475 -513.837282) (xy 6.699227 -513.921549)
			(xy 6.707137 -514.006909) (xy 6.707632 -514.049772) (xy 6.707137 -514.092635) (xy 6.699227 -514.177995)
			(xy 6.683475 -514.262262) (xy 6.660015 -514.344715) (xy 6.629047 -514.424652) (xy 6.590836 -514.501391)
			(xy 6.545707 -514.574277) (xy 6.494046 -514.642688) (xy 6.436292 -514.70604) (xy 6.37294 -514.763794)
			(xy 6.304529 -514.815455) (xy 6.231643 -514.860584) (xy 6.154904 -514.898795) (xy 6.074967 -514.929763)
			(xy 5.992514 -514.953223) (xy 5.908247 -514.968975) (xy 5.822887 -514.976885) (xy 5.737161 -514.976885)
			(xy 5.651801 -514.968975) (xy 5.567534 -514.953223) (xy 5.485081 -514.929763) (xy 5.405144 -514.898795)
			(xy 5.328405 -514.860584) (xy 5.255519 -514.815455) (xy 5.187108 -514.763794) (xy 5.123756 -514.70604)
			(xy 5.066002 -514.642688) (xy 5.014341 -514.574277) (xy 4.969212 -514.501391) (xy 4.931001 -514.424652)
			(xy 4.900033 -514.344715) (xy 4.876573 -514.262262) (xy 4.860821 -514.177995) (xy 4.852911 -514.092635)
			(xy 1.27 -514.092635) (xy 1.27 -517.092629) (xy 4.852911 -517.092629) (xy 4.852911 -517.006903) (xy 4.860821 -516.921543)
			(xy 4.876573 -516.837276) (xy 4.900033 -516.754823) (xy 4.931001 -516.674886) (xy 4.969212 -516.598147)
			(xy 5.014341 -516.525261) (xy 5.066002 -516.45685) (xy 5.123756 -516.393498) (xy 5.187108 -516.335744)
			(xy 5.255519 -516.284083) (xy 5.328405 -516.238954) (xy 5.405144 -516.200743) (xy 5.485081 -516.169775)
			(xy 5.567534 -516.146315) (xy 5.651801 -516.130563) (xy 5.737161 -516.122653) (xy 5.822887 -516.122653)
			(xy 5.908247 -516.130563) (xy 5.992514 -516.146315) (xy 6.074967 -516.169775) (xy 6.154904 -516.200743)
			(xy 6.231643 -516.238954) (xy 6.304529 -516.284083) (xy 6.37294 -516.335744) (xy 6.436292 -516.393498)
			(xy 6.494046 -516.45685) (xy 6.545707 -516.525261) (xy 6.590836 -516.598147) (xy 6.629047 -516.674886)
			(xy 6.660015 -516.754823) (xy 6.683475 -516.837276) (xy 6.699227 -516.921543) (xy 6.707137 -517.006903)
			(xy 6.707632 -517.049766) (xy 6.707137 -517.092629) (xy 6.699227 -517.177989) (xy 6.683475 -517.262256)
			(xy 6.660015 -517.344709) (xy 6.629047 -517.424646) (xy 6.590836 -517.501385) (xy 6.545707 -517.574271)
			(xy 6.494046 -517.642682) (xy 6.436292 -517.706034) (xy 6.37294 -517.763788) (xy 6.304529 -517.815449)
			(xy 6.231643 -517.860578) (xy 6.154904 -517.898789) (xy 6.074967 -517.929757) (xy 5.992514 -517.953217)
			(xy 5.908247 -517.968969) (xy 5.822887 -517.976879) (xy 5.737161 -517.976879) (xy 5.651801 -517.968969)
			(xy 5.567534 -517.953217) (xy 5.485081 -517.929757) (xy 5.405144 -517.898789) (xy 5.328405 -517.860578)
			(xy 5.255519 -517.815449) (xy 5.187108 -517.763788) (xy 5.123756 -517.706034) (xy 5.066002 -517.642682)
			(xy 5.014341 -517.574271) (xy 4.969212 -517.501385) (xy 4.931001 -517.424646) (xy 4.900033 -517.344709)
			(xy 4.876573 -517.262256) (xy 4.860821 -517.177989) (xy 4.852911 -517.092629) (xy 1.27 -517.092629)
			(xy 1.27 -520.04976) (xy 6.671831 -520.04976) (xy 6.675786 -519.957923) (xy 6.687621 -519.866766)
			(xy 6.707248 -519.776963) (xy 6.734522 -519.689181) (xy 6.769242 -519.604067) (xy 6.81115 -519.522254)
			(xy 6.859936 -519.444346) (xy 6.915239 -519.370921) (xy 6.976649 -519.302521) (xy 7.043711 -519.239654)
			(xy 7.11593 -519.182784) (xy 7.19277 -519.132333) (xy 7.273663 -519.088674) (xy 7.358009 -519.052131)
			(xy 7.445185 -519.022974) (xy 7.534544 -519.00142) (xy 7.625425 -518.987626) (xy 7.717156 -518.981696)
			(xy 7.809057 -518.983674) (xy 7.900448 -518.993545) (xy 7.990652 -519.011235) (xy 8.079001 -519.036615)
			(xy 8.142942 -519.061107) (xy 47.82311 -519.061107) (xy 47.82311 -518.979997) (xy 47.83106 -518.899278)
			(xy 47.846883 -518.819727) (xy 47.870428 -518.742111) (xy 47.901467 -518.667175) (xy 47.939702 -518.595643)
			(xy 47.984764 -518.528203) (xy 48.036219 -518.465504) (xy 48.093572 -518.408151) (xy 48.156271 -518.356696)
			(xy 48.223711 -518.311634) (xy 48.295243 -518.273399) (xy 48.370179 -518.24236) (xy 48.447795 -518.218815)
			(xy 48.527346 -518.202992) (xy 48.608065 -518.195042) (xy 48.689175 -518.195042) (xy 48.769894 -518.202992)
			(xy 48.849445 -518.218815) (xy 48.927061 -518.24236) (xy 49.001997 -518.273399) (xy 49.073529 -518.311634)
			(xy 49.140969 -518.356696) (xy 49.203668 -518.408151) (xy 49.261021 -518.465504) (xy 49.312476 -518.528203)
			(xy 49.357538 -518.595643) (xy 49.395773 -518.667175) (xy 49.426812 -518.742111) (xy 49.450357 -518.819727)
			(xy 49.46618 -518.899278) (xy 49.47413 -518.979997) (xy 49.474628 -519.020552) (xy 49.47413 -519.061107)
			(xy 51.32323 -519.061107) (xy 51.32323 -518.979997) (xy 51.33118 -518.899278) (xy 51.347003 -518.819727)
			(xy 51.370548 -518.742111) (xy 51.401587 -518.667175) (xy 51.439822 -518.595643) (xy 51.484884 -518.528203)
			(xy 51.536339 -518.465504) (xy 51.593692 -518.408151) (xy 51.656391 -518.356696) (xy 51.723831 -518.311634)
			(xy 51.795363 -518.273399) (xy 51.870299 -518.24236) (xy 51.947915 -518.218815) (xy 52.027466 -518.202992)
			(xy 52.108185 -518.195042) (xy 52.189295 -518.195042) (xy 52.270014 -518.202992) (xy 52.349565 -518.218815)
			(xy 52.427181 -518.24236) (xy 52.502117 -518.273399) (xy 52.573649 -518.311634) (xy 52.641089 -518.356696)
			(xy 52.703788 -518.408151) (xy 52.761141 -518.465504) (xy 52.812596 -518.528203) (xy 52.857658 -518.595643)
			(xy 52.895893 -518.667175) (xy 52.926932 -518.742111) (xy 52.950477 -518.819727) (xy 52.9663 -518.899278)
			(xy 52.97425 -518.979997) (xy 52.974748 -519.020552) (xy 52.974389 -519.049762) (xy 72.868035 -519.049762)
			(xy 72.872042 -518.847012) (xy 72.884055 -518.644578) (xy 72.904056 -518.442777) (xy 72.932015 -518.241923)
			(xy 72.967886 -518.042331) (xy 73.011615 -517.844312) (xy 73.063133 -517.648175) (xy 73.122359 -517.454227)
			(xy 73.189201 -517.262769) (xy 73.263555 -517.074102) (xy 73.345304 -516.88852) (xy 73.434322 -516.706312)
			(xy 73.530468 -516.527763) (xy 73.633593 -516.353152) (xy 73.743536 -516.182752) (xy 73.860125 -516.016828)
			(xy 73.983178 -515.855639) (xy 74.112503 -515.699438) (xy 74.247898 -515.548468) (xy 74.389151 -515.402964)
			(xy 74.536043 -515.263155) (xy 74.688343 -515.129258) (xy 74.845814 -515.001483) (xy 75.008211 -514.880028)
			(xy 75.175278 -514.765084) (xy 75.346757 -514.65683) (xy 75.522378 -514.555435) (xy 75.701868 -514.461057)
			(xy 75.884946 -514.373845) (xy 76.071327 -514.293933) (xy 76.26072 -514.221446) (xy 76.452828 -514.156499)
			(xy 76.647352 -514.099191) (xy 76.843988 -514.049614) (xy 77.04243 -514.007843) (xy 77.242367 -513.973945)
			(xy 77.443486 -513.947973) (xy 77.645475 -513.929966) (xy 77.848018 -513.919953) (xy 78.050798 -513.917949)
			(xy 78.253499 -513.923959) (xy 78.455804 -513.937971) (xy 78.657398 -513.959966) (xy 78.857965 -513.989907)
			(xy 79.057193 -514.027748) (xy 79.254771 -514.073431) (xy 79.450389 -514.126884) (xy 79.643743 -514.188023)
			(xy 79.834531 -514.256754) (xy 80.022454 -514.332968) (xy 80.20722 -514.416547) (xy 80.388539 -514.50736)
			(xy 80.56613 -514.605265) (xy 80.739713 -514.71011) (xy 80.909019 -514.821731) (xy 81.073784 -514.939953)
			(xy 81.233749 -515.064593) (xy 81.388665 -515.195454) (xy 81.53829 -515.332334) (xy 81.68239 -515.475018)
			(xy 81.820742 -515.623284) (xy 81.953127 -515.7769) (xy 82.079341 -515.935625) (xy 82.199185 -516.099214)
			(xy 82.312473 -516.267409) (xy 82.419028 -516.439948) (xy 82.518683 -516.616563) (xy 82.611283 -516.796976)
			(xy 82.696683 -516.980907) (xy 82.77475 -517.168068) (xy 82.845362 -517.358168) (xy 82.908408 -517.550908)
			(xy 82.963791 -517.745989) (xy 83.011423 -517.943106) (xy 83.051231 -518.14195) (xy 83.083153 -518.342212)
			(xy 83.107137 -518.543578) (xy 83.123148 -518.745735) (xy 83.131159 -518.948367) (xy 83.13166 -519.049762)
			(xy 83.131159 -519.151157) (xy 83.123148 -519.353789) (xy 83.107137 -519.555946) (xy 83.083153 -519.757312)
			(xy 83.051231 -519.957574) (xy 83.011423 -520.156418) (xy 82.963791 -520.353535) (xy 82.908408 -520.548616)
			(xy 82.845362 -520.741356) (xy 82.77475 -520.931456) (xy 82.696683 -521.118617) (xy 82.611283 -521.302548)
			(xy 82.518683 -521.482961) (xy 82.419028 -521.659576) (xy 82.312473 -521.832115) (xy 82.199185 -522.00031)
			(xy 82.079341 -522.163899) (xy 81.953127 -522.322624) (xy 81.820742 -522.47624) (xy 81.68239 -522.624506)
			(xy 81.53829 -522.76719) (xy 81.388665 -522.90407) (xy 81.233749 -523.034931) (xy 81.073784 -523.159571)
			(xy 80.909019 -523.277793) (xy 80.739713 -523.389414) (xy 80.56613 -523.494259) (xy 80.388539 -523.592164)
			(xy 80.20722 -523.682977) (xy 80.022454 -523.766556) (xy 79.834531 -523.84277) (xy 79.643743 -523.911501)
			(xy 79.450389 -523.97264) (xy 79.254771 -524.026093) (xy 79.057193 -524.071776) (xy 78.857965 -524.109617)
			(xy 78.657398 -524.139558) (xy 78.455804 -524.161553) (xy 78.253499 -524.175565) (xy 78.050798 -524.181575)
			(xy 77.848018 -524.179571) (xy 77.645475 -524.169558) (xy 77.443486 -524.151551) (xy 77.242367 -524.125579)
			(xy 77.04243 -524.091681) (xy 76.843988 -524.04991) (xy 76.647352 -524.000333) (xy 76.452828 -523.943025)
			(xy 76.26072 -523.878078) (xy 76.071327 -523.805591) (xy 75.884946 -523.725679) (xy 75.701868 -523.638467)
			(xy 75.522378 -523.544089) (xy 75.346757 -523.442694) (xy 75.175278 -523.33444) (xy 75.008211 -523.219496)
			(xy 74.845814 -523.098041) (xy 74.688343 -522.970266) (xy 74.536043 -522.836369) (xy 74.389151 -522.69656)
			(xy 74.247898 -522.551056) (xy 74.112503 -522.400086) (xy 73.983178 -522.243885) (xy 73.860125 -522.082696)
			(xy 73.743536 -521.916772) (xy 73.633593 -521.746372) (xy 73.530468 -521.571761) (xy 73.434322 -521.393212)
			(xy 73.345304 -521.211004) (xy 73.263555 -521.025422) (xy 73.189201 -520.836755) (xy 73.122359 -520.645297)
			(xy 73.063133 -520.451349) (xy 73.011615 -520.255212) (xy 72.967886 -520.057193) (xy 72.932015 -519.857601)
			(xy 72.904056 -519.656747) (xy 72.884055 -519.454946) (xy 72.872042 -519.252512) (xy 72.868035 -519.049762)
			(xy 52.974389 -519.049762) (xy 52.97425 -519.061107) (xy 52.9663 -519.141826) (xy 52.950477 -519.221377)
			(xy 52.926932 -519.298993) (xy 52.895893 -519.373929) (xy 52.857658 -519.445461) (xy 52.812596 -519.512901)
			(xy 52.761141 -519.5756) (xy 52.703788 -519.632953) (xy 52.641089 -519.684408) (xy 52.573649 -519.72947)
			(xy 52.502117 -519.767705) (xy 52.427181 -519.798744) (xy 52.349565 -519.822289) (xy 52.270014 -519.838112)
			(xy 52.189295 -519.846062) (xy 52.108185 -519.846062) (xy 52.027466 -519.838112) (xy 51.947915 -519.822289)
			(xy 51.870299 -519.798744) (xy 51.795363 -519.767705) (xy 51.723831 -519.72947) (xy 51.656391 -519.684408)
			(xy 51.593692 -519.632953) (xy 51.536339 -519.5756) (xy 51.484884 -519.512901) (xy 51.439822 -519.445461)
			(xy 51.401587 -519.373929) (xy 51.370548 -519.298993) (xy 51.347003 -519.221377) (xy 51.33118 -519.141826)
			(xy 51.32323 -519.061107) (xy 49.47413 -519.061107) (xy 49.46618 -519.141826) (xy 49.450357 -519.221377)
			(xy 49.426812 -519.298993) (xy 49.395773 -519.373929) (xy 49.357538 -519.445461) (xy 49.312476 -519.512901)
			(xy 49.261021 -519.5756) (xy 49.203668 -519.632953) (xy 49.140969 -519.684408) (xy 49.073529 -519.72947)
			(xy 49.001997 -519.767705) (xy 48.927061 -519.798744) (xy 48.849445 -519.822289) (xy 48.769894 -519.838112)
			(xy 48.689175 -519.846062) (xy 48.608065 -519.846062) (xy 48.527346 -519.838112) (xy 48.447795 -519.822289)
			(xy 48.370179 -519.798744) (xy 48.295243 -519.767705) (xy 48.223711 -519.72947) (xy 48.156271 -519.684408)
			(xy 48.093572 -519.632953) (xy 48.036219 -519.5756) (xy 47.984764 -519.512901) (xy 47.939702 -519.445461)
			(xy 47.901467 -519.373929) (xy 47.870428 -519.298993) (xy 47.846883 -519.221377) (xy 47.83106 -519.141826)
			(xy 47.82311 -519.061107) (xy 8.142942 -519.061107) (xy 8.164841 -519.069495) (xy 8.247537 -519.109633)
			(xy 8.326477 -519.156732) (xy 8.401075 -519.210442) (xy 8.470781 -519.270366) (xy 8.535076 -519.33606)
			(xy 8.593487 -519.407038) (xy 8.645579 -519.482775) (xy 8.690968 -519.56271) (xy 8.729318 -519.64625)
			(xy 8.760343 -519.732778) (xy 8.783816 -519.821653) (xy 8.799562 -519.912217) (xy 8.807464 -520.003799)
			(xy 8.807958 -520.04976) (xy 8.807464 -520.095721) (xy 8.799562 -520.187303) (xy 8.783816 -520.277867)
			(xy 8.760343 -520.366742) (xy 8.729318 -520.45327) (xy 8.690968 -520.53681) (xy 8.645579 -520.616745)
			(xy 8.593487 -520.692482) (xy 8.535076 -520.76346) (xy 8.470781 -520.829154) (xy 8.401075 -520.889078)
			(xy 8.326477 -520.942788) (xy 8.247537 -520.989887) (xy 8.164841 -521.030025) (xy 8.079001 -521.062905)
			(xy 7.990652 -521.088285) (xy 7.900448 -521.105975) (xy 7.809057 -521.115846) (xy 7.717156 -521.117824)
			(xy 7.625425 -521.111894) (xy 7.534544 -521.0981) (xy 7.445185 -521.076546) (xy 7.358009 -521.047389)
			(xy 7.273663 -521.010846) (xy 7.19277 -520.967187) (xy 7.11593 -520.916736) (xy 7.043711 -520.859866)
			(xy 6.976649 -520.796999) (xy 6.915239 -520.728599) (xy 6.859936 -520.655174) (xy 6.81115 -520.577266)
			(xy 6.769242 -520.495453) (xy 6.734522 -520.410339) (xy 6.707248 -520.322557) (xy 6.687621 -520.232754)
			(xy 6.675786 -520.141597) (xy 6.671831 -520.04976) (xy 1.27 -520.04976) (xy 1.27 -524.500094) (xy 1.270418 -524.520529)
			(xy 1.277593 -524.560764) (xy 1.291771 -524.599096) (xy 1.30175 -524.616934) (xy 1.30664 -524.625069)
			(xy 1.317574 -524.640584) (xy 1.323594 -524.647922) (xy 1.332484 -524.658082) (xy 1.33477 -524.660368)
			(xy 1.33604 -524.661892) (xy 1.353107 -524.678343) (xy 1.392594 -524.704554) (xy 1.436603 -524.722146)
			(xy 1.483278 -524.730376) (xy 1.506982 -524.730218) (xy 1.51511 -524.729964) (xy 23.50008 -524.729964)
			(xy 23.573919 -524.730454) (xy 23.721386 -524.738334) (xy 23.868223 -524.754063) (xy 24.014014 -524.777595)
			(xy 24.158343 -524.808865) (xy 24.3008 -524.847782) (xy 24.440981 -524.894237) (xy 24.578486 -524.948096)
			(xy 24.712926 -525.009208) (xy 24.843917 -525.077399) (xy 24.907748 -525.11452) (xy 24.950627 -525.140106)
			(xy 25.034722 -525.193968) (xy 25.075896 -525.222216) (xy 25.07615 -525.222216) (xy 25.077928 -525.22374)
			(xy 25.145573 -525.271385) (xy 25.275694 -525.373612) (xy 25.399481 -525.483425) (xy 25.45842 -525.541494)
			(xy 25.490151 -525.573501) (xy 25.551759 -525.639299) (xy 25.58161 -525.673066) (xy 25.586436 -525.6784)
			(xy 25.606245 -525.701205) (xy 25.644984 -525.747564) (xy 25.663906 -525.77111) (xy 25.722834 -525.847564)
			(xy 25.766299 -525.906856) (xy 25.847621 -526.029349) (xy 25.885394 -526.09242) (xy 25.922502 -526.156255)
			(xy 25.990667 -526.287252) (xy 26.051754 -526.421695) (xy 26.105588 -526.559203) (xy 26.152017 -526.699385)
			(xy 26.190908 -526.841842) (xy 26.222152 -526.98617) (xy 26.245659 -527.131958) (xy 26.261362 -527.278791)
			(xy 26.269217 -527.426253) (xy 26.269696 -527.500088) (xy 26.269696 -528.500086) (xy 26.270243 -528.52202)
			(xy 26.278593 -528.565086) (xy 26.294935 -528.605797) (xy 26.318682 -528.642682) (xy 26.348976 -528.674412)
			(xy 26.384723 -528.69984) (xy 26.424634 -528.718049) (xy 26.467268 -528.728382) (xy 26.489152 -528.729956)
		)
		(stroke
			(width 0)
			(type solid)
		)
		(fill yes)
		(layer "In2.Cu")
		(net "P12V")
	)
	(gr_line
		(start 0 -524.500094)
		(end 0 -5.500116)
		(stroke
			(width 2.032)
			(type default)
		)
		(layer "In3.Cu")
	)
	(gr_arc
		(start 0 -524.500094)
		(mid 0.439393 -525.560749)
		(end 1.500124 -525.999964)
		(stroke
			(width 2.032)
			(type default)
		)
		(layer "In3.Cu")
	)
	(gr_poly
		(pts
			(xy 27.598878 -528.983956) (xy 27.614329 -528.983524) (xy 27.644326 -528.976099) (xy 27.671657 -528.961677)
			(xy 27.68346 -528.951698) (xy 27.704555 -528.933522) (xy 27.751023 -528.902846) (xy 27.801456 -528.87925)
			(xy 27.854784 -528.863235) (xy 27.909874 -528.855141) (xy 27.965554 -528.855141) (xy 28.020644 -528.863235)
			(xy 28.073972 -528.87925) (xy 28.124405 -528.902846) (xy 28.170873 -528.933522) (xy 28.191968 -528.951698)
			(xy 28.203783 -528.961661) (xy 28.231108 -528.976085) (xy 28.261101 -528.983509) (xy 28.27655 -528.983956)
			(xy 40.298878 -528.983956) (xy 40.314329 -528.983524) (xy 40.344326 -528.976099) (xy 40.371657 -528.961677)
			(xy 40.38346 -528.951698) (xy 40.404555 -528.933522) (xy 40.451023 -528.902846) (xy 40.501456 -528.87925)
			(xy 40.554784 -528.863235) (xy 40.609874 -528.855141) (xy 40.665554 -528.855141) (xy 40.720644 -528.863235)
			(xy 40.773972 -528.87925) (xy 40.824405 -528.902846) (xy 40.870873 -528.933522) (xy 40.891968 -528.951698)
			(xy 40.903783 -528.961661) (xy 40.931108 -528.976085) (xy 40.961101 -528.983509) (xy 40.97655 -528.983956)
			(xy 52.998878 -528.983956) (xy 53.014329 -528.983524) (xy 53.044326 -528.976099) (xy 53.071657 -528.961677)
			(xy 53.08346 -528.951698) (xy 53.104555 -528.933522) (xy 53.151023 -528.902846) (xy 53.201456 -528.87925)
			(xy 53.254784 -528.863235) (xy 53.309874 -528.855141) (xy 53.365554 -528.855141) (xy 53.420644 -528.863235)
			(xy 53.473972 -528.87925) (xy 53.524405 -528.902846) (xy 53.570873 -528.933522) (xy 53.591968 -528.951698)
			(xy 53.603783 -528.961661) (xy 53.631108 -528.976085) (xy 53.661101 -528.983509) (xy 53.67655 -528.983956)
			(xy 65.698878 -528.983956) (xy 65.714329 -528.983524) (xy 65.744326 -528.976099) (xy 65.771657 -528.961677)
			(xy 65.78346 -528.951698) (xy 65.804555 -528.933522) (xy 65.851023 -528.902846) (xy 65.901456 -528.87925)
			(xy 65.954784 -528.863235) (xy 66.009874 -528.855141) (xy 66.065554 -528.855141) (xy 66.120644 -528.863235)
			(xy 66.173972 -528.87925) (xy 66.224405 -528.902846) (xy 66.270873 -528.933522) (xy 66.291968 -528.951698)
			(xy 66.303783 -528.961661) (xy 66.331108 -528.976085) (xy 66.361101 -528.983509) (xy 66.37655 -528.983956)
			(xy 78.398878 -528.983956) (xy 78.414329 -528.983524) (xy 78.444326 -528.976099) (xy 78.471657 -528.961677)
			(xy 78.48346 -528.951698) (xy 78.504555 -528.933522) (xy 78.551023 -528.902846) (xy 78.601456 -528.87925)
			(xy 78.654784 -528.863235) (xy 78.709874 -528.855141) (xy 78.765554 -528.855141) (xy 78.820644 -528.863235)
			(xy 78.873972 -528.87925) (xy 78.924405 -528.902846) (xy 78.970873 -528.933522) (xy 78.991968 -528.951698)
			(xy 79.003783 -528.961661) (xy 79.031108 -528.976085) (xy 79.061101 -528.983509) (xy 79.07655 -528.983956)
			(xy 91.098878 -528.983956) (xy 91.114329 -528.983524) (xy 91.144326 -528.976099) (xy 91.171657 -528.961677)
			(xy 91.18346 -528.951698) (xy 91.204555 -528.933522) (xy 91.251023 -528.902846) (xy 91.301456 -528.87925)
			(xy 91.354784 -528.863235) (xy 91.409874 -528.855141) (xy 91.465554 -528.855141) (xy 91.520644 -528.863235)
			(xy 91.573972 -528.87925) (xy 91.624405 -528.902846) (xy 91.670873 -528.933522) (xy 91.691968 -528.951698)
			(xy 91.703783 -528.961661) (xy 91.731108 -528.976085) (xy 91.761101 -528.983509) (xy 91.77655 -528.983956)
			(xy 101.000052 -528.983956) (xy 101.045522 -528.983449) (xy 101.136075 -528.975062) (xy 101.225467 -528.958355)
			(xy 101.312937 -528.933471) (xy 101.397737 -528.900622) (xy 101.479144 -528.860089) (xy 101.556464 -528.812216)
			(xy 101.629036 -528.757413) (xy 101.696242 -528.696148) (xy 101.757508 -528.628942) (xy 101.812312 -528.55637)
			(xy 101.860185 -528.479051) (xy 101.900719 -528.397644) (xy 101.933569 -528.312844) (xy 101.958454 -528.225375)
			(xy 101.975161 -528.135983) (xy 101.983549 -528.04543) (xy 101.984048 -527.99996) (xy 101.984048 -525.382236)
			(xy 101.983586 -525.366909) (xy 101.976272 -525.337141) (xy 101.962081 -525.30997) (xy 101.952298 -525.298162)
			(xy 101.934352 -525.277135) (xy 101.904082 -525.230879) (xy 101.880807 -525.180739) (xy 101.865012 -525.127764)
			(xy 101.85703 -525.073064) (xy 101.857026 -525.017784) (xy 101.865002 -524.963083) (xy 101.88079 -524.910106)
			(xy 101.904059 -524.859963) (xy 101.934322 -524.813703) (xy 101.952298 -524.792702) (xy 101.962138 -524.780931)
			(xy 101.976362 -524.753756) (xy 101.983666 -524.723965) (xy 101.984048 -524.708628) (xy 101.984048 -512.682236)
			(xy 101.983586 -512.666909) (xy 101.976272 -512.637141) (xy 101.962081 -512.60997) (xy 101.952298 -512.598162)
			(xy 101.934352 -512.577135) (xy 101.904082 -512.530879) (xy 101.880807 -512.480739) (xy 101.865012 -512.427764)
			(xy 101.85703 -512.373064) (xy 101.857026 -512.317784) (xy 101.865002 -512.263083) (xy 101.88079 -512.210106)
			(xy 101.904059 -512.159963) (xy 101.934322 -512.113703) (xy 101.952298 -512.092702) (xy 101.962138 -512.080931)
			(xy 101.976362 -512.053756) (xy 101.983666 -512.023965) (xy 101.984048 -512.008628) (xy 101.984048 -499.982236)
			(xy 101.983586 -499.966909) (xy 101.976272 -499.937141) (xy 101.962081 -499.90997) (xy 101.952298 -499.898162)
			(xy 101.934352 -499.877135) (xy 101.904082 -499.830879) (xy 101.880807 -499.780739) (xy 101.865012 -499.727764)
			(xy 101.85703 -499.673064) (xy 101.857026 -499.617784) (xy 101.865002 -499.563083) (xy 101.88079 -499.510106)
			(xy 101.904059 -499.459963) (xy 101.934322 -499.413703) (xy 101.952298 -499.392702) (xy 101.962138 -499.380931)
			(xy 101.976362 -499.353756) (xy 101.983666 -499.323965) (xy 101.984048 -499.308628) (xy 101.984048 -487.282236)
			(xy 101.983586 -487.266909) (xy 101.976272 -487.237141) (xy 101.962081 -487.20997) (xy 101.952298 -487.198162)
			(xy 101.934352 -487.177135) (xy 101.904082 -487.130879) (xy 101.880807 -487.080739) (xy 101.865012 -487.027764)
			(xy 101.85703 -486.973064) (xy 101.857026 -486.917784) (xy 101.865002 -486.863083) (xy 101.88079 -486.810106)
			(xy 101.904059 -486.759963) (xy 101.934322 -486.713703) (xy 101.952298 -486.692702) (xy 101.962138 -486.680931)
			(xy 101.976362 -486.653756) (xy 101.983666 -486.623965) (xy 101.984048 -486.608628) (xy 101.984048 -474.582236)
			(xy 101.983586 -474.566909) (xy 101.976272 -474.537141) (xy 101.962081 -474.50997) (xy 101.952298 -474.498162)
			(xy 101.934352 -474.477135) (xy 101.904082 -474.430879) (xy 101.880807 -474.380739) (xy 101.865012 -474.327764)
			(xy 101.85703 -474.273064) (xy 101.857026 -474.217784) (xy 101.865002 -474.163083) (xy 101.88079 -474.110106)
			(xy 101.904059 -474.059963) (xy 101.934322 -474.013703) (xy 101.952298 -473.992702) (xy 101.962138 -473.980931)
			(xy 101.976362 -473.953756) (xy 101.983666 -473.923965) (xy 101.984048 -473.908628) (xy 101.984048 -461.882236)
			(xy 101.983586 -461.866909) (xy 101.976272 -461.837141) (xy 101.962081 -461.80997) (xy 101.952298 -461.798162)
			(xy 101.934352 -461.777135) (xy 101.904082 -461.730879) (xy 101.880807 -461.680739) (xy 101.865012 -461.627764)
			(xy 101.85703 -461.573064) (xy 101.857026 -461.517784) (xy 101.865002 -461.463083) (xy 101.88079 -461.410106)
			(xy 101.904059 -461.359963) (xy 101.934322 -461.313703) (xy 101.952298 -461.292702) (xy 101.962138 -461.280931)
			(xy 101.976362 -461.253756) (xy 101.983666 -461.223965) (xy 101.984048 -461.208628) (xy 101.984048 -449.182236)
			(xy 101.983586 -449.166909) (xy 101.976272 -449.137141) (xy 101.962081 -449.10997) (xy 101.952298 -449.098162)
			(xy 101.934352 -449.077135) (xy 101.904082 -449.030879) (xy 101.880807 -448.980739) (xy 101.865012 -448.927764)
			(xy 101.85703 -448.873064) (xy 101.857026 -448.817784) (xy 101.865002 -448.763083) (xy 101.88079 -448.710106)
			(xy 101.904059 -448.659963) (xy 101.934322 -448.613703) (xy 101.952298 -448.592702) (xy 101.962138 -448.580931)
			(xy 101.976362 -448.553756) (xy 101.983666 -448.523965) (xy 101.984048 -448.508628) (xy 101.984048 -436.482236)
			(xy 101.983586 -436.466909) (xy 101.976272 -436.437141) (xy 101.962081 -436.40997) (xy 101.952298 -436.398162)
			(xy 101.934352 -436.377135) (xy 101.904082 -436.330879) (xy 101.880807 -436.280739) (xy 101.865012 -436.227764)
			(xy 101.85703 -436.173064) (xy 101.857026 -436.117784) (xy 101.865002 -436.063083) (xy 101.88079 -436.010106)
			(xy 101.904059 -435.959963) (xy 101.934322 -435.913703) (xy 101.952298 -435.892702) (xy 101.962138 -435.880931)
			(xy 101.976362 -435.853756) (xy 101.983666 -435.823965) (xy 101.984048 -435.808628) (xy 101.984048 -423.782236)
			(xy 101.983586 -423.766909) (xy 101.976272 -423.737141) (xy 101.962081 -423.70997) (xy 101.952298 -423.698162)
			(xy 101.934352 -423.677135) (xy 101.904082 -423.630879) (xy 101.880807 -423.580739) (xy 101.865012 -423.527764)
			(xy 101.85703 -423.473064) (xy 101.857026 -423.417784) (xy 101.865002 -423.363083) (xy 101.88079 -423.310106)
			(xy 101.904059 -423.259963) (xy 101.934322 -423.213703) (xy 101.952298 -423.192702) (xy 101.962138 -423.180931)
			(xy 101.976362 -423.153756) (xy 101.983666 -423.123965) (xy 101.984048 -423.108628) (xy 101.984048 -411.082236)
			(xy 101.983586 -411.066909) (xy 101.976272 -411.037141) (xy 101.962081 -411.00997) (xy 101.952298 -410.998162)
			(xy 101.934352 -410.977135) (xy 101.904082 -410.930879) (xy 101.880807 -410.880739) (xy 101.865012 -410.827764)
			(xy 101.85703 -410.773064) (xy 101.857026 -410.717784) (xy 101.865002 -410.663083) (xy 101.88079 -410.610106)
			(xy 101.904059 -410.559963) (xy 101.934322 -410.513703) (xy 101.952298 -410.492702) (xy 101.962138 -410.480931)
			(xy 101.976362 -410.453756) (xy 101.983666 -410.423965) (xy 101.984048 -410.408628) (xy 101.984048 -398.382236)
			(xy 101.983586 -398.366909) (xy 101.976272 -398.337141) (xy 101.962081 -398.30997) (xy 101.952298 -398.298162)
			(xy 101.934352 -398.277135) (xy 101.904082 -398.230879) (xy 101.880807 -398.180739) (xy 101.865012 -398.127764)
			(xy 101.85703 -398.073064) (xy 101.857026 -398.017784) (xy 101.865002 -397.963083) (xy 101.88079 -397.910106)
			(xy 101.904059 -397.859963) (xy 101.934322 -397.813703) (xy 101.952298 -397.792702) (xy 101.962138 -397.780931)
			(xy 101.976362 -397.753756) (xy 101.983666 -397.723965) (xy 101.984048 -397.708628) (xy 101.984048 -385.682236)
			(xy 101.983586 -385.666909) (xy 101.976272 -385.637141) (xy 101.962081 -385.60997) (xy 101.952298 -385.598162)
			(xy 101.934352 -385.577135) (xy 101.904082 -385.530879) (xy 101.880807 -385.480739) (xy 101.865012 -385.427764)
			(xy 101.85703 -385.373064) (xy 101.857026 -385.317784) (xy 101.865002 -385.263083) (xy 101.88079 -385.210106)
			(xy 101.904059 -385.159963) (xy 101.934322 -385.113703) (xy 101.952298 -385.092702) (xy 101.962138 -385.080931)
			(xy 101.976362 -385.053756) (xy 101.983666 -385.023965) (xy 101.984048 -385.008628) (xy 101.984048 -372.982236)
			(xy 101.983586 -372.966909) (xy 101.976272 -372.937141) (xy 101.962081 -372.90997) (xy 101.952298 -372.898162)
			(xy 101.934352 -372.877135) (xy 101.904082 -372.830879) (xy 101.880807 -372.780739) (xy 101.865012 -372.727764)
			(xy 101.85703 -372.673064) (xy 101.857026 -372.617784) (xy 101.865002 -372.563083) (xy 101.88079 -372.510106)
			(xy 101.904059 -372.459963) (xy 101.934322 -372.413703) (xy 101.952298 -372.392702) (xy 101.962138 -372.380931)
			(xy 101.976362 -372.353756) (xy 101.983666 -372.323965) (xy 101.984048 -372.308628) (xy 101.984048 -360.282236)
			(xy 101.983586 -360.266909) (xy 101.976272 -360.237141) (xy 101.962081 -360.20997) (xy 101.952298 -360.198162)
			(xy 101.934352 -360.177135) (xy 101.904082 -360.130879) (xy 101.880807 -360.080739) (xy 101.865012 -360.027764)
			(xy 101.85703 -359.973064) (xy 101.857026 -359.917784) (xy 101.865002 -359.863083) (xy 101.88079 -359.810106)
			(xy 101.904059 -359.759963) (xy 101.934322 -359.713703) (xy 101.952298 -359.692702) (xy 101.962138 -359.680931)
			(xy 101.976362 -359.653756) (xy 101.983666 -359.623965) (xy 101.984048 -359.608628) (xy 101.984048 -347.582236)
			(xy 101.983586 -347.566909) (xy 101.976272 -347.537141) (xy 101.962081 -347.50997) (xy 101.952298 -347.498162)
			(xy 101.934352 -347.477135) (xy 101.904082 -347.430879) (xy 101.880807 -347.380739) (xy 101.865012 -347.327764)
			(xy 101.85703 -347.273064) (xy 101.857026 -347.217784) (xy 101.865002 -347.163083) (xy 101.88079 -347.110106)
			(xy 101.904059 -347.059963) (xy 101.934322 -347.013703) (xy 101.952298 -346.992702) (xy 101.962138 -346.980931)
			(xy 101.976362 -346.953756) (xy 101.983666 -346.923965) (xy 101.984048 -346.908628) (xy 101.984048 -334.882236)
			(xy 101.983586 -334.866909) (xy 101.976272 -334.837141) (xy 101.962081 -334.80997) (xy 101.952298 -334.798162)
			(xy 101.934352 -334.777135) (xy 101.904082 -334.730879) (xy 101.880807 -334.680739) (xy 101.865012 -334.627764)
			(xy 101.85703 -334.573064) (xy 101.857026 -334.517784) (xy 101.865002 -334.463083) (xy 101.88079 -334.410106)
			(xy 101.904059 -334.359963) (xy 101.934322 -334.313703) (xy 101.952298 -334.292702) (xy 101.962138 -334.280931)
			(xy 101.976362 -334.253756) (xy 101.983666 -334.223965) (xy 101.984048 -334.208628) (xy 101.984048 -322.182236)
			(xy 101.983586 -322.166909) (xy 101.976272 -322.137141) (xy 101.962081 -322.10997) (xy 101.952298 -322.098162)
			(xy 101.934352 -322.077135) (xy 101.904082 -322.030879) (xy 101.880807 -321.980739) (xy 101.865012 -321.927764)
			(xy 101.85703 -321.873064) (xy 101.857026 -321.817784) (xy 101.865002 -321.763083) (xy 101.88079 -321.710106)
			(xy 101.904059 -321.659963) (xy 101.934322 -321.613703) (xy 101.952298 -321.592702) (xy 101.962138 -321.580931)
			(xy 101.976362 -321.553756) (xy 101.983666 -321.523965) (xy 101.984048 -321.508628) (xy 101.984048 -309.482236)
			(xy 101.983586 -309.466909) (xy 101.976272 -309.437141) (xy 101.962081 -309.40997) (xy 101.952298 -309.398162)
			(xy 101.934352 -309.377135) (xy 101.904082 -309.330879) (xy 101.880807 -309.280739) (xy 101.865012 -309.227764)
			(xy 101.85703 -309.173064) (xy 101.857026 -309.117784) (xy 101.865002 -309.063083) (xy 101.88079 -309.010106)
			(xy 101.904059 -308.959963) (xy 101.934322 -308.913703) (xy 101.952298 -308.892702) (xy 101.962138 -308.880931)
			(xy 101.976362 -308.853756) (xy 101.983666 -308.823965) (xy 101.984048 -308.808628) (xy 101.984048 -296.782236)
			(xy 101.983586 -296.766909) (xy 101.976272 -296.737141) (xy 101.962081 -296.70997) (xy 101.952298 -296.698162)
			(xy 101.934352 -296.677135) (xy 101.904082 -296.630879) (xy 101.880807 -296.580739) (xy 101.865012 -296.527764)
			(xy 101.85703 -296.473064) (xy 101.857026 -296.417784) (xy 101.865002 -296.363083) (xy 101.88079 -296.310106)
			(xy 101.904059 -296.259963) (xy 101.934322 -296.213703) (xy 101.952298 -296.192702) (xy 101.962138 -296.180931)
			(xy 101.976362 -296.153756) (xy 101.983666 -296.123965) (xy 101.984048 -296.108628) (xy 101.984048 -284.082236)
			(xy 101.983586 -284.066909) (xy 101.976272 -284.037141) (xy 101.962081 -284.00997) (xy 101.952298 -283.998162)
			(xy 101.934352 -283.977135) (xy 101.904082 -283.930879) (xy 101.880807 -283.880739) (xy 101.865012 -283.827764)
			(xy 101.85703 -283.773064) (xy 101.857026 -283.717784) (xy 101.865002 -283.663083) (xy 101.88079 -283.610106)
			(xy 101.904059 -283.559963) (xy 101.934322 -283.513703) (xy 101.952298 -283.492702) (xy 101.962138 -283.480931)
			(xy 101.976362 -283.453756) (xy 101.983666 -283.423965) (xy 101.984048 -283.408628) (xy 101.984048 -271.382236)
			(xy 101.983586 -271.366909) (xy 101.976272 -271.337141) (xy 101.962081 -271.30997) (xy 101.952298 -271.298162)
			(xy 101.934352 -271.277135) (xy 101.904082 -271.230879) (xy 101.880807 -271.180739) (xy 101.865012 -271.127764)
			(xy 101.85703 -271.073064) (xy 101.857026 -271.017784) (xy 101.865002 -270.963083) (xy 101.88079 -270.910106)
			(xy 101.904059 -270.859963) (xy 101.934322 -270.813703) (xy 101.952298 -270.792702) (xy 101.962138 -270.780931)
			(xy 101.976362 -270.753756) (xy 101.983666 -270.723965) (xy 101.984048 -270.708628) (xy 101.984048 -258.682236)
			(xy 101.983586 -258.666909) (xy 101.976272 -258.637141) (xy 101.962081 -258.60997) (xy 101.952298 -258.598162)
			(xy 101.934352 -258.577135) (xy 101.904082 -258.530879) (xy 101.880807 -258.480739) (xy 101.865012 -258.427764)
			(xy 101.85703 -258.373064) (xy 101.857026 -258.317784) (xy 101.865002 -258.263083) (xy 101.88079 -258.210106)
			(xy 101.904059 -258.159963) (xy 101.934322 -258.113703) (xy 101.952298 -258.092702) (xy 101.962138 -258.080931)
			(xy 101.976362 -258.053756) (xy 101.983666 -258.023965) (xy 101.984048 -258.008628) (xy 101.984048 -245.982236)
			(xy 101.983586 -245.966909) (xy 101.976272 -245.937141) (xy 101.962081 -245.90997) (xy 101.952298 -245.898162)
			(xy 101.934352 -245.877135) (xy 101.904082 -245.830879) (xy 101.880807 -245.780739) (xy 101.865012 -245.727764)
			(xy 101.85703 -245.673064) (xy 101.857026 -245.617784) (xy 101.865002 -245.563083) (xy 101.88079 -245.510106)
			(xy 101.904059 -245.459963) (xy 101.934322 -245.413703) (xy 101.952298 -245.392702) (xy 101.962138 -245.380931)
			(xy 101.976362 -245.353756) (xy 101.983666 -245.323965) (xy 101.984048 -245.308628) (xy 101.984048 -233.282236)
			(xy 101.983586 -233.266909) (xy 101.976272 -233.237141) (xy 101.962081 -233.20997) (xy 101.952298 -233.198162)
			(xy 101.934352 -233.177135) (xy 101.904082 -233.130879) (xy 101.880807 -233.080739) (xy 101.865012 -233.027764)
			(xy 101.85703 -232.973064) (xy 101.857026 -232.917784) (xy 101.865002 -232.863083) (xy 101.88079 -232.810106)
			(xy 101.904059 -232.759963) (xy 101.934322 -232.713703) (xy 101.952298 -232.692702) (xy 101.962138 -232.680931)
			(xy 101.976362 -232.653756) (xy 101.983666 -232.623965) (xy 101.984048 -232.608628) (xy 101.984048 -220.582236)
			(xy 101.983586 -220.566909) (xy 101.976272 -220.537141) (xy 101.962081 -220.50997) (xy 101.952298 -220.498162)
			(xy 101.934352 -220.477135) (xy 101.904082 -220.430879) (xy 101.880807 -220.380739) (xy 101.865012 -220.327764)
			(xy 101.85703 -220.273064) (xy 101.857026 -220.217784) (xy 101.865002 -220.163083) (xy 101.88079 -220.110106)
			(xy 101.904059 -220.059963) (xy 101.934322 -220.013703) (xy 101.952298 -219.992702) (xy 101.962138 -219.980931)
			(xy 101.976362 -219.953756) (xy 101.983666 -219.923965) (xy 101.984048 -219.908628) (xy 101.984048 -207.882236)
			(xy 101.983586 -207.866909) (xy 101.976272 -207.837141) (xy 101.962081 -207.80997) (xy 101.952298 -207.798162)
			(xy 101.934352 -207.777135) (xy 101.904082 -207.730879) (xy 101.880807 -207.680739) (xy 101.865012 -207.627764)
			(xy 101.85703 -207.573064) (xy 101.857026 -207.517784) (xy 101.865002 -207.463083) (xy 101.88079 -207.410106)
			(xy 101.904059 -207.359963) (xy 101.934322 -207.313703) (xy 101.952298 -207.292702) (xy 101.962138 -207.280931)
			(xy 101.976362 -207.253756) (xy 101.983666 -207.223965) (xy 101.984048 -207.208628) (xy 101.984048 -195.182236)
			(xy 101.983586 -195.166909) (xy 101.976272 -195.137141) (xy 101.962081 -195.10997) (xy 101.952298 -195.098162)
			(xy 101.934352 -195.077135) (xy 101.904082 -195.030879) (xy 101.880807 -194.980739) (xy 101.865012 -194.927764)
			(xy 101.85703 -194.873064) (xy 101.857026 -194.817784) (xy 101.865002 -194.763083) (xy 101.88079 -194.710106)
			(xy 101.904059 -194.659963) (xy 101.934322 -194.613703) (xy 101.952298 -194.592702) (xy 101.962138 -194.580931)
			(xy 101.976362 -194.553756) (xy 101.983666 -194.523965) (xy 101.984048 -194.508628) (xy 101.984048 -182.482236)
			(xy 101.983586 -182.466909) (xy 101.976272 -182.437141) (xy 101.962081 -182.40997) (xy 101.952298 -182.398162)
			(xy 101.934352 -182.377135) (xy 101.904082 -182.330879) (xy 101.880807 -182.280739) (xy 101.865012 -182.227764)
			(xy 101.85703 -182.173064) (xy 101.857026 -182.117784) (xy 101.865002 -182.063083) (xy 101.88079 -182.010106)
			(xy 101.904059 -181.959963) (xy 101.934322 -181.913703) (xy 101.952298 -181.892702) (xy 101.962138 -181.880931)
			(xy 101.976362 -181.853756) (xy 101.983666 -181.823965) (xy 101.984048 -181.808628) (xy 101.984048 -169.782236)
			(xy 101.983586 -169.766909) (xy 101.976272 -169.737141) (xy 101.962081 -169.70997) (xy 101.952298 -169.698162)
			(xy 101.934352 -169.677135) (xy 101.904082 -169.630879) (xy 101.880807 -169.580739) (xy 101.865012 -169.527764)
			(xy 101.85703 -169.473064) (xy 101.857026 -169.417784) (xy 101.865002 -169.363083) (xy 101.88079 -169.310106)
			(xy 101.904059 -169.259963) (xy 101.934322 -169.213703) (xy 101.952298 -169.192702) (xy 101.962138 -169.180931)
			(xy 101.976362 -169.153756) (xy 101.983666 -169.123965) (xy 101.984048 -169.108628) (xy 101.984048 -157.082236)
			(xy 101.983586 -157.066909) (xy 101.976272 -157.037141) (xy 101.962081 -157.00997) (xy 101.952298 -156.998162)
			(xy 101.934352 -156.977135) (xy 101.904082 -156.930879) (xy 101.880807 -156.880739) (xy 101.865012 -156.827764)
			(xy 101.85703 -156.773064) (xy 101.857026 -156.717784) (xy 101.865002 -156.663083) (xy 101.88079 -156.610106)
			(xy 101.904059 -156.559963) (xy 101.934322 -156.513703) (xy 101.952298 -156.492702) (xy 101.962138 -156.480931)
			(xy 101.976362 -156.453756) (xy 101.983666 -156.423965) (xy 101.984048 -156.408628) (xy 101.984048 -144.382236)
			(xy 101.983586 -144.366909) (xy 101.976272 -144.337141) (xy 101.962081 -144.30997) (xy 101.952298 -144.298162)
			(xy 101.934352 -144.277135) (xy 101.904082 -144.230879) (xy 101.880807 -144.180739) (xy 101.865012 -144.127764)
			(xy 101.85703 -144.073064) (xy 101.857026 -144.017784) (xy 101.865002 -143.963083) (xy 101.88079 -143.910106)
			(xy 101.904059 -143.859963) (xy 101.934322 -143.813703) (xy 101.952298 -143.792702) (xy 101.962138 -143.780931)
			(xy 101.976362 -143.753756) (xy 101.983666 -143.723965) (xy 101.984048 -143.708628) (xy 101.984048 -131.682236)
			(xy 101.983586 -131.666909) (xy 101.976272 -131.637141) (xy 101.962081 -131.60997) (xy 101.952298 -131.598162)
			(xy 101.934352 -131.577135) (xy 101.904082 -131.530879) (xy 101.880807 -131.480739) (xy 101.865012 -131.427764)
			(xy 101.85703 -131.373064) (xy 101.857026 -131.317784) (xy 101.865002 -131.263083) (xy 101.88079 -131.210106)
			(xy 101.904059 -131.159963) (xy 101.934322 -131.113703) (xy 101.952298 -131.092702) (xy 101.962138 -131.080931)
			(xy 101.976362 -131.053756) (xy 101.983666 -131.023965) (xy 101.984048 -131.008628) (xy 101.984048 -118.982236)
			(xy 101.983586 -118.966909) (xy 101.976272 -118.937141) (xy 101.962081 -118.90997) (xy 101.952298 -118.898162)
			(xy 101.934352 -118.877135) (xy 101.904082 -118.830879) (xy 101.880807 -118.780739) (xy 101.865012 -118.727764)
			(xy 101.85703 -118.673064) (xy 101.857026 -118.617784) (xy 101.865002 -118.563083) (xy 101.88079 -118.510106)
			(xy 101.904059 -118.459963) (xy 101.934322 -118.413703) (xy 101.952298 -118.392702) (xy 101.962138 -118.380931)
			(xy 101.976362 -118.353756) (xy 101.983666 -118.323965) (xy 101.984048 -118.308628) (xy 101.984048 -106.282236)
			(xy 101.983586 -106.266909) (xy 101.976272 -106.237141) (xy 101.962081 -106.20997) (xy 101.952298 -106.198162)
			(xy 101.934352 -106.177135) (xy 101.904082 -106.130879) (xy 101.880807 -106.080739) (xy 101.865012 -106.027764)
			(xy 101.85703 -105.973064) (xy 101.857026 -105.917784) (xy 101.865002 -105.863083) (xy 101.88079 -105.810106)
			(xy 101.904059 -105.759963) (xy 101.934322 -105.713703) (xy 101.952298 -105.692702) (xy 101.962138 -105.680931)
			(xy 101.976362 -105.653756) (xy 101.983666 -105.623965) (xy 101.984048 -105.608628) (xy 101.984048 -93.582236)
			(xy 101.983586 -93.566909) (xy 101.976272 -93.537141) (xy 101.962081 -93.50997) (xy 101.952298 -93.498162)
			(xy 101.934352 -93.477135) (xy 101.904082 -93.430879) (xy 101.880807 -93.380739) (xy 101.865012 -93.327764)
			(xy 101.85703 -93.273064) (xy 101.857026 -93.217784) (xy 101.865002 -93.163083) (xy 101.88079 -93.110106)
			(xy 101.904059 -93.059963) (xy 101.934322 -93.013703) (xy 101.952298 -92.992702) (xy 101.962138 -92.980931)
			(xy 101.976362 -92.953756) (xy 101.983666 -92.923965) (xy 101.984048 -92.908628) (xy 101.984048 -80.882236)
			(xy 101.983586 -80.866909) (xy 101.976272 -80.837141) (xy 101.962081 -80.80997) (xy 101.952298 -80.798162)
			(xy 101.934352 -80.777135) (xy 101.904082 -80.730879) (xy 101.880807 -80.680739) (xy 101.865012 -80.627764)
			(xy 101.85703 -80.573064) (xy 101.857026 -80.517784) (xy 101.865002 -80.463083) (xy 101.88079 -80.410106)
			(xy 101.904059 -80.359963) (xy 101.934322 -80.313703) (xy 101.952298 -80.292702) (xy 101.962138 -80.280931)
			(xy 101.976362 -80.253756) (xy 101.983666 -80.223965) (xy 101.984048 -80.208628) (xy 101.984048 -68.182236)
			(xy 101.983586 -68.166909) (xy 101.976272 -68.137141) (xy 101.962081 -68.10997) (xy 101.952298 -68.098162)
			(xy 101.934352 -68.077135) (xy 101.904082 -68.030879) (xy 101.880807 -67.980739) (xy 101.865012 -67.927764)
			(xy 101.85703 -67.873064) (xy 101.857026 -67.817784) (xy 101.865002 -67.763083) (xy 101.88079 -67.710106)
			(xy 101.904059 -67.659963) (xy 101.934322 -67.613703) (xy 101.952298 -67.592702) (xy 101.962138 -67.580931)
			(xy 101.976362 -67.553756) (xy 101.983666 -67.523965) (xy 101.984048 -67.508628) (xy 101.984048 -55.482236)
			(xy 101.983586 -55.466909) (xy 101.976272 -55.437141) (xy 101.962081 -55.40997) (xy 101.952298 -55.398162)
			(xy 101.934352 -55.377135) (xy 101.904082 -55.330879) (xy 101.880807 -55.280739) (xy 101.865012 -55.227764)
			(xy 101.85703 -55.173064) (xy 101.857026 -55.117784) (xy 101.865002 -55.063083) (xy 101.88079 -55.010106)
			(xy 101.904059 -54.959963) (xy 101.934322 -54.913703) (xy 101.952298 -54.892702) (xy 101.962138 -54.880931)
			(xy 101.976362 -54.853756) (xy 101.983666 -54.823965) (xy 101.984048 -54.808628) (xy 101.984048 -42.782236)
			(xy 101.983586 -42.766909) (xy 101.976272 -42.737141) (xy 101.962081 -42.70997) (xy 101.952298 -42.698162)
			(xy 101.934352 -42.677135) (xy 101.904082 -42.630879) (xy 101.880807 -42.580739) (xy 101.865012 -42.527764)
			(xy 101.85703 -42.473064) (xy 101.857026 -42.417784) (xy 101.865002 -42.363083) (xy 101.88079 -42.310106)
			(xy 101.904059 -42.259963) (xy 101.934322 -42.213703) (xy 101.952298 -42.192702) (xy 101.962138 -42.180931)
			(xy 101.976362 -42.153756) (xy 101.983666 -42.123965) (xy 101.984048 -42.108628) (xy 101.984048 -30.082236)
			(xy 101.983586 -30.066909) (xy 101.976272 -30.037141) (xy 101.962081 -30.00997) (xy 101.952298 -29.998162)
			(xy 101.934352 -29.977135) (xy 101.904082 -29.930879) (xy 101.880807 -29.880739) (xy 101.865012 -29.827764)
			(xy 101.85703 -29.773064) (xy 101.857026 -29.717784) (xy 101.865002 -29.663083) (xy 101.88079 -29.610106)
			(xy 101.904059 -29.559963) (xy 101.934322 -29.513703) (xy 101.952298 -29.492702) (xy 101.962138 -29.480931)
			(xy 101.976362 -29.453756) (xy 101.983666 -29.423965) (xy 101.984048 -29.408628) (xy 101.984048 -17.382236)
			(xy 101.983586 -17.366909) (xy 101.976272 -17.337141) (xy 101.962081 -17.30997) (xy 101.952298 -17.298162)
			(xy 101.934352 -17.277135) (xy 101.904082 -17.230879) (xy 101.880807 -17.180739) (xy 101.865012 -17.127764)
			(xy 101.85703 -17.073064) (xy 101.857026 -17.017784) (xy 101.865002 -16.963083) (xy 101.88079 -16.910106)
			(xy 101.904059 -16.859963) (xy 101.934322 -16.813703) (xy 101.952298 -16.792702) (xy 101.962138 -16.780931)
			(xy 101.976362 -16.753756) (xy 101.983666 -16.723965) (xy 101.984048 -16.708628) (xy 101.984048 -4.682236)
			(xy 101.983586 -4.666909) (xy 101.976272 -4.637141) (xy 101.962081 -4.60997) (xy 101.952298 -4.598162)
			(xy 101.934352 -4.577135) (xy 101.904082 -4.530879) (xy 101.880807 -4.480739) (xy 101.865012 -4.427764)
			(xy 101.85703 -4.373064) (xy 101.857026 -4.317784) (xy 101.865002 -4.263083) (xy 101.88079 -4.210106)
			(xy 101.904059 -4.159963) (xy 101.934322 -4.113703) (xy 101.952298 -4.092702) (xy 101.962138 -4.080931)
			(xy 101.976362 -4.053756) (xy 101.983666 -4.023965) (xy 101.984048 -4.008628) (xy 101.984048 -1.999996)
			(xy 101.983539 -1.954528) (xy 101.975148 -1.863979) (xy 101.958437 -1.77459) (xy 101.93355 -1.687125)
			(xy 101.900699 -1.60233) (xy 101.860163 -1.520927) (xy 101.81229 -1.443612) (xy 101.757486 -1.371044)
			(xy 101.696221 -1.303842) (xy 101.629016 -1.242581) (xy 101.556445 -1.187781) (xy 101.479127 -1.139911)
			(xy 101.397723 -1.09938) (xy 101.312925 -1.066533) (xy 101.225459 -1.041651) (xy 101.13607 -1.024945)
			(xy 101.04552 -1.016559) (xy 101.000052 -1.016) (xy 95.642938 -1.016) (xy 95.627553 -1.016471) (xy 95.597681 -1.023847)
			(xy 95.570441 -1.038157) (xy 95.55861 -1.048004) (xy 95.537572 -1.065987) (xy 95.491281 -1.09632)
			(xy 95.441093 -1.119645) (xy 95.388061 -1.135473) (xy 95.333298 -1.14347) (xy 95.277954 -1.14347)
			(xy 95.223191 -1.135473) (xy 95.170159 -1.119645) (xy 95.119971 -1.09632) (xy 95.07368 -1.065987)
			(xy 95.052642 -1.048004) (xy 95.04085 -1.0381) (xy 95.0136 -1.023771) (xy 94.983708 -1.016401) (xy 94.968314 -1.016)
			(xy 82.942938 -1.016) (xy 82.927553 -1.016471) (xy 82.897681 -1.023847) (xy 82.870441 -1.038157)
			(xy 82.85861 -1.048004) (xy 82.837572 -1.065987) (xy 82.791281 -1.09632) (xy 82.741093 -1.119645)
			(xy 82.688061 -1.135473) (xy 82.633298 -1.14347) (xy 82.577954 -1.14347) (xy 82.523191 -1.135473)
			(xy 82.470159 -1.119645) (xy 82.419971 -1.09632) (xy 82.37368 -1.065987) (xy 82.352642 -1.048004)
			(xy 82.34085 -1.0381) (xy 82.3136 -1.023771) (xy 82.283708 -1.016401) (xy 82.268314 -1.016) (xy 70.242938 -1.016)
			(xy 70.227553 -1.016471) (xy 70.197681 -1.023847) (xy 70.170441 -1.038157) (xy 70.15861 -1.048004)
			(xy 70.137572 -1.065987) (xy 70.091281 -1.09632) (xy 70.041093 -1.119645) (xy 69.988061 -1.135473)
			(xy 69.933298 -1.14347) (xy 69.877954 -1.14347) (xy 69.823191 -1.135473) (xy 69.770159 -1.119645)
			(xy 69.719971 -1.09632) (xy 69.67368 -1.065987) (xy 69.652642 -1.048004) (xy 69.64085 -1.0381) (xy 69.6136 -1.023771)
			(xy 69.583708 -1.016401) (xy 69.568314 -1.016) (xy 57.542938 -1.016) (xy 57.527553 -1.016471) (xy 57.497681 -1.023847)
			(xy 57.470441 -1.038157) (xy 57.45861 -1.048004) (xy 57.437572 -1.065987) (xy 57.391281 -1.09632)
			(xy 57.341093 -1.119645) (xy 57.288061 -1.135473) (xy 57.233298 -1.14347) (xy 57.177954 -1.14347)
			(xy 57.123191 -1.135473) (xy 57.070159 -1.119645) (xy 57.019971 -1.09632) (xy 56.97368 -1.065987)
			(xy 56.952642 -1.048004) (xy 56.94085 -1.0381) (xy 56.9136 -1.023771) (xy 56.883708 -1.016401) (xy 56.868314 -1.016)
			(xy 44.842938 -1.016) (xy 44.827553 -1.016471) (xy 44.797681 -1.023847) (xy 44.770441 -1.038157)
			(xy 44.75861 -1.048004) (xy 44.737572 -1.065987) (xy 44.691281 -1.09632) (xy 44.641093 -1.119645)
			(xy 44.588061 -1.135473) (xy 44.533298 -1.14347) (xy 44.477954 -1.14347) (xy 44.423191 -1.135473)
			(xy 44.370159 -1.119645) (xy 44.319971 -1.09632) (xy 44.27368 -1.065987) (xy 44.252642 -1.048004)
			(xy 44.24085 -1.0381) (xy 44.2136 -1.023771) (xy 44.183708 -1.016401) (xy 44.168314 -1.016) (xy 32.142938 -1.016)
			(xy 32.127553 -1.016471) (xy 32.097681 -1.023847) (xy 32.070441 -1.038157) (xy 32.05861 -1.048004)
			(xy 32.037572 -1.065987) (xy 31.991281 -1.09632) (xy 31.941093 -1.119645) (xy 31.888061 -1.135473)
			(xy 31.833298 -1.14347) (xy 31.777954 -1.14347) (xy 31.723191 -1.135473) (xy 31.670159 -1.119645)
			(xy 31.619971 -1.09632) (xy 31.57368 -1.065987) (xy 31.552642 -1.048004) (xy 31.54085 -1.0381) (xy 31.5136 -1.023771)
			(xy 31.483708 -1.016401) (xy 31.468314 -1.016) (xy 26.500074 -1.016) (xy 26.468378 -1.01652) (xy 26.40553 -1.024797)
			(xy 26.3443 -1.041207) (xy 26.285735 -1.065469) (xy 26.230839 -1.097168) (xy 26.180549 -1.13576)
			(xy 26.135727 -1.180587) (xy 26.09714 -1.23088) (xy 26.065447 -1.28578) (xy 26.041191 -1.344347)
			(xy 26.024788 -1.405579) (xy 26.016517 -1.468428) (xy 26.01595 -1.500124) (xy 26.01595 -2.500122)
			(xy 26.015455 -2.570697) (xy 26.007541 -2.711624) (xy 25.991737 -2.851885) (xy 25.968093 -2.99104)
			(xy 25.936685 -3.12865) (xy 25.897609 -3.264283) (xy 25.850991 -3.397511) (xy 25.796975 -3.527916)
			(xy 25.735733 -3.655087) (xy 25.667456 -3.778624) (xy 25.59236 -3.898139) (xy 25.510681 -4.013254)
			(xy 25.422676 -4.123609) (xy 25.328622 -4.228856) (xy 25.228814 -4.328663) (xy 25.123568 -4.422717)
			(xy 25.013213 -4.510723) (xy 24.898097 -4.592401) (xy 24.778582 -4.667497) (xy 24.655045 -4.735774)
			(xy 24.527874 -4.797016) (xy 24.39747 -4.851032) (xy 24.264241 -4.89765) (xy 24.128608 -4.936725)
			(xy 23.990998 -4.968134) (xy 23.851843 -4.991777) (xy 23.711582 -5.007581) (xy 23.570655 -5.015495)
			(xy 23.50008 -5.015992) (xy 19.443446 -5.015992) (xy 19.428061 -5.016462) (xy 19.398187 -5.023837)
			(xy 19.370945 -5.038144) (xy 19.359118 -5.047996) (xy 19.338059 -5.06606) (xy 19.2917 -5.096538)
			(xy 19.241414 -5.119978) (xy 19.188262 -5.135885) (xy 19.133366 -5.143923) (xy 19.077886 -5.143923)
			(xy 19.02299 -5.135885) (xy 18.969838 -5.119978) (xy 18.919552 -5.096538) (xy 18.873193 -5.06606)
			(xy 18.852134 -5.047996) (xy 18.840341 -5.038093) (xy 18.813091 -5.023766) (xy 18.7832 -5.016399)
			(xy 18.767806 -5.015992) (xy 6.743446 -5.015992) (xy 6.728061 -5.016462) (xy 6.698187 -5.023837)
			(xy 6.670945 -5.038144) (xy 6.659118 -5.047996) (xy 6.638059 -5.06606) (xy 6.5917 -5.096538) (xy 6.541414 -5.119978)
			(xy 6.488262 -5.135885) (xy 6.433366 -5.143923) (xy 6.377886 -5.143923) (xy 6.32299 -5.135885) (xy 6.269838 -5.119978)
			(xy 6.219552 -5.096538) (xy 6.173193 -5.06606) (xy 6.152134 -5.047996) (xy 6.140341 -5.038093) (xy 6.113091 -5.023766)
			(xy 6.0832 -5.016399) (xy 6.067806 -5.015992) (xy 1.500124 -5.015992) (xy 1.468427 -5.016511) (xy 1.405575 -5.024786)
			(xy 1.344341 -5.041194) (xy 1.285773 -5.065454) (xy 1.230872 -5.097152) (xy 1.180579 -5.135744) (xy 1.135752 -5.18057)
			(xy 1.09716 -5.230864) (xy 1.065463 -5.285765) (xy 1.041203 -5.344333) (xy 1.024795 -5.405567) (xy 1.01652 -5.468419)
			(xy 1.016 -5.500116) (xy 1.016 -7.747) (xy 5.5306 -7.747) (xy 5.534631 -7.617434) (xy 5.54671 -7.48837)
			(xy 5.566789 -7.360306) (xy 5.594791 -7.233739) (xy 5.630608 -7.109156) (xy 5.6741 -6.987042) (xy 5.7251 -6.867868)
			(xy 5.783411 -6.752095) (xy 5.848806 -6.640171) (xy 5.921033 -6.532529) (xy 5.999813 -6.429586) (xy 6.08484 -6.33174)
			(xy 6.175785 -6.239368) (xy 6.272297 -6.15283) (xy 6.374003 -6.072459) (xy 6.480509 -5.998567) (xy 6.591402 -5.931439)
			(xy 6.706254 -5.871335) (xy 6.824621 -5.818488) (xy 6.946044 -5.773101) (xy 7.070054 -5.735352) (xy 7.196171 -5.705385)
			(xy 7.323907 -5.683316) (xy 7.452768 -5.669232) (xy 7.582255 -5.663186) (xy 7.711868 -5.665202) (xy 7.841104 -5.675272)
			(xy 7.969465 -5.693357) (xy 8.096453 -5.719387) (xy 8.221577 -5.753262) (xy 8.344353 -5.79485) (xy 8.464306 -5.843991)
			(xy 8.580971 -5.900494) (xy 8.693899 -5.964141) (xy 8.802651 -6.034685) (xy 8.906807 -6.111854) (xy 9.005964 -6.195349)
			(xy 9.099738 -6.284847) (xy 9.187767 -6.380002) (xy 9.26971 -6.480445) (xy 9.345249 -6.585788) (xy 9.414094 -6.695624)
			(xy 9.475977 -6.809528) (xy 9.522754 -6.91007) (xy 39.818564 -6.91007) (xy 39.819054 -6.852663) (xy 39.826889 -6.738117)
			(xy 39.842523 -6.624372) (xy 39.865882 -6.51196) (xy 39.896859 -6.401403) (xy 39.935308 -6.293218)
			(xy 39.98105 -6.18791) (xy 40.033872 -6.085968) (xy 40.093527 -5.987869) (xy 40.159738 -5.894069)
			(xy 40.232196 -5.805007) (xy 40.310562 -5.721096) (xy 40.394473 -5.64273) (xy 40.483535 -5.570272)
			(xy 40.577335 -5.504061) (xy 40.675434 -5.444406) (xy 40.777376 -5.391584) (xy 40.882684 -5.345842)
			(xy 40.990869 -5.307393) (xy 41.101426 -5.276416) (xy 41.213838 -5.253057) (xy 41.327583 -5.237423)
			(xy 41.442129 -5.229588) (xy 41.556943 -5.229588) (xy 41.671489 -5.237423) (xy 41.785234 -5.253057)
			(xy 41.897646 -5.276416) (xy 42.008203 -5.307393) (xy 42.116388 -5.345842) (xy 42.221696 -5.391584)
			(xy 42.323638 -5.444406) (xy 42.421737 -5.504061) (xy 42.515537 -5.570272) (xy 42.604599 -5.64273)
			(xy 42.68851 -5.721096) (xy 42.766876 -5.805007) (xy 42.839334 -5.894069) (xy 42.905545 -5.987869)
			(xy 42.9652 -6.085968) (xy 43.018022 -6.18791) (xy 43.063764 -6.293218) (xy 43.102213 -6.401403)
			(xy 43.13319 -6.51196) (xy 43.156549 -6.624372) (xy 43.172183 -6.738117) (xy 43.180018 -6.852663)
			(xy 43.180508 -6.91007) (xy 43.180381 -6.943251) (xy 43.177842 -7.009565) (xy 43.175428 -7.042658)
			(xy 43.170272 -7.100942) (xy 43.152948 -7.216671) (xy 43.127616 -7.330914) (xy 43.094401 -7.443119)
			(xy 43.053462 -7.552742) (xy 43.004999 -7.659253) (xy 42.949245 -7.762135) (xy 42.886471 -7.860891)
			(xy 42.816981 -7.955042) (xy 42.741111 -8.044132) (xy 42.659229 -8.127729) (xy 42.571732 -8.20543)
			(xy 42.500813 -8.26008) (xy 93.154506 -8.26008) (xy 93.158522 -8.14381) (xy 93.170549 -8.028095)
			(xy 93.190531 -7.913485) (xy 93.218373 -7.800526) (xy 93.253942 -7.689758) (xy 93.297068 -7.581707)
			(xy 93.347545 -7.476889) (xy 93.405134 -7.375804) (xy 93.46956 -7.278932) (xy 93.540515 -7.186736)
			(xy 93.617662 -7.099655) (xy 93.700633 -7.018104) (xy 93.789033 -6.942472) (xy 93.88244 -6.873118)
			(xy 93.980409 -6.810375) (xy 94.082473 -6.754539) (xy 94.188147 -6.705878) (xy 94.296926 -6.664624)
			(xy 94.408291 -6.630973) (xy 94.521714 -6.605085) (xy 94.636651 -6.587084) (xy 94.752557 -6.577055)
			(xy 94.868879 -6.575047) (xy 94.985062 -6.581069) (xy 95.100553 -6.595092) (xy 95.214801 -6.61705)
			(xy 95.327262 -6.646837) (xy 95.4374 -6.684312) (xy 95.54469 -6.729297) (xy 95.648621 -6.781576)
			(xy 95.748697 -6.840901) (xy 95.844443 -6.906989) (xy 95.9354 -6.979525) (xy 96.021136 -7.058164)
			(xy 96.101243 -7.14253) (xy 96.175339 -7.232222) (xy 96.243069 -7.326812) (xy 96.304113 -7.42585)
			(xy 96.358178 -7.528863) (xy 96.405008 -7.63536) (xy 96.444379 -7.744835) (xy 96.476103 -7.856765)
			(xy 96.500029 -7.970617) (xy 96.516043 -8.085849) (xy 96.52407 -8.201911) (xy 96.524572 -8.26008)
			(xy 96.52407 -8.318249) (xy 96.516043 -8.434311) (xy 96.500029 -8.549543) (xy 96.476103 -8.663395)
			(xy 96.444379 -8.775325) (xy 96.405008 -8.8848) (xy 96.358178 -8.991297) (xy 96.304113 -9.09431)
			(xy 96.243069 -9.193348) (xy 96.175339 -9.287938) (xy 96.101243 -9.37763) (xy 96.021136 -9.461996)
			(xy 95.9354 -9.540635) (xy 95.844443 -9.613171) (xy 95.748697 -9.679259) (xy 95.648621 -9.738584)
			(xy 95.54469 -9.790863) (xy 95.4374 -9.835848) (xy 95.327262 -9.873323) (xy 95.214801 -9.90311) (xy 95.100553 -9.925068)
			(xy 94.985062 -9.939091) (xy 94.868879 -9.945113) (xy 94.752557 -9.943105) (xy 94.636651 -9.933076)
			(xy 94.521714 -9.915075) (xy 94.408291 -9.889187) (xy 94.296926 -9.855536) (xy 94.188147 -9.814282)
			(xy 94.082473 -9.765621) (xy 93.980409 -9.709785) (xy 93.88244 -9.647042) (xy 93.789033 -9.577688)
			(xy 93.700633 -9.502056) (xy 93.617662 -9.420505) (xy 93.540515 -9.333424) (xy 93.46956 -9.241228)
			(xy 93.405134 -9.144356) (xy 93.347545 -9.043271) (xy 93.297068 -8.938453) (xy 93.253942 -8.830402)
			(xy 93.218373 -8.719634) (xy 93.190531 -8.606675) (xy 93.170549 -8.492065) (xy 93.158522 -8.37635)
			(xy 93.154506 -8.26008) (xy 42.500813 -8.26008) (xy 42.479042 -8.276857) (xy 42.381609 -8.341665)
			(xy 42.279905 -8.39954) (xy 42.174422 -8.450202) (xy 42.065671 -8.493404) (xy 41.954179 -8.528939)
			(xy 41.840485 -8.556634) (xy 41.725141 -8.576354) (xy 41.608704 -8.588005) (xy 41.491739 -8.59153)
			(xy 41.374812 -8.586912) (xy 41.258489 -8.574173) (xy 41.143334 -8.553375) (xy 41.029905 -8.524618)
			(xy 40.91875 -8.488042) (xy 40.810407 -8.443825) (xy 40.705403 -8.392179) (xy 40.604244 -8.333356)
			(xy 40.507421 -8.26764) (xy 40.415403 -8.195349) (xy 40.328636 -8.116834) (xy 40.247539 -8.032474)
			(xy 40.172506 -7.942679) (xy 40.103899 -7.847883) (xy 40.042051 -7.748544) (xy 39.987262 -7.645145)
			(xy 39.939796 -7.538186) (xy 39.899884 -7.428185) (xy 39.86772 -7.315674) (xy 39.843457 -7.201199)
			(xy 39.827215 -7.085313) (xy 39.819072 -6.968579) (xy 39.818564 -6.91007) (xy 9.522754 -6.91007)
			(xy 9.530658 -6.927058) (xy 9.577928 -7.047761) (xy 9.617601 -7.171169) (xy 9.649526 -7.296805) (xy 9.673578 -7.424182)
			(xy 9.689665 -7.552808) (xy 9.697724 -7.682186) (xy 9.698228 -7.747) (xy 9.697724 -7.811814) (xy 9.689665 -7.941192)
			(xy 9.673578 -8.069818) (xy 9.649526 -8.197195) (xy 9.617601 -8.322831) (xy 9.577928 -8.446239) (xy 9.530658 -8.566942)
			(xy 9.475977 -8.684472) (xy 9.414094 -8.798376) (xy 9.345249 -8.908212) (xy 9.26971 -9.013555) (xy 9.187767 -9.113998)
			(xy 9.099738 -9.209153) (xy 9.005964 -9.298651) (xy 8.906807 -9.382146) (xy 8.802651 -9.459315) (xy 8.693899 -9.529859)
			(xy 8.580971 -9.593506) (xy 8.464306 -9.650009) (xy 8.344353 -9.69915) (xy 8.221577 -9.740738) (xy 8.096453 -9.774613)
			(xy 7.969465 -9.800643) (xy 7.841104 -9.818728) (xy 7.711868 -9.828798) (xy 7.582255 -9.830814) (xy 7.452768 -9.824768)
			(xy 7.323907 -9.810684) (xy 7.196171 -9.788615) (xy 7.070054 -9.758648) (xy 6.946044 -9.720899) (xy 6.824621 -9.675512)
			(xy 6.706254 -9.622665) (xy 6.591402 -9.562561) (xy 6.480509 -9.495433) (xy 6.374003 -9.421541) (xy 6.272297 -9.34117)
			(xy 6.175785 -9.254632) (xy 6.08484 -9.16226) (xy 5.999813 -9.064414) (xy 5.921033 -8.961471) (xy 5.848806 -8.853829)
			(xy 5.783411 -8.741905) (xy 5.7251 -8.626132) (xy 5.6741 -8.506958) (xy 5.630608 -8.384844) (xy 5.594791 -8.260261)
			(xy 5.566789 -8.133694) (xy 5.54671 -8.00563) (xy 5.534631 -7.876566) (xy 5.5306 -7.747) (xy 1.016 -7.747)
			(xy 1.016 -12.879578) (xy 1.016492 -12.894921) (xy 1.023881 -12.924707) (xy 1.038164 -12.95187) (xy 1.048004 -12.963652)
			(xy 1.065976 -12.984695) (xy 1.09629 -13.030991) (xy 1.119599 -13.08118) (xy 1.135415 -13.13421)
			(xy 1.143407 -13.188967) (xy 1.143407 -13.244305) (xy 1.135415 -13.299062) (xy 1.119599 -13.352092)
			(xy 1.09629 -13.402281) (xy 1.065976 -13.448577) (xy 1.048004 -13.46962) (xy 1.03813 -13.481379)
			(xy 1.023835 -13.508546) (xy 1.01646 -13.538345) (xy 1.016 -13.553694) (xy 1.016 -19.177) (xy 5.5306 -19.177)
			(xy 5.534631 -19.047434) (xy 5.54671 -18.91837) (xy 5.566789 -18.790306) (xy 5.594791 -18.663739)
			(xy 5.630608 -18.539156) (xy 5.6741 -18.417042) (xy 5.7251 -18.297868) (xy 5.783411 -18.182095) (xy 5.848806 -18.070171)
			(xy 5.921033 -17.962529) (xy 5.999813 -17.859586) (xy 6.08484 -17.76174) (xy 6.175785 -17.669368)
			(xy 6.272297 -17.58283) (xy 6.374003 -17.502459) (xy 6.480509 -17.428567) (xy 6.591402 -17.361439)
			(xy 6.706254 -17.301335) (xy 6.824621 -17.248488) (xy 6.946044 -17.203101) (xy 7.070054 -17.165352)
			(xy 7.196171 -17.135385) (xy 7.323907 -17.113316) (xy 7.452768 -17.099232) (xy 7.582255 -17.093186)
			(xy 7.711868 -17.095202) (xy 7.841104 -17.105272) (xy 7.969465 -17.123357) (xy 8.096453 -17.149387)
			(xy 8.221577 -17.183262) (xy 8.344353 -17.22485) (xy 8.464306 -17.273991) (xy 8.580971 -17.330494)
			(xy 8.693899 -17.394141) (xy 8.802651 -17.464685) (xy 8.906807 -17.541854) (xy 9.005964 -17.625349)
			(xy 9.099738 -17.714847) (xy 9.187767 -17.810002) (xy 9.26971 -17.910445) (xy 9.345249 -18.015788)
			(xy 9.414094 -18.125624) (xy 9.475977 -18.239528) (xy 9.530658 -18.357058) (xy 9.577928 -18.477761)
			(xy 9.617601 -18.601169) (xy 9.649526 -18.726805) (xy 9.673578 -18.854182) (xy 9.689665 -18.982808)
			(xy 9.697724 -19.112186) (xy 9.698228 -19.177) (xy 9.697724 -19.241814) (xy 9.689665 -19.371192)
			(xy 9.673578 -19.499818) (xy 9.649526 -19.627195) (xy 9.617601 -19.752831) (xy 9.577928 -19.876239)
			(xy 9.530658 -19.996942) (xy 9.524527 -20.01012) (xy 86.877404 -20.01012) (xy 86.881424 -19.819469)
			(xy 86.893478 -19.629156) (xy 86.913544 -19.439521) (xy 86.941587 -19.2509) (xy 86.977556 -19.06363)
			(xy 87.021388 -18.878042) (xy 87.073005 -18.694467) (xy 87.132315 -18.513231) (xy 87.199213 -18.334656)
			(xy 87.273579 -18.159061) (xy 87.355281 -17.986756) (xy 87.444175 -17.818049) (xy 87.540101 -17.653239)
			(xy 87.64289 -17.49262) (xy 87.752359 -17.336477) (xy 87.868313 -17.185088) (xy 87.990547 -17.038721)
			(xy 88.118841 -16.897637) (xy 88.252969 -16.762088) (xy 88.392693 -16.632313) (xy 88.537763 -16.508543)
			(xy 88.687921 -16.391) (xy 88.842902 -16.279891) (xy 89.002429 -16.175414) (xy 89.166218 -16.077755)
			(xy 89.333978 -15.987088) (xy 89.505412 -15.903574) (xy 89.680214 -15.827361) (xy 89.858073 -15.758585)
			(xy 90.038674 -15.697367) (xy 90.221694 -15.643818) (xy 90.40681 -15.598032) (xy 90.593691 -15.56009)
			(xy 90.782006 -15.530061) (xy 90.971419 -15.507996) (xy 91.161593 -15.493937) (xy 91.352192 -15.487907)
			(xy 91.542875 -15.489917) (xy 91.733304 -15.499964) (xy 91.92314 -15.51803) (xy 92.112046 -15.544083)
			(xy 92.299685 -15.578076) (xy 92.485725 -15.619949) (xy 92.669834 -15.669628) (xy 92.851685 -15.727024)
			(xy 93.030955 -15.792035) (xy 93.207325 -15.864546) (xy 93.380481 -15.944427) (xy 93.550116 -16.031537)
			(xy 93.715928 -16.125721) (xy 93.877622 -16.226812) (xy 94.03491 -16.334628) (xy 94.187513 -16.44898)
			(xy 94.335161 -16.569663) (xy 94.477589 -16.696464) (xy 94.614545 -16.829155) (xy 94.745786 -16.967503)
			(xy 94.871078 -17.11126) (xy 94.990198 -17.260171) (xy 95.102934 -17.413972) (xy 95.209087 -17.572388)
			(xy 95.308467 -17.735139) (xy 95.400897 -17.901934) (xy 95.486214 -18.072478) (xy 95.564266 -18.246466)
			(xy 95.634913 -18.423591) (xy 95.698031 -18.603536) (xy 95.753507 -18.785982) (xy 95.801242 -18.970605)
			(xy 95.841152 -19.157075) (xy 95.873165 -19.345063) (xy 95.897225 -19.534233) (xy 95.913288 -19.724249)
			(xy 95.921327 -19.914773) (xy 95.92183 -20.01012) (xy 95.921327 -20.105467) (xy 95.913288 -20.295991)
			(xy 95.897225 -20.486007) (xy 95.873165 -20.675177) (xy 95.841152 -20.863165) (xy 95.801242 -21.049635)
			(xy 95.753507 -21.234258) (xy 95.698031 -21.416704) (xy 95.634913 -21.596649) (xy 95.564266 -21.773774)
			(xy 95.486214 -21.947762) (xy 95.400897 -22.118306) (xy 95.308467 -22.285101) (xy 95.209087 -22.447852)
			(xy 95.102934 -22.606268) (xy 94.990198 -22.760069) (xy 94.871078 -22.90898) (xy 94.745786 -23.052737)
			(xy 94.614545 -23.191085) (xy 94.477589 -23.323776) (xy 94.335161 -23.450577) (xy 94.187513 -23.57126)
			(xy 94.03491 -23.685612) (xy 93.877622 -23.793428) (xy 93.715928 -23.894519) (xy 93.550116 -23.988703)
			(xy 93.380481 -24.075813) (xy 93.207325 -24.155694) (xy 93.030955 -24.228205) (xy 92.851685 -24.293216)
			(xy 92.669834 -24.350612) (xy 92.485725 -24.400291) (xy 92.299685 -24.442164) (xy 92.112046 -24.476157)
			(xy 91.92314 -24.50221) (xy 91.733304 -24.520276) (xy 91.542875 -24.530323) (xy 91.352192 -24.532333)
			(xy 91.161593 -24.526303) (xy 90.971419 -24.512244) (xy 90.782006 -24.490179) (xy 90.593691 -24.46015)
			(xy 90.40681 -24.422208) (xy 90.221694 -24.376422) (xy 90.038674 -24.322873) (xy 89.858073 -24.261655)
			(xy 89.680214 -24.192879) (xy 89.505412 -24.116666) (xy 89.333978 -24.033152) (xy 89.166218 -23.942485)
			(xy 89.002429 -23.844826) (xy 88.842902 -23.740349) (xy 88.687921 -23.62924) (xy 88.537763 -23.511697)
			(xy 88.392693 -23.387927) (xy 88.252969 -23.258152) (xy 88.118841 -23.122603) (xy 87.990547 -22.981519)
			(xy 87.868313 -22.835152) (xy 87.752359 -22.683763) (xy 87.64289 -22.52762) (xy 87.540101 -22.367001)
			(xy 87.444175 -22.202191) (xy 87.355281 -22.033484) (xy 87.273579 -21.861179) (xy 87.199213 -21.685584)
			(xy 87.132315 -21.507009) (xy 87.073005 -21.325773) (xy 87.021388 -21.142198) (xy 86.977556 -20.95661)
			(xy 86.941587 -20.76934) (xy 86.913544 -20.580719) (xy 86.893478 -20.391084) (xy 86.881424 -20.200771)
			(xy 86.877404 -20.01012) (xy 9.524527 -20.01012) (xy 9.475977 -20.114472) (xy 9.414094 -20.228376)
			(xy 9.345249 -20.338212) (xy 9.26971 -20.443555) (xy 9.187767 -20.543998) (xy 9.099738 -20.639153)
			(xy 9.005964 -20.728651) (xy 8.906807 -20.812146) (xy 8.802651 -20.889315) (xy 8.693899 -20.959859)
			(xy 8.580971 -21.023506) (xy 8.464306 -21.080009) (xy 8.344353 -21.12915) (xy 8.221577 -21.170738)
			(xy 8.096453 -21.204613) (xy 7.969465 -21.230643) (xy 7.841104 -21.248728) (xy 7.711868 -21.258798)
			(xy 7.582255 -21.260814) (xy 7.452768 -21.254768) (xy 7.323907 -21.240684) (xy 7.196171 -21.218615)
			(xy 7.070054 -21.188648) (xy 6.946044 -21.150899) (xy 6.824621 -21.105512) (xy 6.706254 -21.052665)
			(xy 6.591402 -20.992561) (xy 6.480509 -20.925433) (xy 6.374003 -20.851541) (xy 6.272297 -20.77117)
			(xy 6.175785 -20.684632) (xy 6.08484 -20.59226) (xy 5.999813 -20.494414) (xy 5.921033 -20.391471)
			(xy 5.848806 -20.283829) (xy 5.783411 -20.171905) (xy 5.7251 -20.056132) (xy 5.6741 -19.936958) (xy 5.630608 -19.814844)
			(xy 5.594791 -19.690261) (xy 5.566789 -19.563694) (xy 5.54671 -19.43563) (xy 5.534631 -19.306566)
			(xy 5.5306 -19.177) (xy 1.016 -19.177) (xy 1.016 -25.071578) (xy 1.016492 -25.086921) (xy 1.023881 -25.116707)
			(xy 1.038164 -25.14387) (xy 1.048004 -25.155652) (xy 1.065976 -25.176695) (xy 1.09629 -25.222991)
			(xy 1.119599 -25.27318) (xy 1.135415 -25.32621) (xy 1.143407 -25.380967) (xy 1.143407 -25.436305)
			(xy 1.135415 -25.491062) (xy 1.119599 -25.544092) (xy 1.09629 -25.594281) (xy 1.065976 -25.640577)
			(xy 1.048004 -25.66162) (xy 1.03813 -25.673379) (xy 1.023835 -25.700546) (xy 1.01646 -25.730345)
			(xy 1.016 -25.745694) (xy 1.016 -25.909778) (xy 6.671831 -25.909778) (xy 6.675786 -25.817941) (xy 6.687621 -25.726784)
			(xy 6.707248 -25.636981) (xy 6.734522 -25.549199) (xy 6.769242 -25.464085) (xy 6.81115 -25.382272)
			(xy 6.859936 -25.304364) (xy 6.915239 -25.230939) (xy 6.976649 -25.162539) (xy 7.043711 -25.099672)
			(xy 7.11593 -25.042802) (xy 7.19277 -24.992351) (xy 7.273663 -24.948692) (xy 7.358009 -24.912149)
			(xy 7.445185 -24.882992) (xy 7.534544 -24.861438) (xy 7.625425 -24.847644) (xy 7.717156 -24.841714)
			(xy 7.809057 -24.843692) (xy 7.900448 -24.853563) (xy 7.990652 -24.871253) (xy 8.079001 -24.896633)
			(xy 8.164841 -24.929513) (xy 8.247537 -24.969651) (xy 8.326477 -25.01675) (xy 8.401075 -25.07046)
			(xy 8.470781 -25.130384) (xy 8.535076 -25.196078) (xy 8.593487 -25.267056) (xy 8.645579 -25.342793)
			(xy 8.690968 -25.422728) (xy 8.729318 -25.506268) (xy 8.760343 -25.592796) (xy 8.783816 -25.681671)
			(xy 8.799562 -25.772235) (xy 8.807464 -25.863817) (xy 8.807958 -25.909778) (xy 8.807464 -25.955739)
			(xy 8.799562 -26.047321) (xy 8.783816 -26.137885) (xy 8.760343 -26.22676) (xy 8.729318 -26.313288)
			(xy 8.690968 -26.396828) (xy 8.645579 -26.476763) (xy 8.593487 -26.5525) (xy 8.535076 -26.623478)
			(xy 8.470781 -26.689172) (xy 8.401075 -26.749096) (xy 8.326477 -26.802806) (xy 8.247537 -26.849905)
			(xy 8.164841 -26.890043) (xy 8.079001 -26.922923) (xy 7.990652 -26.948303) (xy 7.900448 -26.965993)
			(xy 7.809057 -26.975864) (xy 7.717156 -26.977842) (xy 7.625425 -26.971912) (xy 7.534544 -26.958118)
			(xy 7.445185 -26.936564) (xy 7.358009 -26.907407) (xy 7.273663 -26.870864) (xy 7.19277 -26.827205)
			(xy 7.11593 -26.776754) (xy 7.043711 -26.719884) (xy 6.976649 -26.657017) (xy 6.915239 -26.588617)
			(xy 6.859936 -26.515192) (xy 6.81115 -26.437284) (xy 6.769242 -26.355471) (xy 6.734522 -26.270357)
			(xy 6.707248 -26.182575) (xy 6.687621 -26.092772) (xy 6.675786 -26.001615) (xy 6.671831 -25.909778)
			(xy 1.016 -25.909778) (xy 1.016 -29.19984) (xy 11.341362 -29.19984) (xy 11.345365 -28.994672) (xy 11.357371 -28.789816)
			(xy 11.377361 -28.585585) (xy 11.405303 -28.382289) (xy 11.441156 -28.180238) (xy 11.484865 -27.979739)
			(xy 11.536363 -27.781099) (xy 11.595572 -27.584619) (xy 11.662402 -27.390599) (xy 11.736751 -27.199334)
			(xy 11.818506 -27.011116) (xy 11.907542 -26.82623) (xy 12.003724 -26.64496) (xy 12.106905 -26.467579)
			(xy 12.216928 -26.29436) (xy 12.333626 -26.125565) (xy 12.456821 -25.961452) (xy 12.586324 -25.802271)
			(xy 12.72194 -25.648263) (xy 12.863462 -25.499664) (xy 13.010673 -25.356699) (xy 13.16335 -25.219587)
			(xy 13.321261 -25.088537) (xy 13.484164 -24.963747) (xy 13.651812 -24.845408) (xy 13.82395 -24.7337)
			(xy 14.000315 -24.628793) (xy 14.180639 -24.530847) (xy 14.364647 -24.440012) (xy 14.552059 -24.356424)
			(xy 14.742589 -24.280213) (xy 14.935948 -24.211493) (xy 15.131841 -24.15037) (xy 15.329969 -24.096936)
			(xy 15.530031 -24.051273) (xy 15.731723 -24.01345) (xy 15.934737 -23.983526) (xy 16.138763 -23.961545)
			(xy 16.343492 -23.947541) (xy 16.548612 -23.941536) (xy 16.753809 -23.943538) (xy 16.958772 -23.953544)
			(xy 17.163189 -23.97154) (xy 17.366748 -23.997498) (xy 17.569139 -24.031378) (xy 17.770054 -24.073128)
			(xy 17.969188 -24.122686) (xy 18.166236 -24.179976) (xy 18.360899 -24.24491) (xy 18.55288 -24.317389)
			(xy 18.741887 -24.397304) (xy 18.927632 -24.484532) (xy 19.109833 -24.57894) (xy 19.288211 -24.680386)
			(xy 19.462496 -24.788714) (xy 19.632421 -24.903759) (xy 19.797728 -25.025347) (xy 19.958166 -25.153292)
			(xy 20.113489 -25.287398) (xy 20.263462 -25.427463) (xy 20.407856 -25.573273) (xy 20.546451 -25.724605)
			(xy 20.679036 -25.88123) (xy 20.805409 -26.042908) (xy 20.925378 -26.209393) (xy 21.03876 -26.380433)
			(xy 21.145383 -26.555766) (xy 21.245083 -26.735126) (xy 21.33771 -26.918239) (xy 21.423122 -27.104826)
			(xy 21.501188 -27.294604) (xy 21.571791 -27.487283) (xy 21.634823 -27.68257) (xy 21.690187 -27.880168)
			(xy 21.7378 -28.079775) (xy 21.777588 -28.281088) (xy 21.809492 -28.4838) (xy 21.833462 -28.687603)
			(xy 21.849463 -28.892185) (xy 21.857469 -29.097236) (xy 21.85797 -29.19984) (xy 21.857469 -29.302444)
			(xy 21.849463 -29.507495) (xy 21.833462 -29.712077) (xy 21.809492 -29.91588) (xy 21.777588 -30.118592)
			(xy 21.7378 -30.319905) (xy 21.690187 -30.519512) (xy 21.634823 -30.71711) (xy 21.571791 -30.912397)
			(xy 21.501188 -31.105076) (xy 21.423122 -31.294854) (xy 21.33771 -31.481441) (xy 21.245083 -31.664554)
			(xy 21.145383 -31.843914) (xy 21.03876 -32.019247) (xy 20.925378 -32.190287) (xy 20.846567 -32.299656)
			(xy 72.864733 -32.299656) (xy 72.868742 -32.096785) (xy 72.880762 -31.894231) (xy 72.900776 -31.69231)
			(xy 72.928751 -31.491337) (xy 72.964644 -31.291627) (xy 73.008398 -31.09349) (xy 73.059947 -30.897237)
			(xy 73.119208 -30.703173) (xy 73.18609 -30.511602) (xy 73.260488 -30.322823) (xy 73.342286 -30.13713)
			(xy 73.431356 -29.954814) (xy 73.527559 -29.776159) (xy 73.630746 -29.601445) (xy 73.740754 -29.430943)
			(xy 73.857412 -29.26492) (xy 73.980538 -29.103636) (xy 74.10994 -28.947342) (xy 74.245415 -28.796282)
			(xy 74.386752 -28.650692) (xy 74.533731 -28.5108) (xy 74.686122 -28.376824) (xy 74.843687 -28.248972)
			(xy 75.00618 -28.127446) (xy 75.173347 -28.012433) (xy 75.344927 -27.904115) (xy 75.520652 -27.80266)
			(xy 75.700249 -27.708226) (xy 75.883436 -27.620961) (xy 76.069928 -27.541002) (xy 76.259433 -27.468473)
			(xy 76.451655 -27.403487) (xy 76.646295 -27.346145) (xy 76.843048 -27.296538) (xy 77.041607 -27.254743)
			(xy 77.241663 -27.220825) (xy 77.442902 -27.194837) (xy 77.645011 -27.176819) (xy 77.847674 -27.1668)
			(xy 78.050574 -27.164796) (xy 78.253395 -27.170808) (xy 78.455821 -27.184829) (xy 78.657534 -27.206837)
			(xy 78.858221 -27.236796) (xy 79.057567 -27.27466) (xy 79.255262 -27.32037) (xy 79.450996 -27.373854)
			(xy 79.644465 -27.43503) (xy 79.835366 -27.503801) (xy 80.023401 -27.580061) (xy 80.208277 -27.663689)
			(xy 80.389704 -27.754556) (xy 80.5674 -27.852519) (xy 80.741086 -27.957427) (xy 80.910493 -28.069114)
			(xy 81.075355 -28.187406) (xy 81.235415 -28.31212) (xy 81.390423 -28.443059) (xy 81.540137 -28.58002)
			(xy 81.684323 -28.722789) (xy 81.822757 -28.871143) (xy 81.955221 -29.02485) (xy 82.08151 -29.18367)
			(xy 82.201425 -29.347355) (xy 82.314781 -29.51565) (xy 82.421399 -29.688292) (xy 82.521113 -29.865012)
			(xy 82.613768 -30.045532) (xy 82.699218 -30.229572) (xy 82.777332 -30.416845) (xy 82.847985 -30.607057)
			(xy 82.911069 -30.799912) (xy 82.966485 -30.995109) (xy 83.014146 -31.192342) (xy 83.053977 -31.391305)
			(xy 83.085917 -31.591686) (xy 83.109916 -31.793172) (xy 83.125936 -31.995449) (xy 83.133953 -32.198201)
			(xy 83.134454 -32.299656) (xy 83.133953 -32.401111) (xy 83.125936 -32.603863) (xy 83.109916 -32.80614)
			(xy 83.085917 -33.007626) (xy 83.053977 -33.208007) (xy 83.014146 -33.40697) (xy 82.966485 -33.604203)
			(xy 82.911069 -33.7994) (xy 82.847985 -33.992255) (xy 82.777332 -34.182467) (xy 82.699218 -34.36974)
			(xy 82.613768 -34.55378) (xy 82.521113 -34.7343) (xy 82.421399 -34.91102) (xy 82.314781 -35.083662)
			(xy 82.201425 -35.251957) (xy 82.08151 -35.415642) (xy 81.955221 -35.574462) (xy 81.822757 -35.728169)
			(xy 81.684323 -35.876523) (xy 81.540137 -36.019292) (xy 81.390423 -36.156253) (xy 81.235415 -36.287192)
			(xy 81.075355 -36.411906) (xy 80.910493 -36.530198) (xy 80.741086 -36.641885) (xy 80.5674 -36.746793)
			(xy 80.389704 -36.844756) (xy 80.208277 -36.935623) (xy 80.023401 -37.019251) (xy 79.835366 -37.095511)
			(xy 79.644465 -37.164282) (xy 79.450996 -37.225458) (xy 79.255262 -37.278942) (xy 79.057567 -37.324652)
			(xy 78.858221 -37.362516) (xy 78.657534 -37.392475) (xy 78.455821 -37.414483) (xy 78.253395 -37.428504)
			(xy 78.050574 -37.434516) (xy 77.847674 -37.432512) (xy 77.645011 -37.422493) (xy 77.442902 -37.404475)
			(xy 77.241663 -37.378487) (xy 77.041607 -37.344569) (xy 76.843048 -37.302774) (xy 76.646295 -37.253167)
			(xy 76.451655 -37.195825) (xy 76.259433 -37.130839) (xy 76.069928 -37.05831) (xy 75.883436 -36.978351)
			(xy 75.700249 -36.891086) (xy 75.520652 -36.796652) (xy 75.344927 -36.695197) (xy 75.173347 -36.586879)
			(xy 75.00618 -36.471866) (xy 74.843687 -36.35034) (xy 74.686122 -36.222488) (xy 74.533731 -36.088512)
			(xy 74.386752 -35.94862) (xy 74.245415 -35.80303) (xy 74.10994 -35.65197) (xy 73.980538 -35.495676)
			(xy 73.857412 -35.334392) (xy 73.740754 -35.168369) (xy 73.630746 -34.997867) (xy 73.527559 -34.823153)
			(xy 73.431356 -34.644498) (xy 73.342286 -34.462182) (xy 73.260488 -34.276489) (xy 73.18609 -34.08771)
			(xy 73.119208 -33.896139) (xy 73.059947 -33.702075) (xy 73.008398 -33.505822) (xy 72.964644 -33.307685)
			(xy 72.928751 -33.107975) (xy 72.900776 -32.907002) (xy 72.880762 -32.705081) (xy 72.868742 -32.502527)
			(xy 72.864733 -32.299656) (xy 20.846567 -32.299656) (xy 20.805409 -32.356772) (xy 20.679036 -32.51845)
			(xy 20.546451 -32.675075) (xy 20.407856 -32.826407) (xy 20.263462 -32.972217) (xy 20.113489 -33.112282)
			(xy 19.958166 -33.246388) (xy 19.797728 -33.374333) (xy 19.632421 -33.495921) (xy 19.462496 -33.610966)
			(xy 19.288211 -33.719294) (xy 19.109833 -33.82074) (xy 18.927632 -33.915148) (xy 18.741887 -34.002376)
			(xy 18.55288 -34.082291) (xy 18.360899 -34.15477) (xy 18.166236 -34.219704) (xy 17.969188 -34.276994)
			(xy 17.770054 -34.326552) (xy 17.569139 -34.368302) (xy 17.366748 -34.402182) (xy 17.163189 -34.42814)
			(xy 16.958772 -34.446136) (xy 16.753809 -34.456142) (xy 16.548612 -34.458144) (xy 16.343492 -34.452139)
			(xy 16.138763 -34.438135) (xy 15.934737 -34.416154) (xy 15.731723 -34.38623) (xy 15.530031 -34.348407)
			(xy 15.329969 -34.302744) (xy 15.131841 -34.24931) (xy 14.935948 -34.188187) (xy 14.742589 -34.119467)
			(xy 14.552059 -34.043256) (xy 14.364647 -33.959668) (xy 14.180639 -33.868833) (xy 14.000315 -33.770887)
			(xy 13.82395 -33.66598) (xy 13.651812 -33.554272) (xy 13.484164 -33.435933) (xy 13.321261 -33.311143)
			(xy 13.16335 -33.180093) (xy 13.010673 -33.042981) (xy 12.863462 -32.900016) (xy 12.72194 -32.751417)
			(xy 12.586324 -32.597409) (xy 12.456821 -32.438228) (xy 12.333626 -32.274115) (xy 12.216928 -32.10532)
			(xy 12.106905 -31.932101) (xy 12.003724 -31.75472) (xy 11.907542 -31.57345) (xy 11.818506 -31.388564)
			(xy 11.736751 -31.200346) (xy 11.662402 -31.009081) (xy 11.595572 -30.815061) (xy 11.536363 -30.618581)
			(xy 11.484865 -30.419941) (xy 11.441156 -30.219442) (xy 11.405303 -30.017391) (xy 11.377361 -29.814095)
			(xy 11.357371 -29.609864) (xy 11.345365 -29.405008) (xy 11.341362 -29.19984) (xy 1.016 -29.19984)
			(xy 1.016 -34.90976) (xy 6.671831 -34.90976) (xy 6.675786 -34.817923) (xy 6.687621 -34.726766) (xy 6.707248 -34.636963)
			(xy 6.734522 -34.549181) (xy 6.769242 -34.464067) (xy 6.81115 -34.382254) (xy 6.859936 -34.304346)
			(xy 6.915239 -34.230921) (xy 6.976649 -34.162521) (xy 7.043711 -34.099654) (xy 7.11593 -34.042784)
			(xy 7.19277 -33.992333) (xy 7.273663 -33.948674) (xy 7.358009 -33.912131) (xy 7.445185 -33.882974)
			(xy 7.534544 -33.86142) (xy 7.625425 -33.847626) (xy 7.717156 -33.841696) (xy 7.809057 -33.843674)
			(xy 7.900448 -33.853545) (xy 7.990652 -33.871235) (xy 8.079001 -33.896615) (xy 8.164841 -33.929495)
			(xy 8.247537 -33.969633) (xy 8.326477 -34.016732) (xy 8.401075 -34.070442) (xy 8.470781 -34.130366)
			(xy 8.535076 -34.19606) (xy 8.593487 -34.267038) (xy 8.645579 -34.342775) (xy 8.690968 -34.42271)
			(xy 8.729318 -34.50625) (xy 8.760343 -34.592778) (xy 8.783816 -34.681653) (xy 8.799562 -34.772217)
			(xy 8.807464 -34.863799) (xy 8.807958 -34.90976) (xy 8.807464 -34.955721) (xy 8.799562 -35.047303)
			(xy 8.783816 -35.137867) (xy 8.760343 -35.226742) (xy 8.729318 -35.31327) (xy 8.690968 -35.39681)
			(xy 8.645579 -35.476745) (xy 8.593487 -35.552482) (xy 8.535076 -35.62346) (xy 8.470781 -35.689154)
			(xy 8.401075 -35.749078) (xy 8.326477 -35.802788) (xy 8.247537 -35.849887) (xy 8.164841 -35.890025)
			(xy 8.079001 -35.922905) (xy 7.990652 -35.948285) (xy 7.900448 -35.965975) (xy 7.809057 -35.975846)
			(xy 7.717156 -35.977824) (xy 7.625425 -35.971894) (xy 7.534544 -35.9581) (xy 7.445185 -35.936546)
			(xy 7.358009 -35.907389) (xy 7.273663 -35.870846) (xy 7.19277 -35.827187) (xy 7.11593 -35.776736)
			(xy 7.043711 -35.719866) (xy 6.976649 -35.656999) (xy 6.915239 -35.588599) (xy 6.859936 -35.515174)
			(xy 6.81115 -35.437266) (xy 6.769242 -35.355453) (xy 6.734522 -35.270339) (xy 6.707248 -35.182557)
			(xy 6.687621 -35.092754) (xy 6.675786 -35.001597) (xy 6.671831 -34.90976) (xy 1.016 -34.90976) (xy 1.016 -37.771578)
			(xy 1.016492 -37.786921) (xy 1.023881 -37.816707) (xy 1.038164 -37.84387) (xy 1.048004 -37.855652)
			(xy 1.065976 -37.876695) (xy 1.09629 -37.922991) (xy 1.119599 -37.97318) (xy 1.135415 -38.02621)
			(xy 1.143407 -38.080967) (xy 1.143407 -38.136305) (xy 1.135415 -38.191062) (xy 1.119599 -38.244092)
			(xy 1.09629 -38.294281) (xy 1.065976 -38.340577) (xy 1.048004 -38.36162) (xy 1.03813 -38.373379)
			(xy 1.023835 -38.400546) (xy 1.01646 -38.430345) (xy 1.016 -38.445694) (xy 1.016 -42.291) (xy 5.5306 -42.291)
			(xy 5.534631 -42.161434) (xy 5.54671 -42.03237) (xy 5.566789 -41.904306) (xy 5.594791 -41.777739)
			(xy 5.630608 -41.653156) (xy 5.6741 -41.531042) (xy 5.7251 -41.411868) (xy 5.783411 -41.296095) (xy 5.848806 -41.184171)
			(xy 5.921033 -41.076529) (xy 5.999813 -40.973586) (xy 6.08484 -40.87574) (xy 6.175785 -40.783368)
			(xy 6.272297 -40.69683) (xy 6.374003 -40.616459) (xy 6.480509 -40.542567) (xy 6.591402 -40.475439)
			(xy 6.706254 -40.415335) (xy 6.824621 -40.362488) (xy 6.946044 -40.317101) (xy 7.070054 -40.279352)
			(xy 7.196171 -40.249385) (xy 7.323907 -40.227316) (xy 7.452768 -40.213232) (xy 7.582255 -40.207186)
			(xy 7.711868 -40.209202) (xy 7.841104 -40.219272) (xy 7.969465 -40.237357) (xy 8.096453 -40.263387)
			(xy 8.221577 -40.297262) (xy 8.344353 -40.33885) (xy 8.464306 -40.387991) (xy 8.580971 -40.444494)
			(xy 8.693899 -40.508141) (xy 8.802651 -40.578685) (xy 8.906807 -40.655854) (xy 9.005964 -40.739349)
			(xy 9.099738 -40.828847) (xy 9.187767 -40.924002) (xy 9.26971 -41.024445) (xy 9.345249 -41.129788)
			(xy 9.414094 -41.239624) (xy 9.475977 -41.353528) (xy 9.530658 -41.471058) (xy 9.577928 -41.591761)
			(xy 9.617601 -41.715169) (xy 9.649526 -41.840805) (xy 9.673578 -41.968182) (xy 9.689665 -42.096808)
			(xy 9.697724 -42.226186) (xy 9.698228 -42.291) (xy 9.697724 -42.355814) (xy 9.689665 -42.485192)
			(xy 9.673578 -42.613818) (xy 9.649526 -42.741195) (xy 9.617601 -42.866831) (xy 9.577928 -42.990239)
			(xy 9.530658 -43.110942) (xy 9.475977 -43.228472) (xy 9.414094 -43.342376) (xy 9.345249 -43.452212)
			(xy 9.26971 -43.557555) (xy 9.187767 -43.657998) (xy 9.099738 -43.753153) (xy 9.005964 -43.842651)
			(xy 8.906807 -43.926146) (xy 8.802651 -44.003315) (xy 8.693899 -44.073859) (xy 8.580971 -44.137506)
			(xy 8.464306 -44.194009) (xy 8.344353 -44.24315) (xy 8.221577 -44.284738) (xy 8.096453 -44.318613)
			(xy 7.969465 -44.344643) (xy 7.841104 -44.362728) (xy 7.711868 -44.372798) (xy 7.582255 -44.374814)
			(xy 7.452768 -44.368768) (xy 7.323907 -44.354684) (xy 7.196171 -44.332615) (xy 7.070054 -44.302648)
			(xy 6.946044 -44.264899) (xy 6.824621 -44.219512) (xy 6.706254 -44.166665) (xy 6.591402 -44.106561)
			(xy 6.480509 -44.039433) (xy 6.374003 -43.965541) (xy 6.272297 -43.88517) (xy 6.175785 -43.798632)
			(xy 6.08484 -43.70626) (xy 5.999813 -43.608414) (xy 5.921033 -43.505471) (xy 5.848806 -43.397829)
			(xy 5.783411 -43.285905) (xy 5.7251 -43.170132) (xy 5.6741 -43.050958) (xy 5.630608 -42.928844) (xy 5.594791 -42.804261)
			(xy 5.566789 -42.677694) (xy 5.54671 -42.54963) (xy 5.534631 -42.420566) (xy 5.5306 -42.291) (xy 1.016 -42.291)
			(xy 1.016 -50.471578) (xy 1.016492 -50.486921) (xy 1.023881 -50.516707) (xy 1.038164 -50.54387) (xy 1.048004 -50.555652)
			(xy 1.065976 -50.576695) (xy 1.09629 -50.622991) (xy 1.119599 -50.67318) (xy 1.135415 -50.72621)
			(xy 1.143407 -50.780967) (xy 1.143407 -50.836305) (xy 1.135415 -50.891062) (xy 1.119599 -50.944092)
			(xy 1.09629 -50.994281) (xy 1.065976 -51.040577) (xy 1.048004 -51.06162) (xy 1.03813 -51.073379)
			(xy 1.023835 -51.100546) (xy 1.01646 -51.130345) (xy 1.016 -51.145694) (xy 1.016 -51.36007) (xy 39.818564 -51.36007)
			(xy 39.819054 -51.302663) (xy 39.826889 -51.188117) (xy 39.842523 -51.074372) (xy 39.865882 -50.96196)
			(xy 39.896859 -50.851403) (xy 39.935308 -50.743218) (xy 39.98105 -50.63791) (xy 40.033872 -50.535968)
			(xy 40.093527 -50.437869) (xy 40.159738 -50.344069) (xy 40.232196 -50.255007) (xy 40.310562 -50.171096)
			(xy 40.394473 -50.09273) (xy 40.483535 -50.020272) (xy 40.577335 -49.954061) (xy 40.675434 -49.894406)
			(xy 40.777376 -49.841584) (xy 40.882684 -49.795842) (xy 40.990869 -49.757393) (xy 41.101426 -49.726416)
			(xy 41.213838 -49.703057) (xy 41.327583 -49.687423) (xy 41.442129 -49.679588) (xy 41.556943 -49.679588)
			(xy 41.671489 -49.687423) (xy 41.785234 -49.703057) (xy 41.897646 -49.726416) (xy 42.008203 -49.757393)
			(xy 42.116388 -49.795842) (xy 42.221696 -49.841584) (xy 42.323638 -49.894406) (xy 42.421737 -49.954061)
			(xy 42.515537 -50.020272) (xy 42.604599 -50.09273) (xy 42.68851 -50.171096) (xy 42.766876 -50.255007)
			(xy 42.839334 -50.344069) (xy 42.905545 -50.437869) (xy 42.9652 -50.535968) (xy 43.018022 -50.63791)
			(xy 43.063764 -50.743218) (xy 43.102213 -50.851403) (xy 43.13319 -50.96196) (xy 43.156549 -51.074372)
			(xy 43.172183 -51.188117) (xy 43.180018 -51.302663) (xy 43.180508 -51.36007) (xy 43.180381 -51.393251)
			(xy 43.177842 -51.459565) (xy 43.175428 -51.492658) (xy 43.170272 -51.550942) (xy 43.152948 -51.666671)
			(xy 43.127616 -51.780914) (xy 43.094401 -51.893119) (xy 43.053462 -52.002742) (xy 43.004999 -52.109253)
			(xy 42.949245 -52.212135) (xy 42.886471 -52.310891) (xy 42.816981 -52.405042) (xy 42.741111 -52.494132)
			(xy 42.659229 -52.577729) (xy 42.571732 -52.65543) (xy 42.500813 -52.71008) (xy 93.154506 -52.71008)
			(xy 93.158522 -52.59381) (xy 93.170549 -52.478095) (xy 93.190531 -52.363485) (xy 93.218373 -52.250526)
			(xy 93.253942 -52.139758) (xy 93.297068 -52.031707) (xy 93.347545 -51.926889) (xy 93.405134 -51.825804)
			(xy 93.46956 -51.728932) (xy 93.540515 -51.636736) (xy 93.617662 -51.549655) (xy 93.700633 -51.468104)
			(xy 93.789033 -51.392472) (xy 93.88244 -51.323118) (xy 93.980409 -51.260375) (xy 94.082473 -51.204539)
			(xy 94.188147 -51.155878) (xy 94.296926 -51.114624) (xy 94.408291 -51.080973) (xy 94.521714 -51.055085)
			(xy 94.636651 -51.037084) (xy 94.752557 -51.027055) (xy 94.868879 -51.025047) (xy 94.985062 -51.031069)
			(xy 95.100553 -51.045092) (xy 95.214801 -51.06705) (xy 95.327262 -51.096837) (xy 95.4374 -51.134312)
			(xy 95.54469 -51.179297) (xy 95.648621 -51.231576) (xy 95.748697 -51.290901) (xy 95.844443 -51.356989)
			(xy 95.9354 -51.429525) (xy 96.021136 -51.508164) (xy 96.101243 -51.59253) (xy 96.175339 -51.682222)
			(xy 96.243069 -51.776812) (xy 96.304113 -51.87585) (xy 96.358178 -51.978863) (xy 96.405008 -52.08536)
			(xy 96.444379 -52.194835) (xy 96.476103 -52.306765) (xy 96.500029 -52.420617) (xy 96.516043 -52.535849)
			(xy 96.52407 -52.651911) (xy 96.524572 -52.71008) (xy 96.52407 -52.768249) (xy 96.516043 -52.884311)
			(xy 96.500029 -52.999543) (xy 96.476103 -53.113395) (xy 96.444379 -53.225325) (xy 96.405008 -53.3348)
			(xy 96.358178 -53.441297) (xy 96.304113 -53.54431) (xy 96.243069 -53.643348) (xy 96.175339 -53.737938)
			(xy 96.101243 -53.82763) (xy 96.021136 -53.911996) (xy 95.9354 -53.990635) (xy 95.844443 -54.063171)
			(xy 95.748697 -54.129259) (xy 95.648621 -54.188584) (xy 95.54469 -54.240863) (xy 95.4374 -54.285848)
			(xy 95.327262 -54.323323) (xy 95.214801 -54.35311) (xy 95.100553 -54.375068) (xy 94.985062 -54.389091)
			(xy 94.868879 -54.395113) (xy 94.752557 -54.393105) (xy 94.636651 -54.383076) (xy 94.521714 -54.365075)
			(xy 94.408291 -54.339187) (xy 94.296926 -54.305536) (xy 94.188147 -54.264282) (xy 94.082473 -54.215621)
			(xy 93.980409 -54.159785) (xy 93.88244 -54.097042) (xy 93.789033 -54.027688) (xy 93.700633 -53.952056)
			(xy 93.617662 -53.870505) (xy 93.540515 -53.783424) (xy 93.46956 -53.691228) (xy 93.405134 -53.594356)
			(xy 93.347545 -53.493271) (xy 93.297068 -53.388453) (xy 93.253942 -53.280402) (xy 93.218373 -53.169634)
			(xy 93.190531 -53.056675) (xy 93.170549 -52.942065) (xy 93.158522 -52.82635) (xy 93.154506 -52.71008)
			(xy 42.500813 -52.71008) (xy 42.479042 -52.726857) (xy 42.381609 -52.791665) (xy 42.279905 -52.84954)
			(xy 42.174422 -52.900202) (xy 42.065671 -52.943404) (xy 41.954179 -52.978939) (xy 41.840485 -53.006634)
			(xy 41.725141 -53.026354) (xy 41.608704 -53.038005) (xy 41.491739 -53.04153) (xy 41.374812 -53.036912)
			(xy 41.258489 -53.024173) (xy 41.143334 -53.003375) (xy 41.029905 -52.974618) (xy 40.91875 -52.938042)
			(xy 40.810407 -52.893825) (xy 40.705403 -52.842179) (xy 40.604244 -52.783356) (xy 40.507421 -52.71764)
			(xy 40.415403 -52.645349) (xy 40.328636 -52.566834) (xy 40.247539 -52.482474) (xy 40.172506 -52.392679)
			(xy 40.103899 -52.297883) (xy 40.042051 -52.198544) (xy 39.987262 -52.095145) (xy 39.939796 -51.988186)
			(xy 39.899884 -51.878185) (xy 39.86772 -51.765674) (xy 39.843457 -51.651199) (xy 39.827215 -51.535313)
			(xy 39.819072 -51.418579) (xy 39.818564 -51.36007) (xy 1.016 -51.36007) (xy 1.016 -53.721) (xy 5.5306 -53.721)
			(xy 5.534631 -53.591434) (xy 5.54671 -53.46237) (xy 5.566789 -53.334306) (xy 5.594791 -53.207739)
			(xy 5.630608 -53.083156) (xy 5.6741 -52.961042) (xy 5.7251 -52.841868) (xy 5.783411 -52.726095) (xy 5.848806 -52.614171)
			(xy 5.921033 -52.506529) (xy 5.999813 -52.403586) (xy 6.08484 -52.30574) (xy 6.175785 -52.213368)
			(xy 6.272297 -52.12683) (xy 6.374003 -52.046459) (xy 6.480509 -51.972567) (xy 6.591402 -51.905439)
			(xy 6.706254 -51.845335) (xy 6.824621 -51.792488) (xy 6.946044 -51.747101) (xy 7.070054 -51.709352)
			(xy 7.196171 -51.679385) (xy 7.323907 -51.657316) (xy 7.452768 -51.643232) (xy 7.582255 -51.637186)
			(xy 7.711868 -51.639202) (xy 7.841104 -51.649272) (xy 7.969465 -51.667357) (xy 8.096453 -51.693387)
			(xy 8.221577 -51.727262) (xy 8.344353 -51.76885) (xy 8.464306 -51.817991) (xy 8.580971 -51.874494)
			(xy 8.693899 -51.938141) (xy 8.802651 -52.008685) (xy 8.906807 -52.085854) (xy 9.005964 -52.169349)
			(xy 9.099738 -52.258847) (xy 9.187767 -52.354002) (xy 9.26971 -52.454445) (xy 9.345249 -52.559788)
			(xy 9.414094 -52.669624) (xy 9.475977 -52.783528) (xy 9.530658 -52.901058) (xy 9.577928 -53.021761)
			(xy 9.617601 -53.145169) (xy 9.649526 -53.270805) (xy 9.673578 -53.398182) (xy 9.689665 -53.526808)
			(xy 9.697724 -53.656186) (xy 9.698228 -53.721) (xy 9.697724 -53.785814) (xy 9.689665 -53.915192)
			(xy 9.673578 -54.043818) (xy 9.649526 -54.171195) (xy 9.617601 -54.296831) (xy 9.577928 -54.420239)
			(xy 9.530658 -54.540942) (xy 9.475977 -54.658472) (xy 9.414094 -54.772376) (xy 9.345249 -54.882212)
			(xy 9.26971 -54.987555) (xy 9.187767 -55.087998) (xy 9.099738 -55.183153) (xy 9.005964 -55.272651)
			(xy 8.906807 -55.356146) (xy 8.802651 -55.433315) (xy 8.693899 -55.503859) (xy 8.580971 -55.567506)
			(xy 8.464306 -55.624009) (xy 8.344353 -55.67315) (xy 8.221577 -55.714738) (xy 8.096453 -55.748613)
			(xy 7.969465 -55.774643) (xy 7.841104 -55.792728) (xy 7.711868 -55.802798) (xy 7.582255 -55.804814)
			(xy 7.452768 -55.798768) (xy 7.323907 -55.784684) (xy 7.196171 -55.762615) (xy 7.070054 -55.732648)
			(xy 6.946044 -55.694899) (xy 6.824621 -55.649512) (xy 6.706254 -55.596665) (xy 6.591402 -55.536561)
			(xy 6.480509 -55.469433) (xy 6.374003 -55.395541) (xy 6.272297 -55.31517) (xy 6.175785 -55.228632)
			(xy 6.08484 -55.13626) (xy 5.999813 -55.038414) (xy 5.921033 -54.935471) (xy 5.848806 -54.827829)
			(xy 5.783411 -54.715905) (xy 5.7251 -54.600132) (xy 5.6741 -54.480958) (xy 5.630608 -54.358844) (xy 5.594791 -54.234261)
			(xy 5.566789 -54.107694) (xy 5.54671 -53.97963) (xy 5.534631 -53.850566) (xy 5.5306 -53.721) (xy 1.016 -53.721)
			(xy 1.016 -60.833) (xy 5.5306 -60.833) (xy 5.534631 -60.703434) (xy 5.54671 -60.57437) (xy 5.566789 -60.446306)
			(xy 5.594791 -60.319739) (xy 5.630608 -60.195156) (xy 5.6741 -60.073042) (xy 5.7251 -59.953868) (xy 5.783411 -59.838095)
			(xy 5.848806 -59.726171) (xy 5.921033 -59.618529) (xy 5.999813 -59.515586) (xy 6.08484 -59.41774)
			(xy 6.175785 -59.325368) (xy 6.272297 -59.23883) (xy 6.374003 -59.158459) (xy 6.480509 -59.084567)
			(xy 6.591402 -59.017439) (xy 6.706254 -58.957335) (xy 6.824621 -58.904488) (xy 6.946044 -58.859101)
			(xy 7.070054 -58.821352) (xy 7.196171 -58.791385) (xy 7.323907 -58.769316) (xy 7.452768 -58.755232)
			(xy 7.582255 -58.749186) (xy 7.711868 -58.751202) (xy 7.841104 -58.761272) (xy 7.969465 -58.779357)
			(xy 8.096453 -58.805387) (xy 8.221577 -58.839262) (xy 8.344353 -58.88085) (xy 8.464306 -58.929991)
			(xy 8.580971 -58.986494) (xy 8.693899 -59.050141) (xy 8.802651 -59.120685) (xy 8.906807 -59.197854)
			(xy 9.005964 -59.281349) (xy 9.099738 -59.370847) (xy 9.187767 -59.466002) (xy 9.26971 -59.566445)
			(xy 9.345249 -59.671788) (xy 9.414094 -59.781624) (xy 9.475977 -59.895528) (xy 9.530658 -60.013058)
			(xy 9.577928 -60.133761) (xy 9.617601 -60.257169) (xy 9.649526 -60.382805) (xy 9.673578 -60.510182)
			(xy 9.689665 -60.638808) (xy 9.697724 -60.768186) (xy 9.698228 -60.833) (xy 9.697724 -60.897814)
			(xy 9.689665 -61.027192) (xy 9.673578 -61.155818) (xy 9.649526 -61.283195) (xy 9.617601 -61.408831)
			(xy 9.577928 -61.532239) (xy 9.530658 -61.652942) (xy 9.475977 -61.770472) (xy 9.414094 -61.884376)
			(xy 9.345249 -61.994212) (xy 9.26971 -62.099555) (xy 9.187767 -62.199998) (xy 9.099738 -62.295153)
			(xy 9.005964 -62.384651) (xy 8.906807 -62.468146) (xy 8.802651 -62.545315) (xy 8.693899 -62.615859)
			(xy 8.580971 -62.679506) (xy 8.464306 -62.736009) (xy 8.344353 -62.78515) (xy 8.221577 -62.826738)
			(xy 8.096453 -62.860613) (xy 7.969465 -62.886643) (xy 7.841104 -62.904728) (xy 7.711868 -62.914798)
			(xy 7.582255 -62.916814) (xy 7.452768 -62.910768) (xy 7.323907 -62.896684) (xy 7.196171 -62.874615)
			(xy 7.070054 -62.844648) (xy 6.946044 -62.806899) (xy 6.824621 -62.761512) (xy 6.706254 -62.708665)
			(xy 6.591402 -62.648561) (xy 6.480509 -62.581433) (xy 6.374003 -62.507541) (xy 6.272297 -62.42717)
			(xy 6.175785 -62.340632) (xy 6.08484 -62.24826) (xy 5.999813 -62.150414) (xy 5.921033 -62.047471)
			(xy 5.848806 -61.939829) (xy 5.783411 -61.827905) (xy 5.7251 -61.712132) (xy 5.6741 -61.592958) (xy 5.630608 -61.470844)
			(xy 5.594791 -61.346261) (xy 5.566789 -61.219694) (xy 5.54671 -61.09163) (xy 5.534631 -60.962566)
			(xy 5.5306 -60.833) (xy 1.016 -60.833) (xy 1.016 -63.171578) (xy 1.016492 -63.186921) (xy 1.023881 -63.216707)
			(xy 1.038164 -63.24387) (xy 1.048004 -63.255652) (xy 1.065976 -63.276695) (xy 1.09629 -63.322991)
			(xy 1.119599 -63.37318) (xy 1.135415 -63.42621) (xy 1.143407 -63.480967) (xy 1.143407 -63.536305)
			(xy 1.135415 -63.591062) (xy 1.119599 -63.644092) (xy 1.09629 -63.694281) (xy 1.065976 -63.740577)
			(xy 1.048004 -63.76162) (xy 1.03813 -63.773379) (xy 1.023835 -63.800546) (xy 1.01646 -63.830345)
			(xy 1.016 -63.845694) (xy 1.016 -64.46012) (xy 86.877404 -64.46012) (xy 86.881424 -64.269469) (xy 86.893478 -64.079156)
			(xy 86.913544 -63.889521) (xy 86.941587 -63.7009) (xy 86.977556 -63.51363) (xy 87.021388 -63.328042)
			(xy 87.073005 -63.144467) (xy 87.132315 -62.963231) (xy 87.199213 -62.784656) (xy 87.273579 -62.609061)
			(xy 87.355281 -62.436756) (xy 87.444175 -62.268049) (xy 87.540101 -62.103239) (xy 87.64289 -61.94262)
			(xy 87.752359 -61.786477) (xy 87.868313 -61.635088) (xy 87.990547 -61.488721) (xy 88.118841 -61.347637)
			(xy 88.252969 -61.212088) (xy 88.392693 -61.082313) (xy 88.537763 -60.958543) (xy 88.687921 -60.841)
			(xy 88.842902 -60.729891) (xy 89.002429 -60.625414) (xy 89.166218 -60.527755) (xy 89.333978 -60.437088)
			(xy 89.505412 -60.353574) (xy 89.680214 -60.277361) (xy 89.858073 -60.208585) (xy 90.038674 -60.147367)
			(xy 90.221694 -60.093818) (xy 90.40681 -60.048032) (xy 90.593691 -60.01009) (xy 90.782006 -59.980061)
			(xy 90.971419 -59.957996) (xy 91.161593 -59.943937) (xy 91.352192 -59.937907) (xy 91.542875 -59.939917)
			(xy 91.733304 -59.949964) (xy 91.92314 -59.96803) (xy 92.112046 -59.994083) (xy 92.299685 -60.028076)
			(xy 92.485725 -60.069949) (xy 92.669834 -60.119628) (xy 92.851685 -60.177024) (xy 93.030955 -60.242035)
			(xy 93.207325 -60.314546) (xy 93.380481 -60.394427) (xy 93.550116 -60.481537) (xy 93.715928 -60.575721)
			(xy 93.877622 -60.676812) (xy 94.03491 -60.784628) (xy 94.187513 -60.89898) (xy 94.335161 -61.019663)
			(xy 94.477589 -61.146464) (xy 94.614545 -61.279155) (xy 94.745786 -61.417503) (xy 94.871078 -61.56126)
			(xy 94.990198 -61.710171) (xy 95.102934 -61.863972) (xy 95.209087 -62.022388) (xy 95.308467 -62.185139)
			(xy 95.400897 -62.351934) (xy 95.486214 -62.522478) (xy 95.564266 -62.696466) (xy 95.634913 -62.873591)
			(xy 95.698031 -63.053536) (xy 95.753507 -63.235982) (xy 95.801242 -63.420605) (xy 95.841152 -63.607075)
			(xy 95.873165 -63.795063) (xy 95.897225 -63.984233) (xy 95.913288 -64.174249) (xy 95.921327 -64.364773)
			(xy 95.92183 -64.46012) (xy 95.921327 -64.555467) (xy 95.913288 -64.745991) (xy 95.897225 -64.936007)
			(xy 95.873165 -65.125177) (xy 95.841152 -65.313165) (xy 95.801242 -65.499635) (xy 95.753507 -65.684258)
			(xy 95.698031 -65.866704) (xy 95.634913 -66.046649) (xy 95.564266 -66.223774) (xy 95.486214 -66.397762)
			(xy 95.400897 -66.568306) (xy 95.308467 -66.735101) (xy 95.209087 -66.897852) (xy 95.102934 -67.056268)
			(xy 94.990198 -67.210069) (xy 94.871078 -67.35898) (xy 94.745786 -67.502737) (xy 94.614545 -67.641085)
			(xy 94.477589 -67.773776) (xy 94.335161 -67.900577) (xy 94.187513 -68.02126) (xy 94.03491 -68.135612)
			(xy 93.877622 -68.243428) (xy 93.715928 -68.344519) (xy 93.550116 -68.438703) (xy 93.380481 -68.525813)
			(xy 93.207325 -68.605694) (xy 93.030955 -68.678205) (xy 92.851685 -68.743216) (xy 92.669834 -68.800612)
			(xy 92.485725 -68.850291) (xy 92.299685 -68.892164) (xy 92.112046 -68.926157) (xy 91.92314 -68.95221)
			(xy 91.733304 -68.970276) (xy 91.542875 -68.980323) (xy 91.352192 -68.982333) (xy 91.161593 -68.976303)
			(xy 90.971419 -68.962244) (xy 90.782006 -68.940179) (xy 90.593691 -68.91015) (xy 90.40681 -68.872208)
			(xy 90.221694 -68.826422) (xy 90.038674 -68.772873) (xy 89.858073 -68.711655) (xy 89.680214 -68.642879)
			(xy 89.505412 -68.566666) (xy 89.333978 -68.483152) (xy 89.166218 -68.392485) (xy 89.002429 -68.294826)
			(xy 88.842902 -68.190349) (xy 88.687921 -68.07924) (xy 88.537763 -67.961697) (xy 88.392693 -67.837927)
			(xy 88.252969 -67.708152) (xy 88.118841 -67.572603) (xy 87.990547 -67.431519) (xy 87.868313 -67.285152)
			(xy 87.752359 -67.133763) (xy 87.64289 -66.97762) (xy 87.540101 -66.817001) (xy 87.444175 -66.652191)
			(xy 87.355281 -66.483484) (xy 87.273579 -66.311179) (xy 87.199213 -66.135584) (xy 87.132315 -65.957009)
			(xy 87.073005 -65.775773) (xy 87.021388 -65.592198) (xy 86.977556 -65.40661) (xy 86.941587 -65.21934)
			(xy 86.913544 -65.030719) (xy 86.893478 -64.841084) (xy 86.881424 -64.650771) (xy 86.877404 -64.46012)
			(xy 1.016 -64.46012) (xy 1.016 -72.263) (xy 5.5306 -72.263) (xy 5.534631 -72.133434) (xy 5.54671 -72.00437)
			(xy 5.566789 -71.876306) (xy 5.594791 -71.749739) (xy 5.630608 -71.625156) (xy 5.6741 -71.503042)
			(xy 5.7251 -71.383868) (xy 5.783411 -71.268095) (xy 5.848806 -71.156171) (xy 5.921033 -71.048529)
			(xy 5.999813 -70.945586) (xy 6.08484 -70.84774) (xy 6.175785 -70.755368) (xy 6.272297 -70.66883)
			(xy 6.374003 -70.588459) (xy 6.480509 -70.514567) (xy 6.591402 -70.447439) (xy 6.706254 -70.387335)
			(xy 6.824621 -70.334488) (xy 6.946044 -70.289101) (xy 7.070054 -70.251352) (xy 7.196171 -70.221385)
			(xy 7.323907 -70.199316) (xy 7.452768 -70.185232) (xy 7.582255 -70.179186) (xy 7.711868 -70.181202)
			(xy 7.841104 -70.191272) (xy 7.969465 -70.209357) (xy 8.096453 -70.235387) (xy 8.221577 -70.269262)
			(xy 8.344353 -70.31085) (xy 8.464306 -70.359991) (xy 8.580971 -70.416494) (xy 8.693899 -70.480141)
			(xy 8.802651 -70.550685) (xy 8.906807 -70.627854) (xy 9.005964 -70.711349) (xy 9.099738 -70.800847)
			(xy 9.187767 -70.896002) (xy 9.26971 -70.996445) (xy 9.345249 -71.101788) (xy 9.414094 -71.211624)
			(xy 9.475977 -71.325528) (xy 9.530658 -71.443058) (xy 9.577928 -71.563761) (xy 9.617601 -71.687169)
			(xy 9.649526 -71.812805) (xy 9.673578 -71.940182) (xy 9.689665 -72.068808) (xy 9.697724 -72.198186)
			(xy 9.698228 -72.263) (xy 9.697724 -72.327814) (xy 9.689665 -72.457192) (xy 9.673578 -72.585818)
			(xy 9.649526 -72.713195) (xy 9.617601 -72.838831) (xy 9.577928 -72.962239) (xy 9.530658 -73.082942)
			(xy 9.475977 -73.200472) (xy 9.414094 -73.314376) (xy 9.345249 -73.424212) (xy 9.26971 -73.529555)
			(xy 9.187767 -73.629998) (xy 9.099738 -73.725153) (xy 9.005964 -73.814651) (xy 8.906807 -73.898146)
			(xy 8.802651 -73.975315) (xy 8.693899 -74.045859) (xy 8.580971 -74.109506) (xy 8.464306 -74.166009)
			(xy 8.344353 -74.21515) (xy 8.221577 -74.256738) (xy 8.096453 -74.290613) (xy 7.969465 -74.316643)
			(xy 7.841104 -74.334728) (xy 7.711868 -74.344798) (xy 7.582255 -74.346814) (xy 7.452768 -74.340768)
			(xy 7.323907 -74.326684) (xy 7.196171 -74.304615) (xy 7.070054 -74.274648) (xy 6.946044 -74.236899)
			(xy 6.824621 -74.191512) (xy 6.706254 -74.138665) (xy 6.591402 -74.078561) (xy 6.480509 -74.011433)
			(xy 6.374003 -73.937541) (xy 6.272297 -73.85717) (xy 6.175785 -73.770632) (xy 6.08484 -73.67826)
			(xy 5.999813 -73.580414) (xy 5.921033 -73.477471) (xy 5.848806 -73.369829) (xy 5.783411 -73.257905)
			(xy 5.7251 -73.142132) (xy 5.6741 -73.022958) (xy 5.630608 -72.900844) (xy 5.594791 -72.776261) (xy 5.566789 -72.649694)
			(xy 5.54671 -72.52163) (xy 5.534631 -72.392566) (xy 5.5306 -72.263) (xy 1.016 -72.263) (xy 1.016 -75.871578)
			(xy 1.016492 -75.886921) (xy 1.023881 -75.916707) (xy 1.038164 -75.94387) (xy 1.048004 -75.955652)
			(xy 1.065976 -75.976695) (xy 1.09629 -76.022991) (xy 1.119599 -76.07318) (xy 1.135415 -76.12621)
			(xy 1.143407 -76.180967) (xy 1.143407 -76.236305) (xy 1.135415 -76.291062) (xy 1.119599 -76.344092)
			(xy 1.09629 -76.394281) (xy 1.065976 -76.440577) (xy 1.048004 -76.46162) (xy 1.03813 -76.473379)
			(xy 1.023835 -76.500546) (xy 1.01646 -76.530345) (xy 1.016 -76.545694) (xy 1.016 -77.476858) (xy 6.601727 -77.476858)
			(xy 6.605682 -77.385021) (xy 6.617517 -77.293864) (xy 6.637144 -77.204061) (xy 6.664418 -77.116279)
			(xy 6.699138 -77.031165) (xy 6.741046 -76.949352) (xy 6.789832 -76.871444) (xy 6.845135 -76.798019)
			(xy 6.906545 -76.729619) (xy 6.973607 -76.666752) (xy 7.045826 -76.609882) (xy 7.122666 -76.559431)
			(xy 7.203559 -76.515772) (xy 7.287905 -76.479229) (xy 7.375081 -76.450072) (xy 7.46444 -76.428518)
			(xy 7.555321 -76.414724) (xy 7.647052 -76.408794) (xy 7.738953 -76.410772) (xy 7.830344 -76.420643)
			(xy 7.920548 -76.438333) (xy 8.008897 -76.463713) (xy 8.094737 -76.496593) (xy 8.177433 -76.536731)
			(xy 8.256373 -76.58383) (xy 8.330971 -76.63754) (xy 8.400677 -76.697464) (xy 8.464972 -76.763158)
			(xy 8.523383 -76.834136) (xy 8.575475 -76.909873) (xy 8.620864 -76.989808) (xy 8.659214 -77.073348)
			(xy 8.690239 -77.159876) (xy 8.713712 -77.248751) (xy 8.729458 -77.339315) (xy 8.73736 -77.430897)
			(xy 8.737854 -77.476858) (xy 8.73736 -77.522819) (xy 8.729458 -77.614401) (xy 8.713712 -77.704965)
			(xy 8.690239 -77.79384) (xy 8.659214 -77.880368) (xy 8.620864 -77.963908) (xy 8.575475 -78.043843)
			(xy 8.523383 -78.11958) (xy 8.464972 -78.190558) (xy 8.400677 -78.256252) (xy 8.330971 -78.316176)
			(xy 8.256373 -78.369886) (xy 8.241646 -78.378673) (xy 74.888081 -78.378673) (xy 74.888081 -78.220963)
			(xy 74.896069 -78.063456) (xy 74.912025 -77.906556) (xy 74.935906 -77.750665) (xy 74.967653 -77.596184)
			(xy 75.007183 -77.443509) (xy 75.054395 -77.293033) (xy 75.109169 -77.14514) (xy 75.171362 -77.000212)
			(xy 75.240817 -76.85862) (xy 75.317353 -76.720727) (xy 75.400776 -76.586888) (xy 75.49087 -76.457446)
			(xy 75.587405 -76.332733) (xy 75.690133 -76.21307) (xy 75.798789 -76.098763) (xy 75.913096 -75.990107)
			(xy 76.032759 -75.887379) (xy 76.157472 -75.790844) (xy 76.286914 -75.70075) (xy 76.420753 -75.617327)
			(xy 76.558646 -75.540791) (xy 76.700238 -75.471336) (xy 76.845166 -75.409143) (xy 76.993059 -75.354369)
			(xy 77.143535 -75.307157) (xy 77.29621 -75.267627) (xy 77.450691 -75.23588) (xy 77.606582 -75.211999)
			(xy 77.763482 -75.196043) (xy 77.920989 -75.188055) (xy 78.078699 -75.188055) (xy 78.236206 -75.196043)
			(xy 78.393106 -75.211999) (xy 78.548997 -75.23588) (xy 78.703478 -75.267627) (xy 78.856153 -75.307157)
			(xy 79.006629 -75.354369) (xy 79.154522 -75.409143) (xy 79.29945 -75.471336) (xy 79.441042 -75.540791)
			(xy 79.578935 -75.617327) (xy 79.712774 -75.70075) (xy 79.842216 -75.790844) (xy 79.966929 -75.887379)
			(xy 80.086592 -75.990107) (xy 80.200899 -76.098763) (xy 80.309555 -76.21307) (xy 80.412283 -76.332733)
			(xy 80.508818 -76.457446) (xy 80.598912 -76.586888) (xy 80.682335 -76.720727) (xy 80.758871 -76.85862)
			(xy 80.828326 -77.000212) (xy 80.890519 -77.14514) (xy 80.945293 -77.293033) (xy 80.992505 -77.443509)
			(xy 81.032035 -77.596184) (xy 81.063782 -77.750665) (xy 81.087663 -77.906556) (xy 81.103619 -78.063456)
			(xy 81.111607 -78.220963) (xy 81.112106 -78.299818) (xy 81.111607 -78.378673) (xy 81.103619 -78.53618)
			(xy 81.087663 -78.69308) (xy 81.063782 -78.848971) (xy 81.032035 -79.003452) (xy 80.992505 -79.156127)
			(xy 80.945293 -79.306603) (xy 80.890519 -79.454496) (xy 80.828326 -79.599424) (xy 80.758871 -79.741016)
			(xy 80.682335 -79.878909) (xy 80.598912 -80.012748) (xy 80.508818 -80.14219) (xy 80.412283 -80.266903)
			(xy 80.309555 -80.386566) (xy 80.200899 -80.500873) (xy 80.086592 -80.609529) (xy 79.966929 -80.712257)
			(xy 79.842216 -80.808792) (xy 79.712774 -80.898886) (xy 79.578935 -80.982309) (xy 79.441042 -81.058845)
			(xy 79.29945 -81.1283) (xy 79.154522 -81.190493) (xy 79.006629 -81.245267) (xy 78.856153 -81.292479)
			(xy 78.703478 -81.332009) (xy 78.548997 -81.363756) (xy 78.393106 -81.387637) (xy 78.236206 -81.403593)
			(xy 78.078699 -81.411581) (xy 77.920989 -81.411581) (xy 77.763482 -81.403593) (xy 77.606582 -81.387637)
			(xy 77.450691 -81.363756) (xy 77.29621 -81.332009) (xy 77.143535 -81.292479) (xy 76.993059 -81.245267)
			(xy 76.845166 -81.190493) (xy 76.700238 -81.1283) (xy 76.558646 -81.058845) (xy 76.420753 -80.982309)
			(xy 76.286914 -80.898886) (xy 76.157472 -80.808792) (xy 76.032759 -80.712257) (xy 75.913096 -80.609529)
			(xy 75.798789 -80.500873) (xy 75.690133 -80.386566) (xy 75.587405 -80.266903) (xy 75.49087 -80.14219)
			(xy 75.400776 -80.012748) (xy 75.317353 -79.878909) (xy 75.240817 -79.741016) (xy 75.171362 -79.599424)
			(xy 75.109169 -79.454496) (xy 75.054395 -79.306603) (xy 75.007183 -79.156127) (xy 74.967653 -79.003452)
			(xy 74.935906 -78.848971) (xy 74.912025 -78.69308) (xy 74.896069 -78.53618) (xy 74.888081 -78.378673)
			(xy 8.241646 -78.378673) (xy 8.177433 -78.416985) (xy 8.094737 -78.457123) (xy 8.008897 -78.490003)
			(xy 7.920548 -78.515383) (xy 7.830344 -78.533073) (xy 7.738953 -78.542944) (xy 7.647052 -78.544922)
			(xy 7.555321 -78.538992) (xy 7.46444 -78.525198) (xy 7.375081 -78.503644) (xy 7.287905 -78.474487)
			(xy 7.203559 -78.437944) (xy 7.122666 -78.394285) (xy 7.045826 -78.343834) (xy 6.973607 -78.286964)
			(xy 6.906545 -78.224097) (xy 6.845135 -78.155697) (xy 6.789832 -78.082272) (xy 6.741046 -78.004364)
			(xy 6.699138 -77.922551) (xy 6.664418 -77.837437) (xy 6.637144 -77.749655) (xy 6.617517 -77.659852)
			(xy 6.605682 -77.568695) (xy 6.601727 -77.476858) (xy 1.016 -77.476858) (xy 1.016 -88.571578) (xy 1.016492 -88.586921)
			(xy 1.023881 -88.616707) (xy 1.038164 -88.64387) (xy 1.048004 -88.655652) (xy 1.065976 -88.676695)
			(xy 1.09629 -88.722991) (xy 1.119599 -88.77318) (xy 1.135415 -88.82621) (xy 1.143407 -88.880967)
			(xy 1.143407 -88.936305) (xy 1.135415 -88.991062) (xy 1.119599 -89.044092) (xy 1.09629 -89.094281)
			(xy 1.065976 -89.140577) (xy 1.048004 -89.16162) (xy 1.03813 -89.173379) (xy 1.023835 -89.200546)
			(xy 1.01646 -89.230345) (xy 1.016 -89.245694) (xy 1.016 -89.476834) (xy 6.601727 -89.476834) (xy 6.605682 -89.384997)
			(xy 6.617517 -89.29384) (xy 6.637144 -89.204037) (xy 6.664418 -89.116255) (xy 6.699138 -89.031141)
			(xy 6.741046 -88.949328) (xy 6.789832 -88.87142) (xy 6.845135 -88.797995) (xy 6.906545 -88.729595)
			(xy 6.973607 -88.666728) (xy 7.045826 -88.609858) (xy 7.122666 -88.559407) (xy 7.203559 -88.515748)
			(xy 7.287905 -88.479205) (xy 7.375081 -88.450048) (xy 7.46444 -88.428494) (xy 7.555321 -88.4147)
			(xy 7.647052 -88.40877) (xy 7.738953 -88.410748) (xy 7.830344 -88.420619) (xy 7.920548 -88.438309)
			(xy 8.008897 -88.463689) (xy 8.094737 -88.496569) (xy 8.177433 -88.536707) (xy 8.256373 -88.583806)
			(xy 8.330971 -88.637516) (xy 8.400677 -88.69744) (xy 8.464972 -88.763134) (xy 8.523383 -88.834112)
			(xy 8.575475 -88.909849) (xy 8.620864 -88.989784) (xy 8.659214 -89.073324) (xy 8.690239 -89.159852)
			(xy 8.713712 -89.248727) (xy 8.729458 -89.339291) (xy 8.73736 -89.430873) (xy 8.737854 -89.476834)
			(xy 8.73736 -89.522795) (xy 8.729458 -89.614377) (xy 8.713712 -89.704941) (xy 8.690239 -89.793816)
			(xy 8.659214 -89.880344) (xy 8.620864 -89.963884) (xy 8.575475 -90.043819) (xy 8.523383 -90.119556)
			(xy 8.464972 -90.190534) (xy 8.400677 -90.256228) (xy 8.330971 -90.316152) (xy 8.256373 -90.369862)
			(xy 8.177433 -90.416961) (xy 8.094737 -90.457099) (xy 8.008897 -90.489979) (xy 7.920548 -90.515359)
			(xy 7.830344 -90.533049) (xy 7.738953 -90.54292) (xy 7.647052 -90.544898) (xy 7.555321 -90.538968)
			(xy 7.46444 -90.525174) (xy 7.375081 -90.50362) (xy 7.287905 -90.474463) (xy 7.203559 -90.43792)
			(xy 7.122666 -90.394261) (xy 7.045826 -90.34381) (xy 6.973607 -90.28694) (xy 6.906545 -90.224073)
			(xy 6.845135 -90.155673) (xy 6.789832 -90.082248) (xy 6.741046 -90.00434) (xy 6.699138 -89.922527)
			(xy 6.664418 -89.837413) (xy 6.637144 -89.749631) (xy 6.617517 -89.659828) (xy 6.605682 -89.568671)
			(xy 6.601727 -89.476834) (xy 1.016 -89.476834) (xy 1.016 -95.377) (xy 5.5306 -95.377) (xy 5.534631 -95.247434)
			(xy 5.54671 -95.11837) (xy 5.566789 -94.990306) (xy 5.594791 -94.863739) (xy 5.630608 -94.739156)
			(xy 5.6741 -94.617042) (xy 5.7251 -94.497868) (xy 5.783411 -94.382095) (xy 5.848806 -94.270171) (xy 5.921033 -94.162529)
			(xy 5.999813 -94.059586) (xy 6.08484 -93.96174) (xy 6.175785 -93.869368) (xy 6.272297 -93.78283)
			(xy 6.374003 -93.702459) (xy 6.480509 -93.628567) (xy 6.591402 -93.561439) (xy 6.706254 -93.501335)
			(xy 6.824621 -93.448488) (xy 6.946044 -93.403101) (xy 7.070054 -93.365352) (xy 7.196171 -93.335385)
			(xy 7.323907 -93.313316) (xy 7.452768 -93.299232) (xy 7.582255 -93.293186) (xy 7.711868 -93.295202)
			(xy 7.841104 -93.305272) (xy 7.969465 -93.323357) (xy 8.096453 -93.349387) (xy 8.221577 -93.383262)
			(xy 8.344353 -93.42485) (xy 8.464306 -93.473991) (xy 8.580971 -93.530494) (xy 8.693899 -93.594141)
			(xy 8.802651 -93.664685) (xy 8.906807 -93.741854) (xy 9.005964 -93.825349) (xy 9.099738 -93.914847)
			(xy 9.187767 -94.010002) (xy 9.26971 -94.110445) (xy 9.345249 -94.215788) (xy 9.414094 -94.325624)
			(xy 9.475977 -94.439528) (xy 9.530658 -94.557058) (xy 9.577928 -94.677761) (xy 9.617601 -94.801169)
			(xy 9.649526 -94.926805) (xy 9.673578 -95.054182) (xy 9.689665 -95.182808) (xy 9.697724 -95.312186)
			(xy 9.698228 -95.377) (xy 9.697724 -95.441814) (xy 9.689665 -95.571192) (xy 9.673578 -95.699818)
			(xy 9.65276 -95.81007) (xy 39.818564 -95.81007) (xy 39.819054 -95.752663) (xy 39.826889 -95.638117)
			(xy 39.842523 -95.524372) (xy 39.865882 -95.41196) (xy 39.896859 -95.301403) (xy 39.935308 -95.193218)
			(xy 39.98105 -95.08791) (xy 40.033872 -94.985968) (xy 40.093527 -94.887869) (xy 40.159738 -94.794069)
			(xy 40.232196 -94.705007) (xy 40.310562 -94.621096) (xy 40.394473 -94.54273) (xy 40.483535 -94.470272)
			(xy 40.577335 -94.404061) (xy 40.675434 -94.344406) (xy 40.777376 -94.291584) (xy 40.882684 -94.245842)
			(xy 40.990869 -94.207393) (xy 41.101426 -94.176416) (xy 41.213838 -94.153057) (xy 41.327583 -94.137423)
			(xy 41.442129 -94.129588) (xy 41.556943 -94.129588) (xy 41.671489 -94.137423) (xy 41.785234 -94.153057)
			(xy 41.897646 -94.176416) (xy 42.008203 -94.207393) (xy 42.116388 -94.245842) (xy 42.221696 -94.291584)
			(xy 42.323638 -94.344406) (xy 42.421737 -94.404061) (xy 42.515537 -94.470272) (xy 42.604599 -94.54273)
			(xy 42.68851 -94.621096) (xy 42.766876 -94.705007) (xy 42.839334 -94.794069) (xy 42.905545 -94.887869)
			(xy 42.9652 -94.985968) (xy 43.018022 -95.08791) (xy 43.063764 -95.193218) (xy 43.102213 -95.301403)
			(xy 43.13319 -95.41196) (xy 43.156549 -95.524372) (xy 43.172183 -95.638117) (xy 43.180018 -95.752663)
			(xy 43.180508 -95.81007) (xy 43.180381 -95.843251) (xy 43.177842 -95.909565) (xy 43.175428 -95.942658)
			(xy 43.170272 -96.000942) (xy 43.152948 -96.116671) (xy 43.127616 -96.230914) (xy 43.094401 -96.343119)
			(xy 43.053462 -96.452742) (xy 43.004999 -96.559253) (xy 42.949245 -96.662135) (xy 42.886471 -96.760891)
			(xy 42.816981 -96.855042) (xy 42.741111 -96.944132) (xy 42.659229 -97.027729) (xy 42.571732 -97.10543)
			(xy 42.500813 -97.16008) (xy 93.154506 -97.16008) (xy 93.158522 -97.04381) (xy 93.170549 -96.928095)
			(xy 93.190531 -96.813485) (xy 93.218373 -96.700526) (xy 93.253942 -96.589758) (xy 93.297068 -96.481707)
			(xy 93.347545 -96.376889) (xy 93.405134 -96.275804) (xy 93.46956 -96.178932) (xy 93.540515 -96.086736)
			(xy 93.617662 -95.999655) (xy 93.700633 -95.918104) (xy 93.789033 -95.842472) (xy 93.88244 -95.773118)
			(xy 93.980409 -95.710375) (xy 94.082473 -95.654539) (xy 94.188147 -95.605878) (xy 94.296926 -95.564624)
			(xy 94.408291 -95.530973) (xy 94.521714 -95.505085) (xy 94.636651 -95.487084) (xy 94.752557 -95.477055)
			(xy 94.868879 -95.475047) (xy 94.985062 -95.481069) (xy 95.100553 -95.495092) (xy 95.214801 -95.51705)
			(xy 95.327262 -95.546837) (xy 95.4374 -95.584312) (xy 95.54469 -95.629297) (xy 95.648621 -95.681576)
			(xy 95.748697 -95.740901) (xy 95.844443 -95.806989) (xy 95.9354 -95.879525) (xy 96.021136 -95.958164)
			(xy 96.101243 -96.04253) (xy 96.175339 -96.132222) (xy 96.243069 -96.226812) (xy 96.304113 -96.32585)
			(xy 96.358178 -96.428863) (xy 96.405008 -96.53536) (xy 96.444379 -96.644835) (xy 96.476103 -96.756765)
			(xy 96.500029 -96.870617) (xy 96.516043 -96.985849) (xy 96.52407 -97.101911) (xy 96.524572 -97.16008)
			(xy 96.52407 -97.218249) (xy 96.516043 -97.334311) (xy 96.500029 -97.449543) (xy 96.476103 -97.563395)
			(xy 96.444379 -97.675325) (xy 96.405008 -97.7848) (xy 96.358178 -97.891297) (xy 96.304113 -97.99431)
			(xy 96.243069 -98.093348) (xy 96.175339 -98.187938) (xy 96.101243 -98.27763) (xy 96.021136 -98.361996)
			(xy 95.9354 -98.440635) (xy 95.844443 -98.513171) (xy 95.748697 -98.579259) (xy 95.648621 -98.638584)
			(xy 95.54469 -98.690863) (xy 95.4374 -98.735848) (xy 95.327262 -98.773323) (xy 95.214801 -98.80311)
			(xy 95.100553 -98.825068) (xy 94.985062 -98.839091) (xy 94.868879 -98.845113) (xy 94.752557 -98.843105)
			(xy 94.636651 -98.833076) (xy 94.521714 -98.815075) (xy 94.408291 -98.789187) (xy 94.296926 -98.755536)
			(xy 94.188147 -98.714282) (xy 94.082473 -98.665621) (xy 93.980409 -98.609785) (xy 93.88244 -98.547042)
			(xy 93.789033 -98.477688) (xy 93.700633 -98.402056) (xy 93.617662 -98.320505) (xy 93.540515 -98.233424)
			(xy 93.46956 -98.141228) (xy 93.405134 -98.044356) (xy 93.347545 -97.943271) (xy 93.297068 -97.838453)
			(xy 93.253942 -97.730402) (xy 93.218373 -97.619634) (xy 93.190531 -97.506675) (xy 93.170549 -97.392065)
			(xy 93.158522 -97.27635) (xy 93.154506 -97.16008) (xy 42.500813 -97.16008) (xy 42.479042 -97.176857)
			(xy 42.381609 -97.241665) (xy 42.279905 -97.29954) (xy 42.174422 -97.350202) (xy 42.065671 -97.393404)
			(xy 41.954179 -97.428939) (xy 41.840485 -97.456634) (xy 41.725141 -97.476354) (xy 41.608704 -97.488005)
			(xy 41.491739 -97.49153) (xy 41.374812 -97.486912) (xy 41.258489 -97.474173) (xy 41.143334 -97.453375)
			(xy 41.029905 -97.424618) (xy 40.91875 -97.388042) (xy 40.810407 -97.343825) (xy 40.705403 -97.292179)
			(xy 40.604244 -97.233356) (xy 40.507421 -97.16764) (xy 40.415403 -97.095349) (xy 40.328636 -97.016834)
			(xy 40.247539 -96.932474) (xy 40.172506 -96.842679) (xy 40.103899 -96.747883) (xy 40.042051 -96.648544)
			(xy 39.987262 -96.545145) (xy 39.939796 -96.438186) (xy 39.899884 -96.328185) (xy 39.86772 -96.215674)
			(xy 39.843457 -96.101199) (xy 39.827215 -95.985313) (xy 39.819072 -95.868579) (xy 39.818564 -95.81007)
			(xy 9.65276 -95.81007) (xy 9.649526 -95.827195) (xy 9.617601 -95.952831) (xy 9.577928 -96.076239)
			(xy 9.530658 -96.196942) (xy 9.475977 -96.314472) (xy 9.414094 -96.428376) (xy 9.345249 -96.538212)
			(xy 9.26971 -96.643555) (xy 9.187767 -96.743998) (xy 9.099738 -96.839153) (xy 9.005964 -96.928651)
			(xy 8.906807 -97.012146) (xy 8.802651 -97.089315) (xy 8.693899 -97.159859) (xy 8.580971 -97.223506)
			(xy 8.464306 -97.280009) (xy 8.344353 -97.32915) (xy 8.221577 -97.370738) (xy 8.096453 -97.404613)
			(xy 7.969465 -97.430643) (xy 7.841104 -97.448728) (xy 7.711868 -97.458798) (xy 7.582255 -97.460814)
			(xy 7.452768 -97.454768) (xy 7.323907 -97.440684) (xy 7.196171 -97.418615) (xy 7.070054 -97.388648)
			(xy 6.946044 -97.350899) (xy 6.824621 -97.305512) (xy 6.706254 -97.252665) (xy 6.591402 -97.192561)
			(xy 6.480509 -97.125433) (xy 6.374003 -97.051541) (xy 6.272297 -96.97117) (xy 6.175785 -96.884632)
			(xy 6.08484 -96.79226) (xy 5.999813 -96.694414) (xy 5.921033 -96.591471) (xy 5.848806 -96.483829)
			(xy 5.783411 -96.371905) (xy 5.7251 -96.256132) (xy 5.6741 -96.136958) (xy 5.630608 -96.014844) (xy 5.594791 -95.890261)
			(xy 5.566789 -95.763694) (xy 5.54671 -95.63563) (xy 5.534631 -95.506566) (xy 5.5306 -95.377) (xy 1.016 -95.377)
			(xy 1.016 -101.271578) (xy 1.016492 -101.286921) (xy 1.023881 -101.316707) (xy 1.038164 -101.34387)
			(xy 1.048004 -101.355652) (xy 1.065976 -101.376695) (xy 1.09629 -101.422991) (xy 1.119599 -101.47318)
			(xy 1.135415 -101.52621) (xy 1.143407 -101.580967) (xy 1.143407 -101.636305) (xy 1.135415 -101.691062)
			(xy 1.119599 -101.744092) (xy 1.09629 -101.794281) (xy 1.065976 -101.840577) (xy 1.048004 -101.86162)
			(xy 1.03813 -101.873379) (xy 1.023835 -101.900546) (xy 1.01646 -101.930345) (xy 1.016 -101.945694)
			(xy 1.016 -106.807) (xy 5.5306 -106.807) (xy 5.534631 -106.677434) (xy 5.54671 -106.54837) (xy 5.566789 -106.420306)
			(xy 5.594791 -106.293739) (xy 5.630608 -106.169156) (xy 5.6741 -106.047042) (xy 5.7251 -105.927868)
			(xy 5.783411 -105.812095) (xy 5.848806 -105.700171) (xy 5.921033 -105.592529) (xy 5.999813 -105.489586)
			(xy 6.08484 -105.39174) (xy 6.175785 -105.299368) (xy 6.272297 -105.21283) (xy 6.374003 -105.132459)
			(xy 6.480509 -105.058567) (xy 6.591402 -104.991439) (xy 6.706254 -104.931335) (xy 6.824621 -104.878488)
			(xy 6.946044 -104.833101) (xy 7.070054 -104.795352) (xy 7.196171 -104.765385) (xy 7.323907 -104.743316)
			(xy 7.452768 -104.729232) (xy 7.582255 -104.723186) (xy 7.711868 -104.725202) (xy 7.841104 -104.735272)
			(xy 7.969465 -104.753357) (xy 8.096453 -104.779387) (xy 8.221577 -104.813262) (xy 8.344353 -104.85485)
			(xy 8.464306 -104.903991) (xy 8.580971 -104.960494) (xy 8.693899 -105.024141) (xy 8.802651 -105.094685)
			(xy 8.906807 -105.171854) (xy 9.005964 -105.255349) (xy 9.099738 -105.344847) (xy 9.187767 -105.440002)
			(xy 9.26971 -105.540445) (xy 9.345249 -105.645788) (xy 9.414094 -105.755624) (xy 9.475977 -105.869528)
			(xy 9.530658 -105.987058) (xy 9.577928 -106.107761) (xy 9.617601 -106.231169) (xy 9.649526 -106.356805)
			(xy 9.673578 -106.484182) (xy 9.689665 -106.612808) (xy 9.697724 -106.742186) (xy 9.698228 -106.807)
			(xy 9.697724 -106.871814) (xy 9.689665 -107.001192) (xy 9.673578 -107.129818) (xy 9.649526 -107.257195)
			(xy 9.617601 -107.382831) (xy 9.577928 -107.506239) (xy 9.530658 -107.626942) (xy 9.475977 -107.744472)
			(xy 9.414094 -107.858376) (xy 9.345249 -107.968212) (xy 9.26971 -108.073555) (xy 9.187767 -108.173998)
			(xy 9.099738 -108.269153) (xy 9.005964 -108.358651) (xy 8.906807 -108.442146) (xy 8.802651 -108.519315)
			(xy 8.693899 -108.589859) (xy 8.580971 -108.653506) (xy 8.464306 -108.710009) (xy 8.344353 -108.75915)
			(xy 8.221577 -108.800738) (xy 8.096453 -108.834613) (xy 7.969465 -108.860643) (xy 7.841104 -108.878728)
			(xy 7.711868 -108.888798) (xy 7.582255 -108.890814) (xy 7.452768 -108.884768) (xy 7.323907 -108.870684)
			(xy 7.196171 -108.848615) (xy 7.070054 -108.818648) (xy 6.946044 -108.780899) (xy 6.824621 -108.735512)
			(xy 6.706254 -108.682665) (xy 6.591402 -108.622561) (xy 6.480509 -108.555433) (xy 6.374003 -108.481541)
			(xy 6.272297 -108.40117) (xy 6.175785 -108.314632) (xy 6.08484 -108.22226) (xy 5.999813 -108.124414)
			(xy 5.921033 -108.021471) (xy 5.848806 -107.913829) (xy 5.783411 -107.801905) (xy 5.7251 -107.686132)
			(xy 5.6741 -107.566958) (xy 5.630608 -107.444844) (xy 5.594791 -107.320261) (xy 5.566789 -107.193694)
			(xy 5.54671 -107.06563) (xy 5.534631 -106.936566) (xy 5.5306 -106.807) (xy 1.016 -106.807) (xy 1.016 -108.909866)
			(xy 86.877404 -108.909866) (xy 86.881424 -108.719215) (xy 86.893478 -108.528902) (xy 86.913544 -108.339267)
			(xy 86.941587 -108.150646) (xy 86.977556 -107.963376) (xy 87.021388 -107.777788) (xy 87.073005 -107.594213)
			(xy 87.132315 -107.412977) (xy 87.199213 -107.234402) (xy 87.273579 -107.058807) (xy 87.355281 -106.886502)
			(xy 87.444175 -106.717795) (xy 87.540101 -106.552985) (xy 87.64289 -106.392366) (xy 87.752359 -106.236223)
			(xy 87.868313 -106.084834) (xy 87.990547 -105.938467) (xy 88.118841 -105.797383) (xy 88.252969 -105.661834)
			(xy 88.392693 -105.532059) (xy 88.537763 -105.408289) (xy 88.687921 -105.290746) (xy 88.842902 -105.179637)
			(xy 89.002429 -105.07516) (xy 89.166218 -104.977501) (xy 89.333978 -104.886834) (xy 89.505412 -104.80332)
			(xy 89.680214 -104.727107) (xy 89.858073 -104.658331) (xy 90.038674 -104.597113) (xy 90.221694 -104.543564)
			(xy 90.40681 -104.497778) (xy 90.593691 -104.459836) (xy 90.782006 -104.429807) (xy 90.971419 -104.407742)
			(xy 91.161593 -104.393683) (xy 91.352192 -104.387653) (xy 91.542875 -104.389663) (xy 91.733304 -104.39971)
			(xy 91.92314 -104.417776) (xy 92.112046 -104.443829) (xy 92.299685 -104.477822) (xy 92.485725 -104.519695)
			(xy 92.669834 -104.569374) (xy 92.851685 -104.62677) (xy 93.030955 -104.691781) (xy 93.207325 -104.764292)
			(xy 93.380481 -104.844173) (xy 93.550116 -104.931283) (xy 93.715928 -105.025467) (xy 93.877622 -105.126558)
			(xy 94.03491 -105.234374) (xy 94.187513 -105.348726) (xy 94.335161 -105.469409) (xy 94.477589 -105.59621)
			(xy 94.614545 -105.728901) (xy 94.745786 -105.867249) (xy 94.871078 -106.011006) (xy 94.990198 -106.159917)
			(xy 95.102934 -106.313718) (xy 95.209087 -106.472134) (xy 95.308467 -106.634885) (xy 95.400897 -106.80168)
			(xy 95.486214 -106.972224) (xy 95.564266 -107.146212) (xy 95.634913 -107.323337) (xy 95.698031 -107.503282)
			(xy 95.753507 -107.685728) (xy 95.801242 -107.870351) (xy 95.841152 -108.056821) (xy 95.873165 -108.244809)
			(xy 95.897225 -108.433979) (xy 95.913288 -108.623995) (xy 95.921327 -108.814519) (xy 95.92183 -108.909866)
			(xy 95.921327 -109.005213) (xy 95.913288 -109.195737) (xy 95.897225 -109.385753) (xy 95.873165 -109.574923)
			(xy 95.841152 -109.762911) (xy 95.801242 -109.949381) (xy 95.753507 -110.134004) (xy 95.698031 -110.31645)
			(xy 95.634913 -110.496395) (xy 95.564266 -110.67352) (xy 95.486214 -110.847508) (xy 95.400897 -111.018052)
			(xy 95.308467 -111.184847) (xy 95.209087 -111.347598) (xy 95.102934 -111.506014) (xy 94.990198 -111.659815)
			(xy 94.871078 -111.808726) (xy 94.745786 -111.952483) (xy 94.614545 -112.090831) (xy 94.477589 -112.223522)
			(xy 94.335161 -112.350323) (xy 94.187513 -112.471006) (xy 94.03491 -112.585358) (xy 93.877622 -112.693174)
			(xy 93.715928 -112.794265) (xy 93.550116 -112.888449) (xy 93.380481 -112.975559) (xy 93.207325 -113.05544)
			(xy 93.030955 -113.127951) (xy 92.851685 -113.192962) (xy 92.669834 -113.250358) (xy 92.485725 -113.300037)
			(xy 92.299685 -113.34191) (xy 92.112046 -113.375903) (xy 91.92314 -113.401956) (xy 91.733304 -113.420022)
			(xy 91.542875 -113.430069) (xy 91.352192 -113.432079) (xy 91.161593 -113.426049) (xy 90.971419 -113.41199)
			(xy 90.782006 -113.389925) (xy 90.593691 -113.359896) (xy 90.40681 -113.321954) (xy 90.221694 -113.276168)
			(xy 90.038674 -113.222619) (xy 89.858073 -113.161401) (xy 89.680214 -113.092625) (xy 89.505412 -113.016412)
			(xy 89.333978 -112.932898) (xy 89.166218 -112.842231) (xy 89.002429 -112.744572) (xy 88.842902 -112.640095)
			(xy 88.687921 -112.528986) (xy 88.537763 -112.411443) (xy 88.392693 -112.287673) (xy 88.252969 -112.157898)
			(xy 88.118841 -112.022349) (xy 87.990547 -111.881265) (xy 87.868313 -111.734898) (xy 87.752359 -111.583509)
			(xy 87.64289 -111.427366) (xy 87.540101 -111.266747) (xy 87.444175 -111.101937) (xy 87.355281 -110.93323)
			(xy 87.273579 -110.760925) (xy 87.199213 -110.58533) (xy 87.132315 -110.406755) (xy 87.073005 -110.225519)
			(xy 87.021388 -110.041944) (xy 86.977556 -109.856356) (xy 86.941587 -109.669086) (xy 86.913544 -109.480465)
			(xy 86.893478 -109.29083) (xy 86.881424 -109.100517) (xy 86.877404 -108.909866) (xy 1.016 -108.909866)
			(xy 1.016 -113.971578) (xy 1.016492 -113.986921) (xy 1.023881 -114.016707) (xy 1.038164 -114.04387)
			(xy 1.048004 -114.055652) (xy 1.065976 -114.076695) (xy 1.09629 -114.122991) (xy 1.119599 -114.17318)
			(xy 1.135415 -114.22621) (xy 1.143407 -114.280967) (xy 1.143407 -114.336305) (xy 1.135415 -114.391062)
			(xy 1.119599 -114.444092) (xy 1.09629 -114.494281) (xy 1.065976 -114.540577) (xy 1.048004 -114.56162)
			(xy 1.03813 -114.573379) (xy 1.023835 -114.600546) (xy 1.01646 -114.630345) (xy 1.016 -114.645694)
			(xy 1.016 -118.09984) (xy 11.34441 -118.09984) (xy 11.348411 -117.894791) (xy 11.36041 -117.690054)
			(xy 11.380388 -117.485941) (xy 11.408314 -117.282762) (xy 11.444146 -117.080829) (xy 11.48783 -116.880446)
			(xy 11.539298 -116.681921) (xy 11.598473 -116.485555) (xy 11.665264 -116.291648) (xy 11.73957 -116.100494)
			(xy 11.821277 -115.912384) (xy 11.910262 -115.727606) (xy 12.006388 -115.54644) (xy 12.109509 -115.369163)
			(xy 12.219469 -115.196044) (xy 12.336099 -115.027347) (xy 12.459222 -114.863329) (xy 12.588651 -114.70424)
			(xy 12.724188 -114.550322) (xy 12.865627 -114.401808) (xy 13.012754 -114.258927) (xy 13.165342 -114.121894)
			(xy 13.323161 -113.99092) (xy 13.48597 -113.866202) (xy 13.653521 -113.747932) (xy 13.825559 -113.636288)
			(xy 14.001822 -113.531442) (xy 14.182041 -113.433553) (xy 14.365942 -113.34277) (xy 14.553246 -113.259232)
			(xy 14.743666 -113.183064) (xy 14.936912 -113.114384) (xy 15.132692 -113.053296) (xy 15.330705 -112.999894)
			(xy 15.530652 -112.954257) (xy 15.732226 -112.916457) (xy 15.935122 -112.886549) (xy 16.139031 -112.864581)
			(xy 16.343641 -112.850586) (xy 16.548641 -112.844584) (xy 16.75372 -112.846585) (xy 16.958564 -112.856585)
			(xy 17.162863 -112.874571) (xy 17.366304 -112.900513) (xy 17.568577 -112.934374) (xy 17.769376 -112.9761)
			(xy 17.968394 -113.025629) (xy 18.165328 -113.082885) (xy 18.359878 -113.147782) (xy 18.551748 -113.220219)
			(xy 18.740645 -113.300087) (xy 18.926283 -113.387265) (xy 19.108378 -113.481619) (xy 19.286653 -113.583006)
			(xy 19.460836 -113.691271) (xy 19.630663 -113.806249) (xy 19.795875 -113.927767) (xy 19.956219 -114.055637)
			(xy 20.111453 -114.189666) (xy 20.261339 -114.32965) (xy 20.405649 -114.475375) (xy 20.544163 -114.62662)
			(xy 20.676672 -114.783153) (xy 20.802972 -114.944738) (xy 20.922871 -115.111127) (xy 21.036188 -115.282067)
			(xy 21.142748 -115.457299) (xy 21.242391 -115.636554) (xy 21.334964 -115.819561) (xy 21.420326 -116.00604)
			(xy 21.498347 -116.195708) (xy 21.56891 -116.388276) (xy 21.631905 -116.58345) (xy 21.687237 -116.780933)
			(xy 21.734822 -116.980424) (xy 21.774587 -117.181621) (xy 21.806472 -117.384215) (xy 21.830429 -117.5879)
			(xy 21.84642 -117.792364) (xy 21.854422 -117.997296) (xy 21.854922 -118.09984) (xy 21.854422 -118.202384)
			(xy 21.84642 -118.407316) (xy 21.830429 -118.61178) (xy 21.806472 -118.815465) (xy 21.774587 -119.018059)
			(xy 21.734822 -119.219256) (xy 21.687237 -119.418747) (xy 21.631905 -119.61623) (xy 21.56891 -119.811404)
			(xy 21.498347 -120.003972) (xy 21.420326 -120.19364) (xy 21.334964 -120.380119) (xy 21.242391 -120.563126)
			(xy 21.142748 -120.742381) (xy 21.036188 -120.917613) (xy 20.922871 -121.088553) (xy 20.842811 -121.199656)
			(xy 72.865241 -121.199656) (xy 72.86925 -120.996785) (xy 72.88127 -120.794231) (xy 72.901284 -120.59231)
			(xy 72.929259 -120.391337) (xy 72.965152 -120.191627) (xy 73.008906 -119.99349) (xy 73.060455 -119.797237)
			(xy 73.119716 -119.603173) (xy 73.186598 -119.411602) (xy 73.260996 -119.222823) (xy 73.342794 -119.03713)
			(xy 73.431864 -118.854814) (xy 73.528067 -118.676159) (xy 73.631254 -118.501445) (xy 73.741262 -118.330943)
			(xy 73.85792 -118.16492) (xy 73.981046 -118.003636) (xy 74.110448 -117.847342) (xy 74.245923 -117.696282)
			(xy 74.38726 -117.550692) (xy 74.534239 -117.4108) (xy 74.68663 -117.276824) (xy 74.844195 -117.148972)
			(xy 75.006688 -117.027446) (xy 75.173855 -116.912433) (xy 75.345435 -116.804115) (xy 75.52116 -116.70266)
			(xy 75.700757 -116.608226) (xy 75.883944 -116.520961) (xy 76.070436 -116.441002) (xy 76.259941 -116.368473)
			(xy 76.452163 -116.303487) (xy 76.646803 -116.246145) (xy 76.843556 -116.196538) (xy 77.042115 -116.154743)
			(xy 77.242171 -116.120825) (xy 77.44341 -116.094837) (xy 77.645519 -116.076819) (xy 77.848182 -116.0668)
			(xy 78.051082 -116.064796) (xy 78.253903 -116.070808) (xy 78.456329 -116.084829) (xy 78.658042 -116.106837)
			(xy 78.858729 -116.136796) (xy 79.058075 -116.17466) (xy 79.25577 -116.22037) (xy 79.451504 -116.273854)
			(xy 79.644973 -116.33503) (xy 79.835874 -116.403801) (xy 80.023909 -116.480061) (xy 80.208785 -116.563689)
			(xy 80.390212 -116.654556) (xy 80.567908 -116.752519) (xy 80.741594 -116.857427) (xy 80.911001 -116.969114)
			(xy 81.075863 -117.087406) (xy 81.235923 -117.21212) (xy 81.390931 -117.343059) (xy 81.540645 -117.48002)
			(xy 81.684831 -117.622789) (xy 81.823265 -117.771143) (xy 81.955729 -117.92485) (xy 82.082018 -118.08367)
			(xy 82.201933 -118.247355) (xy 82.315289 -118.41565) (xy 82.421907 -118.588292) (xy 82.521621 -118.765012)
			(xy 82.614276 -118.945532) (xy 82.699726 -119.129572) (xy 82.77784 -119.316845) (xy 82.848493 -119.507057)
			(xy 82.911577 -119.699912) (xy 82.966993 -119.895109) (xy 83.014654 -120.092342) (xy 83.054485 -120.291305)
			(xy 83.086425 -120.491686) (xy 83.110424 -120.693172) (xy 83.126444 -120.895449) (xy 83.134461 -121.098201)
			(xy 83.134962 -121.199656) (xy 83.134461 -121.301111) (xy 83.126444 -121.503863) (xy 83.110424 -121.70614)
			(xy 83.086425 -121.907626) (xy 83.054485 -122.108007) (xy 83.014654 -122.30697) (xy 82.966993 -122.504203)
			(xy 82.911577 -122.6994) (xy 82.848493 -122.892255) (xy 82.77784 -123.082467) (xy 82.699726 -123.26974)
			(xy 82.614276 -123.45378) (xy 82.521621 -123.6343) (xy 82.421907 -123.81102) (xy 82.315289 -123.983662)
			(xy 82.201933 -124.151957) (xy 82.082018 -124.315642) (xy 81.955729 -124.474462) (xy 81.823265 -124.628169)
			(xy 81.684831 -124.776523) (xy 81.540645 -124.919292) (xy 81.390931 -125.056253) (xy 81.235923 -125.187192)
			(xy 81.075863 -125.311906) (xy 80.911001 -125.430198) (xy 80.741594 -125.541885) (xy 80.567908 -125.646793)
			(xy 80.390212 -125.744756) (xy 80.208785 -125.835623) (xy 80.023909 -125.919251) (xy 79.835874 -125.995511)
			(xy 79.644973 -126.064282) (xy 79.451504 -126.125458) (xy 79.25577 -126.178942) (xy 79.058075 -126.224652)
			(xy 78.858729 -126.262516) (xy 78.658042 -126.292475) (xy 78.456329 -126.314483) (xy 78.253903 -126.328504)
			(xy 78.051082 -126.334516) (xy 77.848182 -126.332512) (xy 77.645519 -126.322493) (xy 77.44341 -126.304475)
			(xy 77.242171 -126.278487) (xy 77.042115 -126.244569) (xy 76.843556 -126.202774) (xy 76.646803 -126.153167)
			(xy 76.452163 -126.095825) (xy 76.259941 -126.030839) (xy 76.070436 -125.95831) (xy 75.883944 -125.878351)
			(xy 75.700757 -125.791086) (xy 75.52116 -125.696652) (xy 75.345435 -125.595197) (xy 75.173855 -125.486879)
			(xy 75.006688 -125.371866) (xy 74.844195 -125.25034) (xy 74.68663 -125.122488) (xy 74.534239 -124.988512)
			(xy 74.38726 -124.84862) (xy 74.245923 -124.70303) (xy 74.110448 -124.55197) (xy 73.981046 -124.395676)
			(xy 73.85792 -124.234392) (xy 73.741262 -124.068369) (xy 73.631254 -123.897867) (xy 73.528067 -123.723153)
			(xy 73.431864 -123.544498) (xy 73.342794 -123.362182) (xy 73.260996 -123.176489) (xy 73.186598 -122.98771)
			(xy 73.119716 -122.796139) (xy 73.060455 -122.602075) (xy 73.008906 -122.405822) (xy 72.965152 -122.207685)
			(xy 72.929259 -122.007975) (xy 72.901284 -121.807002) (xy 72.88127 -121.605081) (xy 72.86925 -121.402527)
			(xy 72.865241 -121.199656) (xy 20.842811 -121.199656) (xy 20.802972 -121.254942) (xy 20.676672 -121.416527)
			(xy 20.544163 -121.57306) (xy 20.405649 -121.724305) (xy 20.261339 -121.87003) (xy 20.111453 -122.010014)
			(xy 19.956219 -122.144043) (xy 19.795875 -122.271913) (xy 19.630663 -122.393431) (xy 19.460836 -122.508409)
			(xy 19.286653 -122.616674) (xy 19.108378 -122.718061) (xy 18.926283 -122.812415) (xy 18.740645 -122.899593)
			(xy 18.551748 -122.979461) (xy 18.359878 -123.051898) (xy 18.165328 -123.116795) (xy 17.968394 -123.174051)
			(xy 17.769376 -123.22358) (xy 17.568577 -123.265306) (xy 17.366304 -123.299167) (xy 17.162863 -123.325109)
			(xy 16.958564 -123.343095) (xy 16.75372 -123.353095) (xy 16.548641 -123.355096) (xy 16.343641 -123.349094)
			(xy 16.139031 -123.335099) (xy 15.935122 -123.313131) (xy 15.732226 -123.283223) (xy 15.530652 -123.245423)
			(xy 15.330705 -123.199786) (xy 15.132692 -123.146384) (xy 14.936912 -123.085296) (xy 14.743666 -123.016616)
			(xy 14.553246 -122.940448) (xy 14.365942 -122.85691) (xy 14.182041 -122.766127) (xy 14.001822 -122.668238)
			(xy 13.825559 -122.563392) (xy 13.653521 -122.451748) (xy 13.48597 -122.333478) (xy 13.323161 -122.20876)
			(xy 13.165342 -122.077786) (xy 13.012754 -121.940753) (xy 12.865627 -121.797872) (xy 12.724188 -121.649358)
			(xy 12.588651 -121.49544) (xy 12.459222 -121.336351) (xy 12.336099 -121.172333) (xy 12.219469 -121.003636)
			(xy 12.109509 -120.830517) (xy 12.006388 -120.65324) (xy 11.910262 -120.472074) (xy 11.821277 -120.287296)
			(xy 11.73957 -120.099186) (xy 11.665264 -119.908032) (xy 11.598473 -119.714125) (xy 11.539298 -119.517759)
			(xy 11.48783 -119.319234) (xy 11.444146 -119.118851) (xy 11.408314 -118.916918) (xy 11.380388 -118.713739)
			(xy 11.36041 -118.509626) (xy 11.348411 -118.304889) (xy 11.34441 -118.09984) (xy 1.016 -118.09984)
			(xy 1.016 -126.671578) (xy 1.016492 -126.686921) (xy 1.023881 -126.716707) (xy 1.038164 -126.74387)
			(xy 1.048004 -126.755652) (xy 1.065976 -126.776695) (xy 1.09629 -126.822991) (xy 1.119599 -126.87318)
			(xy 1.135415 -126.92621) (xy 1.143407 -126.980967) (xy 1.143407 -127.036305) (xy 1.135415 -127.091062)
			(xy 1.119599 -127.144092) (xy 1.09629 -127.194281) (xy 1.065976 -127.240577) (xy 1.048004 -127.26162)
			(xy 1.03813 -127.273379) (xy 1.023835 -127.300546) (xy 1.01646 -127.330345) (xy 1.016 -127.345694)
			(xy 1.016 -130.746068) (xy 5.677649 -130.746068) (xy 5.677649 -130.619932) (xy 5.685569 -130.494044)
			(xy 5.701379 -130.368902) (xy 5.725014 -130.244999) (xy 5.756383 -130.122826) (xy 5.795361 -130.002863)
			(xy 5.841795 -129.885584) (xy 5.895502 -129.771452) (xy 5.956269 -129.660917) (xy 6.023856 -129.554417)
			(xy 6.097997 -129.45237) (xy 6.1784 -129.35518) (xy 6.264746 -129.26323) (xy 6.356696 -129.176884)
			(xy 6.453886 -129.096481) (xy 6.555933 -129.02234) (xy 6.662433 -128.954753) (xy 6.772968 -128.893986)
			(xy 6.8871 -128.840279) (xy 7.004379 -128.793845) (xy 7.124342 -128.754867) (xy 7.246515 -128.723498)
			(xy 7.370418 -128.699863) (xy 7.49556 -128.684053) (xy 7.621448 -128.676133) (xy 7.747584 -128.676133)
			(xy 7.873472 -128.684053) (xy 7.998614 -128.699863) (xy 8.122517 -128.723498) (xy 8.24469 -128.754867)
			(xy 8.364653 -128.793845) (xy 8.481932 -128.840279) (xy 8.596064 -128.893986) (xy 8.706599 -128.954753)
			(xy 8.813099 -129.02234) (xy 8.915146 -129.096481) (xy 9.012336 -129.176884) (xy 9.104286 -129.26323)
			(xy 9.190632 -129.35518) (xy 9.271035 -129.45237) (xy 9.345176 -129.554417) (xy 9.412763 -129.660917)
			(xy 9.47353 -129.771452) (xy 9.527237 -129.885584) (xy 9.573671 -130.002863) (xy 9.612649 -130.122826)
			(xy 9.644018 -130.244999) (xy 9.667653 -130.368902) (xy 9.683463 -130.494044) (xy 9.691383 -130.619932)
			(xy 9.691878 -130.683) (xy 9.691383 -130.746068) (xy 9.683463 -130.871956) (xy 9.667653 -130.997098)
			(xy 9.644018 -131.121001) (xy 9.612649 -131.243174) (xy 9.573671 -131.363137) (xy 9.527237 -131.480416)
			(xy 9.47353 -131.594548) (xy 9.412763 -131.705083) (xy 9.345176 -131.811583) (xy 9.271035 -131.91363)
			(xy 9.190632 -132.01082) (xy 9.104286 -132.10277) (xy 9.012336 -132.189116) (xy 8.915146 -132.269519)
			(xy 8.813099 -132.34366) (xy 8.706599 -132.411247) (xy 8.596064 -132.472014) (xy 8.481932 -132.525721)
			(xy 8.364653 -132.572155) (xy 8.24469 -132.611133) (xy 8.122517 -132.642502) (xy 7.998614 -132.666137)
			(xy 7.873472 -132.681947) (xy 7.747584 -132.689867) (xy 7.621448 -132.689867) (xy 7.49556 -132.681947)
			(xy 7.370418 -132.666137) (xy 7.246515 -132.642502) (xy 7.124342 -132.611133) (xy 7.004379 -132.572155)
			(xy 6.8871 -132.525721) (xy 6.772968 -132.472014) (xy 6.662433 -132.411247) (xy 6.555933 -132.34366)
			(xy 6.453886 -132.269519) (xy 6.356696 -132.189116) (xy 6.264746 -132.10277) (xy 6.1784 -132.01082)
			(xy 6.097997 -131.91363) (xy 6.023856 -131.811583) (xy 5.956269 -131.705083) (xy 5.895502 -131.594548)
			(xy 5.841795 -131.480416) (xy 5.795361 -131.363137) (xy 5.756383 -131.243174) (xy 5.725014 -131.121001)
			(xy 5.701379 -130.997098) (xy 5.685569 -130.871956) (xy 5.677649 -130.746068) (xy 1.016 -130.746068)
			(xy 1.016 -139.371578) (xy 1.016492 -139.386921) (xy 1.023881 -139.416707) (xy 1.038164 -139.44387)
			(xy 1.048004 -139.455652) (xy 1.065976 -139.476695) (xy 1.09629 -139.522991) (xy 1.119599 -139.57318)
			(xy 1.135415 -139.62621) (xy 1.143407 -139.680967) (xy 1.143407 -139.736305) (xy 1.135415 -139.791062)
			(xy 1.119599 -139.844092) (xy 1.09629 -139.894281) (xy 1.065976 -139.940577) (xy 1.048004 -139.96162)
			(xy 1.03813 -139.973379) (xy 1.023835 -140.000546) (xy 1.01646 -140.030345) (xy 1.016 -140.045694)
			(xy 1.016 -142.176068) (xy 5.677649 -142.176068) (xy 5.677649 -142.049932) (xy 5.685569 -141.924044)
			(xy 5.701379 -141.798902) (xy 5.725014 -141.674999) (xy 5.756383 -141.552826) (xy 5.795361 -141.432863)
			(xy 5.841795 -141.315584) (xy 5.895502 -141.201452) (xy 5.956269 -141.090917) (xy 6.023856 -140.984417)
			(xy 6.097997 -140.88237) (xy 6.1784 -140.78518) (xy 6.264746 -140.69323) (xy 6.356696 -140.606884)
			(xy 6.453886 -140.526481) (xy 6.555933 -140.45234) (xy 6.662433 -140.384753) (xy 6.772968 -140.323986)
			(xy 6.8871 -140.270279) (xy 7.004379 -140.223845) (xy 7.124342 -140.184867) (xy 7.246515 -140.153498)
			(xy 7.370418 -140.129863) (xy 7.49556 -140.114053) (xy 7.621448 -140.106133) (xy 7.747584 -140.106133)
			(xy 7.873472 -140.114053) (xy 7.998614 -140.129863) (xy 8.122517 -140.153498) (xy 8.24469 -140.184867)
			(xy 8.364653 -140.223845) (xy 8.441392 -140.254228) (xy 39.818818 -140.254228) (xy 39.819523 -140.195605)
			(xy 39.828091 -140.078667) (xy 39.844787 -139.962611) (xy 39.86953 -139.848001) (xy 39.902199 -139.735393)
			(xy 39.942635 -139.625335) (xy 39.990642 -139.518363) (xy 40.045986 -139.414996) (xy 40.108399 -139.315737)
			(xy 40.177577 -139.221068) (xy 40.253183 -139.13145) (xy 40.334851 -139.047318) (xy 40.422182 -138.969081)
			(xy 40.514753 -138.89712) (xy 40.612113 -138.831784) (xy 40.713789 -138.773392) (xy 40.819288 -138.722226)
			(xy 40.928095 -138.678537) (xy 41.039682 -138.642535) (xy 41.153506 -138.614397) (xy 41.269014 -138.594259)
			(xy 41.385645 -138.582218) (xy 41.502832 -138.578334) (xy 41.620004 -138.582625) (xy 41.736593 -138.595071)
			(xy 41.85203 -138.615611) (xy 41.965756 -138.644144) (xy 42.077217 -138.680533) (xy 42.185872 -138.724601)
			(xy 42.291192 -138.776133) (xy 42.392665 -138.834878) (xy 42.489797 -138.900552) (xy 42.582117 -138.972834)
			(xy 42.669176 -139.051374) (xy 42.750551 -139.135789) (xy 42.825845 -139.225669) (xy 42.894694 -139.320578)
			(xy 42.956761 -139.420054) (xy 43.011746 -139.523612) (xy 43.059381 -139.630751) (xy 43.099434 -139.740948)
			(xy 43.131712 -139.853669) (xy 43.156056 -139.968365) (xy 43.172348 -140.084478) (xy 43.18051 -140.201445)
			(xy 43.181016 -140.26007) (xy 43.180861 -140.290833) (xy 43.178574 -140.352316) (xy 43.176444 -140.383006)
			(xy 43.175682 -140.392404) (xy 43.170622 -140.450806) (xy 43.153396 -140.566771) (xy 43.12813 -140.681253)
			(xy 43.094949 -140.793697) (xy 43.054014 -140.903555) (xy 43.005523 -141.010294) (xy 42.949712 -141.113395)
			(xy 42.886853 -141.212356) (xy 42.817252 -141.306696) (xy 42.741246 -141.395958) (xy 42.659204 -141.479706)
			(xy 42.571527 -141.557535) (xy 42.503292 -141.61008) (xy 93.15476 -141.61008) (xy 93.158776 -141.49381)
			(xy 93.170803 -141.378095) (xy 93.190785 -141.263485) (xy 93.218627 -141.150526) (xy 93.254196 -141.039758)
			(xy 93.297322 -140.931707) (xy 93.347799 -140.826889) (xy 93.405388 -140.725804) (xy 93.469814 -140.628932)
			(xy 93.540769 -140.536736) (xy 93.617916 -140.449655) (xy 93.700887 -140.368104) (xy 93.789287 -140.292472)
			(xy 93.882694 -140.223118) (xy 93.980663 -140.160375) (xy 94.082727 -140.104539) (xy 94.188401 -140.055878)
			(xy 94.29718 -140.014624) (xy 94.408545 -139.980973) (xy 94.521968 -139.955085) (xy 94.636905 -139.937084)
			(xy 94.752811 -139.927055) (xy 94.869133 -139.925047) (xy 94.985316 -139.931069) (xy 95.100807 -139.945092)
			(xy 95.215055 -139.96705) (xy 95.327516 -139.996837) (xy 95.437654 -140.034312) (xy 95.544944 -140.079297)
			(xy 95.648875 -140.131576) (xy 95.748951 -140.190901) (xy 95.844697 -140.256989) (xy 95.935654 -140.329525)
			(xy 96.02139 -140.408164) (xy 96.101497 -140.49253) (xy 96.175593 -140.582222) (xy 96.243323 -140.676812)
			(xy 96.304367 -140.77585) (xy 96.358432 -140.878863) (xy 96.405262 -140.98536) (xy 96.444633 -141.094835)
			(xy 96.476357 -141.206765) (xy 96.500283 -141.320617) (xy 96.516297 -141.435849) (xy 96.524324 -141.551911)
			(xy 96.524826 -141.61008) (xy 96.524324 -141.668249) (xy 96.516297 -141.784311) (xy 96.500283 -141.899543)
			(xy 96.476357 -142.013395) (xy 96.444633 -142.125325) (xy 96.405262 -142.2348) (xy 96.358432 -142.341297)
			(xy 96.304367 -142.44431) (xy 96.243323 -142.543348) (xy 96.175593 -142.637938) (xy 96.101497 -142.72763)
			(xy 96.02139 -142.811996) (xy 95.935654 -142.890635) (xy 95.844697 -142.963171) (xy 95.748951 -143.029259)
			(xy 95.648875 -143.088584) (xy 95.544944 -143.140863) (xy 95.437654 -143.185848) (xy 95.327516 -143.223323)
			(xy 95.215055 -143.25311) (xy 95.100807 -143.275068) (xy 94.985316 -143.289091) (xy 94.869133 -143.295113)
			(xy 94.752811 -143.293105) (xy 94.636905 -143.283076) (xy 94.521968 -143.265075) (xy 94.408545 -143.239187)
			(xy 94.29718 -143.205536) (xy 94.188401 -143.164282) (xy 94.082727 -143.115621) (xy 93.980663 -143.059785)
			(xy 93.882694 -142.997042) (xy 93.789287 -142.927688) (xy 93.700887 -142.852056) (xy 93.617916 -142.770505)
			(xy 93.540769 -142.683424) (xy 93.469814 -142.591228) (xy 93.405388 -142.494356) (xy 93.347799 -142.393271)
			(xy 93.297322 -142.288453) (xy 93.254196 -142.180402) (xy 93.218627 -142.069634) (xy 93.190785 -141.956675)
			(xy 93.170803 -141.842065) (xy 93.158776 -141.72635) (xy 93.15476 -141.61008) (xy 42.503292 -141.61008)
			(xy 42.47864 -141.629064) (xy 42.380994 -141.693948) (xy 42.279065 -141.75187) (xy 42.173347 -141.802549)
			(xy 42.064355 -141.845738) (xy 41.952619 -141.881228) (xy 41.838681 -141.908845) (xy 41.723096 -141.928457)
			(xy 41.606425 -141.939967) (xy 41.489236 -141.943319) (xy 41.372098 -141.938497) (xy 41.25558 -141.925525)
			(xy 41.14025 -141.904466) (xy 41.026668 -141.875421) (xy 40.915385 -141.838533) (xy 40.806943 -141.79398)
			(xy 40.70187 -141.74198) (xy 40.600675 -141.682784) (xy 40.50385 -141.616681) (xy 40.411868 -141.543992)
			(xy 40.325173 -141.46507) (xy 40.244189 -141.380299) (xy 40.169308 -141.290091) (xy 40.100895 -141.194885)
			(xy 40.039282 -141.095143) (xy 39.984769 -140.991351) (xy 39.937621 -140.884012) (xy 39.898066 -140.773649)
			(xy 39.866298 -140.660798) (xy 39.842471 -140.546008) (xy 39.826699 -140.429836) (xy 39.819061 -140.312848)
			(xy 39.818818 -140.254228) (xy 8.441392 -140.254228) (xy 8.481932 -140.270279) (xy 8.596064 -140.323986)
			(xy 8.706599 -140.384753) (xy 8.813099 -140.45234) (xy 8.915146 -140.526481) (xy 9.012336 -140.606884)
			(xy 9.104286 -140.69323) (xy 9.190632 -140.78518) (xy 9.271035 -140.88237) (xy 9.345176 -140.984417)
			(xy 9.412763 -141.090917) (xy 9.47353 -141.201452) (xy 9.527237 -141.315584) (xy 9.573671 -141.432863)
			(xy 9.612649 -141.552826) (xy 9.644018 -141.674999) (xy 9.667653 -141.798902) (xy 9.683463 -141.924044)
			(xy 9.691383 -142.049932) (xy 9.691878 -142.113) (xy 9.691383 -142.176068) (xy 9.683463 -142.301956)
			(xy 9.667653 -142.427098) (xy 9.644018 -142.551001) (xy 9.612649 -142.673174) (xy 9.573671 -142.793137)
			(xy 9.527237 -142.910416) (xy 9.47353 -143.024548) (xy 9.412763 -143.135083) (xy 9.345176 -143.241583)
			(xy 9.271035 -143.34363) (xy 9.190632 -143.44082) (xy 9.104286 -143.53277) (xy 9.012336 -143.619116)
			(xy 8.915146 -143.699519) (xy 8.813099 -143.77366) (xy 8.706599 -143.841247) (xy 8.596064 -143.902014)
			(xy 8.481932 -143.955721) (xy 8.364653 -144.002155) (xy 8.24469 -144.041133) (xy 8.122517 -144.072502)
			(xy 7.998614 -144.096137) (xy 7.873472 -144.111947) (xy 7.747584 -144.119867) (xy 7.621448 -144.119867)
			(xy 7.49556 -144.111947) (xy 7.370418 -144.096137) (xy 7.246515 -144.072502) (xy 7.124342 -144.041133)
			(xy 7.004379 -144.002155) (xy 6.8871 -143.955721) (xy 6.772968 -143.902014) (xy 6.662433 -143.841247)
			(xy 6.555933 -143.77366) (xy 6.453886 -143.699519) (xy 6.356696 -143.619116) (xy 6.264746 -143.53277)
			(xy 6.1784 -143.44082) (xy 6.097997 -143.34363) (xy 6.023856 -143.241583) (xy 5.956269 -143.135083)
			(xy 5.895502 -143.024548) (xy 5.841795 -142.910416) (xy 5.795361 -142.793137) (xy 5.756383 -142.673174)
			(xy 5.725014 -142.551001) (xy 5.701379 -142.427098) (xy 5.685569 -142.301956) (xy 5.677649 -142.176068)
			(xy 1.016 -142.176068) (xy 1.016 -152.071578) (xy 1.016492 -152.086921) (xy 1.023881 -152.116707)
			(xy 1.038164 -152.14387) (xy 1.048004 -152.155652) (xy 1.065976 -152.176695) (xy 1.09629 -152.222991)
			(xy 1.119599 -152.27318) (xy 1.135415 -152.32621) (xy 1.143407 -152.380967) (xy 1.143407 -152.436305)
			(xy 1.135415 -152.491062) (xy 1.119599 -152.544092) (xy 1.09629 -152.594281) (xy 1.065976 -152.640577)
			(xy 1.048004 -152.66162) (xy 1.03813 -152.673379) (xy 1.023835 -152.700546) (xy 1.01646 -152.730345)
			(xy 1.016 -152.745694) (xy 1.016 -153.359866) (xy 86.877404 -153.359866) (xy 86.881424 -153.169215)
			(xy 86.893478 -152.978902) (xy 86.913544 -152.789267) (xy 86.941587 -152.600646) (xy 86.977556 -152.413376)
			(xy 87.021388 -152.227788) (xy 87.073005 -152.044213) (xy 87.132315 -151.862977) (xy 87.199213 -151.684402)
			(xy 87.273579 -151.508807) (xy 87.355281 -151.336502) (xy 87.444175 -151.167795) (xy 87.540101 -151.002985)
			(xy 87.64289 -150.842366) (xy 87.752359 -150.686223) (xy 87.868313 -150.534834) (xy 87.990547 -150.388467)
			(xy 88.118841 -150.247383) (xy 88.252969 -150.111834) (xy 88.392693 -149.982059) (xy 88.537763 -149.858289)
			(xy 88.687921 -149.740746) (xy 88.842902 -149.629637) (xy 89.002429 -149.52516) (xy 89.166218 -149.427501)
			(xy 89.333978 -149.336834) (xy 89.505412 -149.25332) (xy 89.680214 -149.177107) (xy 89.858073 -149.108331)
			(xy 90.038674 -149.047113) (xy 90.221694 -148.993564) (xy 90.40681 -148.947778) (xy 90.593691 -148.909836)
			(xy 90.782006 -148.879807) (xy 90.971419 -148.857742) (xy 91.161593 -148.843683) (xy 91.352192 -148.837653)
			(xy 91.542875 -148.839663) (xy 91.733304 -148.84971) (xy 91.92314 -148.867776) (xy 92.112046 -148.893829)
			(xy 92.299685 -148.927822) (xy 92.485725 -148.969695) (xy 92.669834 -149.019374) (xy 92.851685 -149.07677)
			(xy 93.030955 -149.141781) (xy 93.207325 -149.214292) (xy 93.380481 -149.294173) (xy 93.550116 -149.381283)
			(xy 93.715928 -149.475467) (xy 93.877622 -149.576558) (xy 94.03491 -149.684374) (xy 94.187513 -149.798726)
			(xy 94.335161 -149.919409) (xy 94.477589 -150.04621) (xy 94.614545 -150.178901) (xy 94.745786 -150.317249)
			(xy 94.871078 -150.461006) (xy 94.990198 -150.609917) (xy 95.102934 -150.763718) (xy 95.209087 -150.922134)
			(xy 95.308467 -151.084885) (xy 95.400897 -151.25168) (xy 95.486214 -151.422224) (xy 95.564266 -151.596212)
			(xy 95.634913 -151.773337) (xy 95.698031 -151.953282) (xy 95.753507 -152.135728) (xy 95.801242 -152.320351)
			(xy 95.841152 -152.506821) (xy 95.873165 -152.694809) (xy 95.897225 -152.883979) (xy 95.913288 -153.073995)
			(xy 95.921327 -153.264519) (xy 95.92183 -153.359866) (xy 95.921327 -153.455213) (xy 95.913288 -153.645737)
			(xy 95.897225 -153.835753) (xy 95.873165 -154.024923) (xy 95.841152 -154.212911) (xy 95.801242 -154.399381)
			(xy 95.753507 -154.584004) (xy 95.698031 -154.76645) (xy 95.634913 -154.946395) (xy 95.564266 -155.12352)
			(xy 95.486214 -155.297508) (xy 95.400897 -155.468052) (xy 95.308467 -155.634847) (xy 95.209087 -155.797598)
			(xy 95.102934 -155.956014) (xy 94.990198 -156.109815) (xy 94.871078 -156.258726) (xy 94.745786 -156.402483)
			(xy 94.614545 -156.540831) (xy 94.477589 -156.673522) (xy 94.335161 -156.800323) (xy 94.187513 -156.921006)
			(xy 94.03491 -157.035358) (xy 93.877622 -157.143174) (xy 93.715928 -157.244265) (xy 93.550116 -157.338449)
			(xy 93.380481 -157.425559) (xy 93.207325 -157.50544) (xy 93.030955 -157.577951) (xy 92.851685 -157.642962)
			(xy 92.669834 -157.700358) (xy 92.485725 -157.750037) (xy 92.299685 -157.79191) (xy 92.112046 -157.825903)
			(xy 91.92314 -157.851956) (xy 91.733304 -157.870022) (xy 91.542875 -157.880069) (xy 91.352192 -157.882079)
			(xy 91.161593 -157.876049) (xy 90.971419 -157.86199) (xy 90.782006 -157.839925) (xy 90.593691 -157.809896)
			(xy 90.40681 -157.771954) (xy 90.221694 -157.726168) (xy 90.038674 -157.672619) (xy 89.858073 -157.611401)
			(xy 89.680214 -157.542625) (xy 89.505412 -157.466412) (xy 89.333978 -157.382898) (xy 89.166218 -157.292231)
			(xy 89.002429 -157.194572) (xy 88.842902 -157.090095) (xy 88.687921 -156.978986) (xy 88.537763 -156.861443)
			(xy 88.392693 -156.737673) (xy 88.252969 -156.607898) (xy 88.118841 -156.472349) (xy 87.990547 -156.331265)
			(xy 87.868313 -156.184898) (xy 87.752359 -156.033509) (xy 87.64289 -155.877366) (xy 87.540101 -155.716747)
			(xy 87.444175 -155.551937) (xy 87.355281 -155.38323) (xy 87.273579 -155.210925) (xy 87.199213 -155.03533)
			(xy 87.132315 -154.856755) (xy 87.073005 -154.675519) (xy 87.021388 -154.491944) (xy 86.977556 -154.306356)
			(xy 86.941587 -154.119086) (xy 86.913544 -153.930465) (xy 86.893478 -153.74083) (xy 86.881424 -153.550517)
			(xy 86.877404 -153.359866) (xy 1.016 -153.359866) (xy 1.016 -164.771578) (xy 1.016492 -164.786921)
			(xy 1.023881 -164.816707) (xy 1.038164 -164.84387) (xy 1.048004 -164.855652) (xy 1.065976 -164.876695)
			(xy 1.09629 -164.922991) (xy 1.119599 -164.97318) (xy 1.135415 -165.02621) (xy 1.143407 -165.080967)
			(xy 1.143407 -165.136305) (xy 1.135415 -165.191062) (xy 1.119599 -165.244092) (xy 1.09629 -165.294281)
			(xy 1.065976 -165.340577) (xy 1.048004 -165.36162) (xy 1.03813 -165.373379) (xy 1.023835 -165.400546)
			(xy 1.01646 -165.430345) (xy 1.016 -165.445694) (xy 1.016 -177.471578) (xy 1.016492 -177.486921)
			(xy 1.023881 -177.516707) (xy 1.038164 -177.54387) (xy 1.048004 -177.555652) (xy 1.065976 -177.576695)
			(xy 1.09629 -177.622991) (xy 1.119599 -177.67318) (xy 1.135415 -177.72621) (xy 1.143407 -177.780967)
			(xy 1.143407 -177.836305) (xy 1.135415 -177.891062) (xy 1.119599 -177.944092) (xy 1.09629 -177.994281)
			(xy 1.065976 -178.040577) (xy 1.048004 -178.06162) (xy 1.03813 -178.073379) (xy 1.023835 -178.100546)
			(xy 1.01646 -178.130345) (xy 1.016 -178.145694) (xy 1.016 -184.704228) (xy 39.818818 -184.704228)
			(xy 39.819523 -184.645605) (xy 39.828091 -184.528667) (xy 39.844787 -184.412611) (xy 39.86953 -184.298001)
			(xy 39.902199 -184.185393) (xy 39.942635 -184.075335) (xy 39.990642 -183.968363) (xy 40.045986 -183.864996)
			(xy 40.108399 -183.765737) (xy 40.177577 -183.671068) (xy 40.253183 -183.58145) (xy 40.334851 -183.497318)
			(xy 40.422182 -183.419081) (xy 40.514753 -183.34712) (xy 40.612113 -183.281784) (xy 40.713789 -183.223392)
			(xy 40.819288 -183.172226) (xy 40.928095 -183.128537) (xy 41.039682 -183.092535) (xy 41.153506 -183.064397)
			(xy 41.269014 -183.044259) (xy 41.385645 -183.032218) (xy 41.502832 -183.028334) (xy 41.620004 -183.032625)
			(xy 41.736593 -183.045071) (xy 41.85203 -183.065611) (xy 41.965756 -183.094144) (xy 42.077217 -183.130533)
			(xy 42.185872 -183.174601) (xy 42.291192 -183.226133) (xy 42.392665 -183.284878) (xy 42.489797 -183.350552)
			(xy 42.582117 -183.422834) (xy 42.669176 -183.501374) (xy 42.750551 -183.585789) (xy 42.825845 -183.675669)
			(xy 42.894694 -183.770578) (xy 42.956761 -183.870054) (xy 43.011746 -183.973612) (xy 43.059381 -184.080751)
			(xy 43.099434 -184.190948) (xy 43.131712 -184.303669) (xy 43.156056 -184.418365) (xy 43.172348 -184.534478)
			(xy 43.18051 -184.651445) (xy 43.181016 -184.71007) (xy 43.180861 -184.740833) (xy 43.178574 -184.802316)
			(xy 43.176444 -184.833006) (xy 43.175682 -184.842404) (xy 43.170622 -184.900806) (xy 43.153396 -185.016771)
			(xy 43.12813 -185.131253) (xy 43.094949 -185.243697) (xy 43.054014 -185.353555) (xy 43.005523 -185.460294)
			(xy 42.949712 -185.563395) (xy 42.886853 -185.662356) (xy 42.817252 -185.756696) (xy 42.741246 -185.845958)
			(xy 42.659204 -185.929706) (xy 42.571527 -186.007535) (xy 42.503292 -186.06008) (xy 93.15476 -186.06008)
			(xy 93.158776 -185.94381) (xy 93.170803 -185.828095) (xy 93.190785 -185.713485) (xy 93.218627 -185.600526)
			(xy 93.254196 -185.489758) (xy 93.297322 -185.381707) (xy 93.347799 -185.276889) (xy 93.405388 -185.175804)
			(xy 93.469814 -185.078932) (xy 93.540769 -184.986736) (xy 93.617916 -184.899655) (xy 93.700887 -184.818104)
			(xy 93.789287 -184.742472) (xy 93.882694 -184.673118) (xy 93.980663 -184.610375) (xy 94.082727 -184.554539)
			(xy 94.188401 -184.505878) (xy 94.29718 -184.464624) (xy 94.408545 -184.430973) (xy 94.521968 -184.405085)
			(xy 94.636905 -184.387084) (xy 94.752811 -184.377055) (xy 94.869133 -184.375047) (xy 94.985316 -184.381069)
			(xy 95.100807 -184.395092) (xy 95.215055 -184.41705) (xy 95.327516 -184.446837) (xy 95.437654 -184.484312)
			(xy 95.544944 -184.529297) (xy 95.648875 -184.581576) (xy 95.748951 -184.640901) (xy 95.844697 -184.706989)
			(xy 95.935654 -184.779525) (xy 96.02139 -184.858164) (xy 96.101497 -184.94253) (xy 96.175593 -185.032222)
			(xy 96.243323 -185.126812) (xy 96.304367 -185.22585) (xy 96.358432 -185.328863) (xy 96.405262 -185.43536)
			(xy 96.444633 -185.544835) (xy 96.476357 -185.656765) (xy 96.500283 -185.770617) (xy 96.516297 -185.885849)
			(xy 96.524324 -186.001911) (xy 96.524826 -186.06008) (xy 96.524324 -186.118249) (xy 96.516297 -186.234311)
			(xy 96.500283 -186.349543) (xy 96.476357 -186.463395) (xy 96.444633 -186.575325) (xy 96.405262 -186.6848)
			(xy 96.358432 -186.791297) (xy 96.304367 -186.89431) (xy 96.243323 -186.993348) (xy 96.175593 -187.087938)
			(xy 96.101497 -187.17763) (xy 96.02139 -187.261996) (xy 95.935654 -187.340635) (xy 95.844697 -187.413171)
			(xy 95.748951 -187.479259) (xy 95.648875 -187.538584) (xy 95.544944 -187.590863) (xy 95.437654 -187.635848)
			(xy 95.327516 -187.673323) (xy 95.215055 -187.70311) (xy 95.100807 -187.725068) (xy 94.985316 -187.739091)
			(xy 94.869133 -187.745113) (xy 94.752811 -187.743105) (xy 94.636905 -187.733076) (xy 94.521968 -187.715075)
			(xy 94.408545 -187.689187) (xy 94.29718 -187.655536) (xy 94.188401 -187.614282) (xy 94.082727 -187.565621)
			(xy 93.980663 -187.509785) (xy 93.882694 -187.447042) (xy 93.789287 -187.377688) (xy 93.700887 -187.302056)
			(xy 93.617916 -187.220505) (xy 93.540769 -187.133424) (xy 93.469814 -187.041228) (xy 93.405388 -186.944356)
			(xy 93.347799 -186.843271) (xy 93.297322 -186.738453) (xy 93.254196 -186.630402) (xy 93.218627 -186.519634)
			(xy 93.190785 -186.406675) (xy 93.170803 -186.292065) (xy 93.158776 -186.17635) (xy 93.15476 -186.06008)
			(xy 42.503292 -186.06008) (xy 42.47864 -186.079064) (xy 42.380994 -186.143948) (xy 42.279065 -186.20187)
			(xy 42.173347 -186.252549) (xy 42.064355 -186.295738) (xy 41.952619 -186.331228) (xy 41.838681 -186.358845)
			(xy 41.723096 -186.378457) (xy 41.606425 -186.389967) (xy 41.489236 -186.393319) (xy 41.372098 -186.388497)
			(xy 41.25558 -186.375525) (xy 41.14025 -186.354466) (xy 41.026668 -186.325421) (xy 40.915385 -186.288533)
			(xy 40.806943 -186.24398) (xy 40.70187 -186.19198) (xy 40.600675 -186.132784) (xy 40.50385 -186.066681)
			(xy 40.411868 -185.993992) (xy 40.325173 -185.91507) (xy 40.244189 -185.830299) (xy 40.169308 -185.740091)
			(xy 40.100895 -185.644885) (xy 40.039282 -185.545143) (xy 39.984769 -185.441351) (xy 39.937621 -185.334012)
			(xy 39.898066 -185.223649) (xy 39.866298 -185.110798) (xy 39.842471 -184.996008) (xy 39.826699 -184.879836)
			(xy 39.819061 -184.762848) (xy 39.818818 -184.704228) (xy 1.016 -184.704228) (xy 1.016 -190.171578)
			(xy 1.016492 -190.186921) (xy 1.023881 -190.216707) (xy 1.038164 -190.24387) (xy 1.048004 -190.255652)
			(xy 1.065976 -190.276695) (xy 1.09629 -190.322991) (xy 1.119599 -190.37318) (xy 1.135415 -190.42621)
			(xy 1.143407 -190.480967) (xy 1.143407 -190.536305) (xy 1.135415 -190.591062) (xy 1.119599 -190.644092)
			(xy 1.09629 -190.694281) (xy 1.065976 -190.740577) (xy 1.048004 -190.76162) (xy 1.03813 -190.773379)
			(xy 1.023835 -190.800546) (xy 1.01646 -190.830345) (xy 1.016 -190.845694) (xy 1.016 -197.81012) (xy 86.877404 -197.81012)
			(xy 86.881424 -197.619469) (xy 86.893478 -197.429156) (xy 86.913544 -197.239521) (xy 86.941587 -197.0509)
			(xy 86.977556 -196.86363) (xy 87.021388 -196.678042) (xy 87.073005 -196.494467) (xy 87.132315 -196.313231)
			(xy 87.199213 -196.134656) (xy 87.273579 -195.959061) (xy 87.355281 -195.786756) (xy 87.444175 -195.618049)
			(xy 87.540101 -195.453239) (xy 87.64289 -195.29262) (xy 87.752359 -195.136477) (xy 87.868313 -194.985088)
			(xy 87.990547 -194.838721) (xy 88.118841 -194.697637) (xy 88.252969 -194.562088) (xy 88.392693 -194.432313)
			(xy 88.537763 -194.308543) (xy 88.687921 -194.191) (xy 88.842902 -194.079891) (xy 89.002429 -193.975414)
			(xy 89.166218 -193.877755) (xy 89.333978 -193.787088) (xy 89.505412 -193.703574) (xy 89.680214 -193.627361)
			(xy 89.858073 -193.558585) (xy 90.038674 -193.497367) (xy 90.221694 -193.443818) (xy 90.40681 -193.398032)
			(xy 90.593691 -193.36009) (xy 90.782006 -193.330061) (xy 90.971419 -193.307996) (xy 91.161593 -193.293937)
			(xy 91.352192 -193.287907) (xy 91.542875 -193.289917) (xy 91.733304 -193.299964) (xy 91.92314 -193.31803)
			(xy 92.112046 -193.344083) (xy 92.299685 -193.378076) (xy 92.485725 -193.419949) (xy 92.669834 -193.469628)
			(xy 92.851685 -193.527024) (xy 93.030955 -193.592035) (xy 93.207325 -193.664546) (xy 93.380481 -193.744427)
			(xy 93.550116 -193.831537) (xy 93.715928 -193.925721) (xy 93.877622 -194.026812) (xy 94.03491 -194.134628)
			(xy 94.187513 -194.24898) (xy 94.335161 -194.369663) (xy 94.477589 -194.496464) (xy 94.614545 -194.629155)
			(xy 94.745786 -194.767503) (xy 94.871078 -194.91126) (xy 94.990198 -195.060171) (xy 95.102934 -195.213972)
			(xy 95.209087 -195.372388) (xy 95.308467 -195.535139) (xy 95.400897 -195.701934) (xy 95.486214 -195.872478)
			(xy 95.564266 -196.046466) (xy 95.634913 -196.223591) (xy 95.698031 -196.403536) (xy 95.753507 -196.585982)
			(xy 95.801242 -196.770605) (xy 95.841152 -196.957075) (xy 95.873165 -197.145063) (xy 95.897225 -197.334233)
			(xy 95.913288 -197.524249) (xy 95.921327 -197.714773) (xy 95.92183 -197.81012) (xy 95.921327 -197.905467)
			(xy 95.913288 -198.095991) (xy 95.897225 -198.286007) (xy 95.873165 -198.475177) (xy 95.841152 -198.663165)
			(xy 95.801242 -198.849635) (xy 95.753507 -199.034258) (xy 95.698031 -199.216704) (xy 95.634913 -199.396649)
			(xy 95.564266 -199.573774) (xy 95.486214 -199.747762) (xy 95.400897 -199.918306) (xy 95.308467 -200.085101)
			(xy 95.209087 -200.247852) (xy 95.102934 -200.406268) (xy 94.990198 -200.560069) (xy 94.871078 -200.70898)
			(xy 94.745786 -200.852737) (xy 94.614545 -200.991085) (xy 94.477589 -201.123776) (xy 94.335161 -201.250577)
			(xy 94.187513 -201.37126) (xy 94.03491 -201.485612) (xy 93.877622 -201.593428) (xy 93.715928 -201.694519)
			(xy 93.550116 -201.788703) (xy 93.380481 -201.875813) (xy 93.207325 -201.955694) (xy 93.030955 -202.028205)
			(xy 92.851685 -202.093216) (xy 92.669834 -202.150612) (xy 92.485725 -202.200291) (xy 92.299685 -202.242164)
			(xy 92.112046 -202.276157) (xy 91.92314 -202.30221) (xy 91.733304 -202.320276) (xy 91.542875 -202.330323)
			(xy 91.352192 -202.332333) (xy 91.161593 -202.326303) (xy 90.971419 -202.312244) (xy 90.782006 -202.290179)
			(xy 90.593691 -202.26015) (xy 90.40681 -202.222208) (xy 90.221694 -202.176422) (xy 90.038674 -202.122873)
			(xy 89.858073 -202.061655) (xy 89.680214 -201.992879) (xy 89.505412 -201.916666) (xy 89.333978 -201.833152)
			(xy 89.166218 -201.742485) (xy 89.002429 -201.644826) (xy 88.842902 -201.540349) (xy 88.687921 -201.42924)
			(xy 88.537763 -201.311697) (xy 88.392693 -201.187927) (xy 88.252969 -201.058152) (xy 88.118841 -200.922603)
			(xy 87.990547 -200.781519) (xy 87.868313 -200.635152) (xy 87.752359 -200.483763) (xy 87.64289 -200.32762)
			(xy 87.540101 -200.167001) (xy 87.444175 -200.002191) (xy 87.355281 -199.833484) (xy 87.273579 -199.661179)
			(xy 87.199213 -199.485584) (xy 87.132315 -199.307009) (xy 87.073005 -199.125773) (xy 87.021388 -198.942198)
			(xy 86.977556 -198.75661) (xy 86.941587 -198.56934) (xy 86.913544 -198.380719) (xy 86.893478 -198.191084)
			(xy 86.881424 -198.000771) (xy 86.877404 -197.81012) (xy 1.016 -197.81012) (xy 1.016 -202.871578)
			(xy 1.016492 -202.886921) (xy 1.023881 -202.916707) (xy 1.038164 -202.94387) (xy 1.048004 -202.955652)
			(xy 1.065976 -202.976695) (xy 1.09629 -203.022991) (xy 1.119599 -203.07318) (xy 1.135415 -203.12621)
			(xy 1.143407 -203.180967) (xy 1.143407 -203.236305) (xy 1.135415 -203.291062) (xy 1.119599 -203.344092)
			(xy 1.09629 -203.394281) (xy 1.065976 -203.440577) (xy 1.048004 -203.46162) (xy 1.03813 -203.473379)
			(xy 1.023835 -203.500546) (xy 1.01646 -203.530345) (xy 1.016 -203.545694) (xy 1.016 -206.99984) (xy 11.34441 -206.99984)
			(xy 11.348411 -206.794791) (xy 11.36041 -206.590054) (xy 11.380388 -206.385941) (xy 11.408314 -206.182762)
			(xy 11.444146 -205.980829) (xy 11.48783 -205.780446) (xy 11.539298 -205.581921) (xy 11.598473 -205.385555)
			(xy 11.665264 -205.191648) (xy 11.73957 -205.000494) (xy 11.821277 -204.812384) (xy 11.910262 -204.627606)
			(xy 12.006388 -204.44644) (xy 12.109509 -204.269163) (xy 12.219469 -204.096044) (xy 12.336099 -203.927347)
			(xy 12.459222 -203.763329) (xy 12.588651 -203.60424) (xy 12.724188 -203.450322) (xy 12.865627 -203.301808)
			(xy 13.012754 -203.158927) (xy 13.165342 -203.021894) (xy 13.323161 -202.89092) (xy 13.48597 -202.766202)
			(xy 13.653521 -202.647932) (xy 13.825559 -202.536288) (xy 14.001822 -202.431442) (xy 14.182041 -202.333553)
			(xy 14.365942 -202.24277) (xy 14.553246 -202.159232) (xy 14.743666 -202.083064) (xy 14.936912 -202.014384)
			(xy 15.132692 -201.953296) (xy 15.330705 -201.899894) (xy 15.530652 -201.854257) (xy 15.732226 -201.816457)
			(xy 15.935122 -201.786549) (xy 16.139031 -201.764581) (xy 16.343641 -201.750586) (xy 16.548641 -201.744584)
			(xy 16.75372 -201.746585) (xy 16.958564 -201.756585) (xy 17.162863 -201.774571) (xy 17.366304 -201.800513)
			(xy 17.568577 -201.834374) (xy 17.769376 -201.8761) (xy 17.968394 -201.925629) (xy 18.165328 -201.982885)
			(xy 18.359878 -202.047782) (xy 18.551748 -202.120219) (xy 18.740645 -202.200087) (xy 18.926283 -202.287265)
			(xy 19.108378 -202.381619) (xy 19.286653 -202.483006) (xy 19.460836 -202.591271) (xy 19.630663 -202.706249)
			(xy 19.795875 -202.827767) (xy 19.956219 -202.955637) (xy 20.111453 -203.089666) (xy 20.261339 -203.22965)
			(xy 20.405649 -203.375375) (xy 20.544163 -203.52662) (xy 20.676672 -203.683153) (xy 20.802972 -203.844738)
			(xy 20.922871 -204.011127) (xy 21.036188 -204.182067) (xy 21.142748 -204.357299) (xy 21.242391 -204.536554)
			(xy 21.334964 -204.719561) (xy 21.420326 -204.90604) (xy 21.498347 -205.095708) (xy 21.56891 -205.288276)
			(xy 21.631905 -205.48345) (xy 21.687237 -205.680933) (xy 21.734822 -205.880424) (xy 21.774587 -206.081621)
			(xy 21.806472 -206.284215) (xy 21.830429 -206.4879) (xy 21.84642 -206.692364) (xy 21.854422 -206.897296)
			(xy 21.854922 -206.99984) (xy 21.854422 -207.102384) (xy 21.84642 -207.307316) (xy 21.830429 -207.51178)
			(xy 21.806472 -207.715465) (xy 21.774587 -207.918059) (xy 21.734822 -208.119256) (xy 21.687237 -208.318747)
			(xy 21.631905 -208.51623) (xy 21.56891 -208.711404) (xy 21.498347 -208.903972) (xy 21.420326 -209.09364)
			(xy 21.334964 -209.280119) (xy 21.242391 -209.463126) (xy 21.142748 -209.642381) (xy 21.036188 -209.817613)
			(xy 20.922871 -209.988553) (xy 20.842811 -210.099656) (xy 72.864987 -210.099656) (xy 72.868996 -209.896785)
			(xy 72.881016 -209.694231) (xy 72.90103 -209.49231) (xy 72.929005 -209.291337) (xy 72.964898 -209.091627)
			(xy 73.008652 -208.89349) (xy 73.060201 -208.697237) (xy 73.119462 -208.503173) (xy 73.186344 -208.311602)
			(xy 73.260742 -208.122823) (xy 73.34254 -207.93713) (xy 73.43161 -207.754814) (xy 73.527813 -207.576159)
			(xy 73.631 -207.401445) (xy 73.741008 -207.230943) (xy 73.857666 -207.06492) (xy 73.980792 -206.903636)
			(xy 74.110194 -206.747342) (xy 74.245669 -206.596282) (xy 74.387006 -206.450692) (xy 74.533985 -206.3108)
			(xy 74.686376 -206.176824) (xy 74.843941 -206.048972) (xy 75.006434 -205.927446) (xy 75.173601 -205.812433)
			(xy 75.345181 -205.704115) (xy 75.520906 -205.60266) (xy 75.700503 -205.508226) (xy 75.88369 -205.420961)
			(xy 76.070182 -205.341002) (xy 76.259687 -205.268473) (xy 76.451909 -205.203487) (xy 76.646549 -205.146145)
			(xy 76.843302 -205.096538) (xy 77.041861 -205.054743) (xy 77.241917 -205.020825) (xy 77.443156 -204.994837)
			(xy 77.645265 -204.976819) (xy 77.847928 -204.9668) (xy 78.050828 -204.964796) (xy 78.253649 -204.970808)
			(xy 78.456075 -204.984829) (xy 78.657788 -205.006837) (xy 78.858475 -205.036796) (xy 79.057821 -205.07466)
			(xy 79.255516 -205.12037) (xy 79.45125 -205.173854) (xy 79.644719 -205.23503) (xy 79.83562 -205.303801)
			(xy 80.023655 -205.380061) (xy 80.208531 -205.463689) (xy 80.389958 -205.554556) (xy 80.567654 -205.652519)
			(xy 80.74134 -205.757427) (xy 80.910747 -205.869114) (xy 81.075609 -205.987406) (xy 81.235669 -206.11212)
			(xy 81.390677 -206.243059) (xy 81.540391 -206.38002) (xy 81.684577 -206.522789) (xy 81.823011 -206.671143)
			(xy 81.955475 -206.82485) (xy 82.081764 -206.98367) (xy 82.201679 -207.147355) (xy 82.315035 -207.31565)
			(xy 82.421653 -207.488292) (xy 82.521367 -207.665012) (xy 82.614022 -207.845532) (xy 82.699472 -208.029572)
			(xy 82.777586 -208.216845) (xy 82.848239 -208.407057) (xy 82.911323 -208.599912) (xy 82.966739 -208.795109)
			(xy 83.0144 -208.992342) (xy 83.054231 -209.191305) (xy 83.086171 -209.391686) (xy 83.11017 -209.593172)
			(xy 83.12619 -209.795449) (xy 83.134207 -209.998201) (xy 83.134708 -210.099656) (xy 83.134207 -210.201111)
			(xy 83.12619 -210.403863) (xy 83.11017 -210.60614) (xy 83.086171 -210.807626) (xy 83.054231 -211.008007)
			(xy 83.0144 -211.20697) (xy 82.966739 -211.404203) (xy 82.911323 -211.5994) (xy 82.848239 -211.792255)
			(xy 82.777586 -211.982467) (xy 82.699472 -212.16974) (xy 82.614022 -212.35378) (xy 82.521367 -212.5343)
			(xy 82.421653 -212.71102) (xy 82.315035 -212.883662) (xy 82.201679 -213.051957) (xy 82.081764 -213.215642)
			(xy 81.955475 -213.374462) (xy 81.823011 -213.528169) (xy 81.684577 -213.676523) (xy 81.540391 -213.819292)
			(xy 81.390677 -213.956253) (xy 81.235669 -214.087192) (xy 81.075609 -214.211906) (xy 80.910747 -214.330198)
			(xy 80.74134 -214.441885) (xy 80.567654 -214.546793) (xy 80.389958 -214.644756) (xy 80.208531 -214.735623)
			(xy 80.023655 -214.819251) (xy 79.83562 -214.895511) (xy 79.644719 -214.964282) (xy 79.45125 -215.025458)
			(xy 79.255516 -215.078942) (xy 79.057821 -215.124652) (xy 78.858475 -215.162516) (xy 78.657788 -215.192475)
			(xy 78.456075 -215.214483) (xy 78.253649 -215.228504) (xy 78.050828 -215.234516) (xy 77.847928 -215.232512)
			(xy 77.645265 -215.222493) (xy 77.443156 -215.204475) (xy 77.241917 -215.178487) (xy 77.041861 -215.144569)
			(xy 76.843302 -215.102774) (xy 76.646549 -215.053167) (xy 76.451909 -214.995825) (xy 76.259687 -214.930839)
			(xy 76.070182 -214.85831) (xy 75.88369 -214.778351) (xy 75.700503 -214.691086) (xy 75.520906 -214.596652)
			(xy 75.345181 -214.495197) (xy 75.173601 -214.386879) (xy 75.006434 -214.271866) (xy 74.843941 -214.15034)
			(xy 74.686376 -214.022488) (xy 74.533985 -213.888512) (xy 74.387006 -213.74862) (xy 74.245669 -213.60303)
			(xy 74.110194 -213.45197) (xy 73.980792 -213.295676) (xy 73.857666 -213.134392) (xy 73.741008 -212.968369)
			(xy 73.631 -212.797867) (xy 73.527813 -212.623153) (xy 73.43161 -212.444498) (xy 73.34254 -212.262182)
			(xy 73.260742 -212.076489) (xy 73.186344 -211.88771) (xy 73.119462 -211.696139) (xy 73.060201 -211.502075)
			(xy 73.008652 -211.305822) (xy 72.964898 -211.107685) (xy 72.929005 -210.907975) (xy 72.90103 -210.707002)
			(xy 72.881016 -210.505081) (xy 72.868996 -210.302527) (xy 72.864987 -210.099656) (xy 20.842811 -210.099656)
			(xy 20.802972 -210.154942) (xy 20.676672 -210.316527) (xy 20.544163 -210.47306) (xy 20.405649 -210.624305)
			(xy 20.261339 -210.77003) (xy 20.111453 -210.910014) (xy 19.956219 -211.044043) (xy 19.795875 -211.171913)
			(xy 19.630663 -211.293431) (xy 19.460836 -211.408409) (xy 19.286653 -211.516674) (xy 19.108378 -211.618061)
			(xy 18.926283 -211.712415) (xy 18.740645 -211.799593) (xy 18.551748 -211.879461) (xy 18.359878 -211.951898)
			(xy 18.165328 -212.016795) (xy 17.968394 -212.074051) (xy 17.769376 -212.12358) (xy 17.568577 -212.165306)
			(xy 17.366304 -212.199167) (xy 17.162863 -212.225109) (xy 16.958564 -212.243095) (xy 16.75372 -212.253095)
			(xy 16.548641 -212.255096) (xy 16.343641 -212.249094) (xy 16.139031 -212.235099) (xy 15.935122 -212.213131)
			(xy 15.732226 -212.183223) (xy 15.530652 -212.145423) (xy 15.330705 -212.099786) (xy 15.132692 -212.046384)
			(xy 14.936912 -211.985296) (xy 14.743666 -211.916616) (xy 14.553246 -211.840448) (xy 14.365942 -211.75691)
			(xy 14.182041 -211.666127) (xy 14.001822 -211.568238) (xy 13.825559 -211.463392) (xy 13.653521 -211.351748)
			(xy 13.48597 -211.233478) (xy 13.323161 -211.10876) (xy 13.165342 -210.977786) (xy 13.012754 -210.840753)
			(xy 12.865627 -210.697872) (xy 12.724188 -210.549358) (xy 12.588651 -210.39544) (xy 12.459222 -210.236351)
			(xy 12.336099 -210.072333) (xy 12.219469 -209.903636) (xy 12.109509 -209.730517) (xy 12.006388 -209.55324)
			(xy 11.910262 -209.372074) (xy 11.821277 -209.187296) (xy 11.73957 -208.999186) (xy 11.665264 -208.808032)
			(xy 11.598473 -208.614125) (xy 11.539298 -208.417759) (xy 11.48783 -208.219234) (xy 11.444146 -208.018851)
			(xy 11.408314 -207.816918) (xy 11.380388 -207.613739) (xy 11.36041 -207.409626) (xy 11.348411 -207.204889)
			(xy 11.34441 -206.99984) (xy 1.016 -206.99984) (xy 1.016 -215.571578) (xy 1.016492 -215.586921) (xy 1.023881 -215.616707)
			(xy 1.038164 -215.64387) (xy 1.048004 -215.655652) (xy 1.065976 -215.676695) (xy 1.09629 -215.722991)
			(xy 1.119599 -215.77318) (xy 1.135415 -215.82621) (xy 1.143407 -215.880967) (xy 1.143407 -215.936305)
			(xy 1.135415 -215.991062) (xy 1.119599 -216.044092) (xy 1.09629 -216.094281) (xy 1.065976 -216.140577)
			(xy 1.048004 -216.16162) (xy 1.03813 -216.173379) (xy 1.023835 -216.200546) (xy 1.01646 -216.230345)
			(xy 1.016 -216.245694) (xy 1.016 -228.271578) (xy 1.016492 -228.286921) (xy 1.023881 -228.316707)
			(xy 1.038164 -228.34387) (xy 1.048004 -228.355652) (xy 1.065976 -228.376695) (xy 1.09629 -228.422991)
			(xy 1.119599 -228.47318) (xy 1.135415 -228.52621) (xy 1.143407 -228.580967) (xy 1.143407 -228.636305)
			(xy 1.135415 -228.691062) (xy 1.119599 -228.744092) (xy 1.09629 -228.794281) (xy 1.065976 -228.840577)
			(xy 1.048004 -228.86162) (xy 1.03813 -228.873379) (xy 1.023835 -228.900546) (xy 1.01646 -228.930345)
			(xy 1.016 -228.945694) (xy 1.016 -229.16007) (xy 39.818564 -229.16007) (xy 39.819058 -229.102661)
			(xy 39.826902 -228.988113) (xy 39.842544 -228.874366) (xy 39.865911 -228.761952) (xy 39.896896 -228.651394)
			(xy 39.935352 -228.543209) (xy 39.981101 -228.4379) (xy 40.03393 -228.335958) (xy 40.093592 -228.237859)
			(xy 40.159809 -228.14406) (xy 40.232272 -228.054998) (xy 40.310645 -227.971089) (xy 40.39456 -227.892723)
			(xy 40.483627 -227.820266) (xy 40.577431 -227.754056) (xy 40.675535 -227.694402) (xy 40.777481 -227.641581)
			(xy 40.882793 -227.595839) (xy 40.990981 -227.557391) (xy 41.101541 -227.526415) (xy 41.213957 -227.503056)
			(xy 41.327705 -227.487423) (xy 41.442254 -227.479588) (xy 41.557072 -227.479588) (xy 41.671621 -227.487423)
			(xy 41.785369 -227.503056) (xy 41.897785 -227.526415) (xy 42.008345 -227.557391) (xy 42.116533 -227.595839)
			(xy 42.221845 -227.641581) (xy 42.323791 -227.694402) (xy 42.421895 -227.754056) (xy 42.515699 -227.820266)
			(xy 42.604766 -227.892723) (xy 42.688681 -227.971089) (xy 42.767054 -228.054998) (xy 42.839517 -228.14406)
			(xy 42.905734 -228.237859) (xy 42.965396 -228.335958) (xy 43.018225 -228.4379) (xy 43.063974 -228.543209)
			(xy 43.10243 -228.651394) (xy 43.133415 -228.761952) (xy 43.156782 -228.874366) (xy 43.172424 -228.988113)
			(xy 43.180268 -229.102661) (xy 43.180762 -229.16007) (xy 43.180576 -229.193253) (xy 43.177909 -229.259567)
			(xy 43.175428 -229.292658) (xy 43.170272 -229.350942) (xy 43.152948 -229.466671) (xy 43.127616 -229.580914)
			(xy 43.094401 -229.693119) (xy 43.053462 -229.802742) (xy 43.004999 -229.909253) (xy 42.949245 -230.012135)
			(xy 42.886471 -230.110891) (xy 42.816981 -230.205042) (xy 42.741111 -230.294132) (xy 42.659229 -230.377729)
			(xy 42.571732 -230.45543) (xy 42.500813 -230.51008) (xy 93.154506 -230.51008) (xy 93.158522 -230.39381)
			(xy 93.170549 -230.278095) (xy 93.190531 -230.163485) (xy 93.218373 -230.050526) (xy 93.253942 -229.939758)
			(xy 93.297068 -229.831707) (xy 93.347545 -229.726889) (xy 93.405134 -229.625804) (xy 93.46956 -229.528932)
			(xy 93.540515 -229.436736) (xy 93.617662 -229.349655) (xy 93.700633 -229.268104) (xy 93.789033 -229.192472)
			(xy 93.88244 -229.123118) (xy 93.980409 -229.060375) (xy 94.082473 -229.004539) (xy 94.188147 -228.955878)
			(xy 94.296926 -228.914624) (xy 94.408291 -228.880973) (xy 94.521714 -228.855085) (xy 94.636651 -228.837084)
			(xy 94.752557 -228.827055) (xy 94.868879 -228.825047) (xy 94.985062 -228.831069) (xy 95.100553 -228.845092)
			(xy 95.214801 -228.86705) (xy 95.327262 -228.896837) (xy 95.4374 -228.934312) (xy 95.54469 -228.979297)
			(xy 95.648621 -229.031576) (xy 95.748697 -229.090901) (xy 95.844443 -229.156989) (xy 95.9354 -229.229525)
			(xy 96.021136 -229.308164) (xy 96.101243 -229.39253) (xy 96.175339 -229.482222) (xy 96.243069 -229.576812)
			(xy 96.304113 -229.67585) (xy 96.358178 -229.778863) (xy 96.405008 -229.88536) (xy 96.444379 -229.994835)
			(xy 96.476103 -230.106765) (xy 96.500029 -230.220617) (xy 96.516043 -230.335849) (xy 96.52407 -230.451911)
			(xy 96.524572 -230.51008) (xy 96.52407 -230.568249) (xy 96.516043 -230.684311) (xy 96.500029 -230.799543)
			(xy 96.476103 -230.913395) (xy 96.444379 -231.025325) (xy 96.405008 -231.1348) (xy 96.358178 -231.241297)
			(xy 96.304113 -231.34431) (xy 96.243069 -231.443348) (xy 96.175339 -231.537938) (xy 96.101243 -231.62763)
			(xy 96.021136 -231.711996) (xy 95.9354 -231.790635) (xy 95.844443 -231.863171) (xy 95.748697 -231.929259)
			(xy 95.648621 -231.988584) (xy 95.54469 -232.040863) (xy 95.4374 -232.085848) (xy 95.327262 -232.123323)
			(xy 95.214801 -232.15311) (xy 95.100553 -232.175068) (xy 94.985062 -232.189091) (xy 94.868879 -232.195113)
			(xy 94.752557 -232.193105) (xy 94.636651 -232.183076) (xy 94.521714 -232.165075) (xy 94.408291 -232.139187)
			(xy 94.296926 -232.105536) (xy 94.188147 -232.064282) (xy 94.082473 -232.015621) (xy 93.980409 -231.959785)
			(xy 93.88244 -231.897042) (xy 93.789033 -231.827688) (xy 93.700633 -231.752056) (xy 93.617662 -231.670505)
			(xy 93.540515 -231.583424) (xy 93.46956 -231.491228) (xy 93.405134 -231.394356) (xy 93.347545 -231.293271)
			(xy 93.297068 -231.188453) (xy 93.253942 -231.080402) (xy 93.218373 -230.969634) (xy 93.190531 -230.856675)
			(xy 93.170549 -230.742065) (xy 93.158522 -230.62635) (xy 93.154506 -230.51008) (xy 42.500813 -230.51008)
			(xy 42.479042 -230.526857) (xy 42.381609 -230.591665) (xy 42.279905 -230.64954) (xy 42.174422 -230.700202)
			(xy 42.065671 -230.743404) (xy 41.954179 -230.778939) (xy 41.840485 -230.806634) (xy 41.725141 -230.826354)
			(xy 41.608704 -230.838005) (xy 41.491739 -230.84153) (xy 41.374812 -230.836912) (xy 41.258489 -230.824173)
			(xy 41.143334 -230.803375) (xy 41.029905 -230.774618) (xy 40.91875 -230.738042) (xy 40.810407 -230.693825)
			(xy 40.705403 -230.642179) (xy 40.604244 -230.583356) (xy 40.507421 -230.51764) (xy 40.415403 -230.445349)
			(xy 40.328636 -230.366834) (xy 40.247539 -230.282474) (xy 40.172506 -230.192679) (xy 40.103899 -230.097883)
			(xy 40.042051 -229.998544) (xy 39.987262 -229.895145) (xy 39.939796 -229.788186) (xy 39.899884 -229.678185)
			(xy 39.86772 -229.565674) (xy 39.843457 -229.451199) (xy 39.827215 -229.335313) (xy 39.819072 -229.218579)
			(xy 39.818564 -229.16007) (xy 1.016 -229.16007) (xy 1.016 -240.971578) (xy 1.016492 -240.986921)
			(xy 1.023881 -241.016707) (xy 1.038164 -241.04387) (xy 1.048004 -241.055652) (xy 1.065976 -241.076695)
			(xy 1.09629 -241.122991) (xy 1.119599 -241.17318) (xy 1.135415 -241.22621) (xy 1.143407 -241.280967)
			(xy 1.143407 -241.336305) (xy 1.135415 -241.391062) (xy 1.119599 -241.444092) (xy 1.09629 -241.494281)
			(xy 1.065976 -241.540577) (xy 1.048004 -241.56162) (xy 1.03813 -241.573379) (xy 1.023835 -241.600546)
			(xy 1.01646 -241.630345) (xy 1.016 -241.645694) (xy 1.016 -242.26012) (xy 86.877404 -242.26012) (xy 86.881424 -242.069469)
			(xy 86.893478 -241.879156) (xy 86.913544 -241.689521) (xy 86.941587 -241.5009) (xy 86.977556 -241.31363)
			(xy 87.021388 -241.128042) (xy 87.073005 -240.944467) (xy 87.132315 -240.763231) (xy 87.199213 -240.584656)
			(xy 87.273579 -240.409061) (xy 87.355281 -240.236756) (xy 87.444175 -240.068049) (xy 87.540101 -239.903239)
			(xy 87.64289 -239.74262) (xy 87.752359 -239.586477) (xy 87.868313 -239.435088) (xy 87.990547 -239.288721)
			(xy 88.118841 -239.147637) (xy 88.252969 -239.012088) (xy 88.392693 -238.882313) (xy 88.537763 -238.758543)
			(xy 88.687921 -238.641) (xy 88.842902 -238.529891) (xy 89.002429 -238.425414) (xy 89.166218 -238.327755)
			(xy 89.333978 -238.237088) (xy 89.505412 -238.153574) (xy 89.680214 -238.077361) (xy 89.858073 -238.008585)
			(xy 90.038674 -237.947367) (xy 90.221694 -237.893818) (xy 90.40681 -237.848032) (xy 90.593691 -237.81009)
			(xy 90.782006 -237.780061) (xy 90.971419 -237.757996) (xy 91.161593 -237.743937) (xy 91.352192 -237.737907)
			(xy 91.542875 -237.739917) (xy 91.733304 -237.749964) (xy 91.92314 -237.76803) (xy 92.112046 -237.794083)
			(xy 92.299685 -237.828076) (xy 92.485725 -237.869949) (xy 92.669834 -237.919628) (xy 92.851685 -237.977024)
			(xy 93.030955 -238.042035) (xy 93.207325 -238.114546) (xy 93.380481 -238.194427) (xy 93.550116 -238.281537)
			(xy 93.715928 -238.375721) (xy 93.877622 -238.476812) (xy 94.03491 -238.584628) (xy 94.187513 -238.69898)
			(xy 94.335161 -238.819663) (xy 94.477589 -238.946464) (xy 94.614545 -239.079155) (xy 94.745786 -239.217503)
			(xy 94.871078 -239.36126) (xy 94.990198 -239.510171) (xy 95.102934 -239.663972) (xy 95.209087 -239.822388)
			(xy 95.308467 -239.985139) (xy 95.400897 -240.151934) (xy 95.486214 -240.322478) (xy 95.564266 -240.496466)
			(xy 95.634913 -240.673591) (xy 95.698031 -240.853536) (xy 95.753507 -241.035982) (xy 95.801242 -241.220605)
			(xy 95.841152 -241.407075) (xy 95.873165 -241.595063) (xy 95.897225 -241.784233) (xy 95.913288 -241.974249)
			(xy 95.921327 -242.164773) (xy 95.92183 -242.26012) (xy 95.921327 -242.355467) (xy 95.913288 -242.545991)
			(xy 95.897225 -242.736007) (xy 95.873165 -242.925177) (xy 95.841152 -243.113165) (xy 95.801242 -243.299635)
			(xy 95.753507 -243.484258) (xy 95.698031 -243.666704) (xy 95.634913 -243.846649) (xy 95.564266 -244.023774)
			(xy 95.486214 -244.197762) (xy 95.400897 -244.368306) (xy 95.308467 -244.535101) (xy 95.209087 -244.697852)
			(xy 95.102934 -244.856268) (xy 94.990198 -245.010069) (xy 94.871078 -245.15898) (xy 94.745786 -245.302737)
			(xy 94.614545 -245.441085) (xy 94.477589 -245.573776) (xy 94.335161 -245.700577) (xy 94.187513 -245.82126)
			(xy 94.03491 -245.935612) (xy 93.877622 -246.043428) (xy 93.715928 -246.144519) (xy 93.550116 -246.238703)
			(xy 93.380481 -246.325813) (xy 93.207325 -246.405694) (xy 93.030955 -246.478205) (xy 92.851685 -246.543216)
			(xy 92.669834 -246.600612) (xy 92.485725 -246.650291) (xy 92.299685 -246.692164) (xy 92.112046 -246.726157)
			(xy 91.92314 -246.75221) (xy 91.733304 -246.770276) (xy 91.542875 -246.780323) (xy 91.352192 -246.782333)
			(xy 91.161593 -246.776303) (xy 90.971419 -246.762244) (xy 90.782006 -246.740179) (xy 90.593691 -246.71015)
			(xy 90.40681 -246.672208) (xy 90.221694 -246.626422) (xy 90.038674 -246.572873) (xy 89.858073 -246.511655)
			(xy 89.680214 -246.442879) (xy 89.505412 -246.366666) (xy 89.333978 -246.283152) (xy 89.166218 -246.192485)
			(xy 89.002429 -246.094826) (xy 88.842902 -245.990349) (xy 88.687921 -245.87924) (xy 88.537763 -245.761697)
			(xy 88.392693 -245.637927) (xy 88.252969 -245.508152) (xy 88.118841 -245.372603) (xy 87.990547 -245.231519)
			(xy 87.868313 -245.085152) (xy 87.752359 -244.933763) (xy 87.64289 -244.77762) (xy 87.540101 -244.617001)
			(xy 87.444175 -244.452191) (xy 87.355281 -244.283484) (xy 87.273579 -244.111179) (xy 87.199213 -243.935584)
			(xy 87.132315 -243.757009) (xy 87.073005 -243.575773) (xy 87.021388 -243.392198) (xy 86.977556 -243.20661)
			(xy 86.941587 -243.01934) (xy 86.913544 -242.830719) (xy 86.893478 -242.641084) (xy 86.881424 -242.450771)
			(xy 86.877404 -242.26012) (xy 1.016 -242.26012) (xy 1.016 -250.020582) (xy 3.582162 -250.020582)
			(xy 3.582653 -249.963338) (xy 3.590754 -249.849137) (xy 3.606915 -249.735795) (xy 3.631055 -249.623881)
			(xy 3.663052 -249.513955) (xy 3.702747 -249.406568) (xy 3.74994 -249.302259) (xy 3.804394 -249.20155)
			(xy 3.865837 -249.104947) (xy 3.933962 -249.012932) (xy 4.008425 -248.925969) (xy 4.088855 -248.844491)
			(xy 4.174848 -248.768908) (xy 4.265973 -248.699599) (xy 4.361773 -248.636911) (xy 4.461769 -248.581157)
			(xy 4.565458 -248.532619) (xy 4.672322 -248.491538) (xy 4.781825 -248.458121) (xy 4.893417 -248.432535)
			(xy 5.006541 -248.414908) (xy 5.120627 -248.405329) (xy 5.235106 -248.403846) (xy 5.349402 -248.410467)
			(xy 5.462944 -248.425157) (xy 5.575162 -248.447844) (xy 5.685494 -248.478413) (xy 5.793386 -248.516712)
			(xy 5.898298 -248.562549) (xy 5.999704 -248.615693) (xy 6.097096 -248.675879) (xy 6.189986 -248.742805)
			(xy 6.277908 -248.816135) (xy 6.360421 -248.895501) (xy 6.437112 -248.980507) (xy 6.507597 -249.070726)
			(xy 6.571522 -249.165706) (xy 6.628567 -249.26497) (xy 6.678446 -249.368022) (xy 6.720909 -249.474344)
			(xy 6.755743 -249.583404) (xy 6.782773 -249.694656) (xy 6.801865 -249.807541) (xy 6.812922 -249.921494)
			(xy 6.815888 -250.035944) (xy 6.81075 -250.150316) (xy 6.797533 -250.264039) (xy 6.776303 -250.376542)
			(xy 6.747166 -250.48726) (xy 6.710269 -250.59564) (xy 6.665797 -250.701137) (xy 6.613971 -250.803224)
			(xy 6.555053 -250.901388) (xy 6.489337 -250.995137) (xy 6.453632 -251.039884) (xy 6.059424 -251.039884)
			(xy 6.020367 -251.072253) (xy 5.938107 -251.131626) (xy 5.895086 -251.158502) (xy 5.881509 -251.167452)
			(xy 5.858992 -251.190897) (xy 5.843109 -251.219259) (xy 5.834884 -251.250707) (xy 5.83438 -251.26696)
			(xy 5.83438 -251.50699) (xy 5.834126 -251.50699) (xy 5.779452 -251.529781) (xy 5.667407 -251.568246)
			(xy 5.552848 -251.598407) (xy 5.436387 -251.620101) (xy 5.318652 -251.633212) (xy 5.200272 -251.637669)
			(xy 5.081884 -251.633449) (xy 4.964122 -251.620575) (xy 4.847619 -251.599114) (xy 4.732999 -251.569183)
			(xy 4.620877 -251.530943) (xy 4.566158 -251.50826) (xy 4.565904 -251.50826) (xy 4.565904 -251.26823)
			(xy 4.56544 -251.25195) (xy 4.557181 -251.220454) (xy 4.541219 -251.192074) (xy 4.518594 -251.168658)
			(xy 4.504944 -251.159772) (xy 4.45885 -251.131059) (xy 4.370982 -251.067228) (xy 4.32943 -251.032264)
			(xy 3.937762 -251.032264) (xy 3.903919 -250.989342) (xy 3.841441 -250.89964) (xy 3.785164 -250.805923)
			(xy 3.735346 -250.708619) (xy 3.692214 -250.608172) (xy 3.655964 -250.505042) (xy 3.626762 -250.399698)
			(xy 3.604742 -250.292623) (xy 3.590005 -250.184306) (xy 3.582617 -250.07524) (xy 3.582162 -250.020582)
			(xy 1.016 -250.020582) (xy 1.016 -253.671578) (xy 1.016492 -253.686921) (xy 1.023881 -253.716707)
			(xy 1.038164 -253.74387) (xy 1.048004 -253.755652) (xy 1.065976 -253.776695) (xy 1.09629 -253.822991)
			(xy 1.119599 -253.87318) (xy 1.135415 -253.92621) (xy 1.143407 -253.980967) (xy 1.143407 -254.036305)
			(xy 1.135415 -254.091062) (xy 1.119599 -254.144092) (xy 1.09629 -254.194281) (xy 1.065976 -254.240577)
			(xy 1.048004 -254.26162) (xy 1.03813 -254.273379) (xy 1.023835 -254.300546) (xy 1.01646 -254.330345)
			(xy 1.016 -254.345694) (xy 1.016 -266.371578) (xy 1.016492 -266.386921) (xy 1.023881 -266.416707)
			(xy 1.038164 -266.44387) (xy 1.048004 -266.455652) (xy 1.065976 -266.476695) (xy 1.09629 -266.522991)
			(xy 1.119599 -266.57318) (xy 1.135415 -266.62621) (xy 1.143407 -266.680967) (xy 1.143407 -266.736305)
			(xy 1.135415 -266.791062) (xy 1.119599 -266.844092) (xy 1.09629 -266.894281) (xy 1.065976 -266.940577)
			(xy 1.048004 -266.96162) (xy 1.03813 -266.973379) (xy 1.023835 -267.000546) (xy 1.01646 -267.030345)
			(xy 1.016 -267.045694) (xy 1.016 -267.850739) (xy 3.584556 -267.850739) (xy 3.589879 -267.737285)
			(xy 3.603163 -267.624485) (xy 3.624341 -267.512897) (xy 3.653308 -267.403074) (xy 3.689922 -267.295558)
			(xy 3.734001 -267.190881) (xy 3.785327 -267.08956) (xy 3.843647 -266.992097) (xy 3.908672 -266.898974)
			(xy 3.980081 -266.81065) (xy 4.05752 -266.727563) (xy 4.140607 -266.650124) (xy 4.228931 -266.578715)
			(xy 4.322054 -266.51369) (xy 4.419517 -266.455369) (xy 4.520837 -266.404043) (xy 4.625514 -266.359963)
			(xy 4.73303 -266.323349) (xy 4.842854 -266.294382) (xy 4.954441 -266.273204) (xy 5.067241 -266.25992)
			(xy 5.180695 -266.254596) (xy 5.294243 -266.257258) (xy 5.407324 -266.267894) (xy 5.519377 -266.28645)
			(xy 5.629849 -266.312835) (xy 5.738194 -266.346919) (xy 5.843876 -266.388532) (xy 5.946371 -266.437469)
			(xy 6.045175 -266.493488) (xy 6.139797 -266.556312) (xy 6.229771 -266.625631) (xy 6.31465 -266.701101)
			(xy 6.394016 -266.78235) (xy 6.467475 -266.868975) (xy 6.534666 -266.960549) (xy 6.595255 -267.056618)
			(xy 6.648942 -267.156707) (xy 6.695463 -267.260322) (xy 6.734588 -267.36695) (xy 6.766122 -267.476064)
			(xy 6.78991 -267.587124) (xy 6.805834 -267.699582) (xy 6.813816 -267.81288) (xy 6.814312 -267.86967)
			(xy 6.813806 -267.92732) (xy 6.805599 -268.042327) (xy 6.789208 -268.156456) (xy 6.764716 -268.269125)
			(xy 6.73225 -268.37976) (xy 6.691973 -268.487796) (xy 6.644093 -268.592684) (xy 6.588851 -268.693889)
			(xy 6.52653 -268.790895) (xy 6.457448 -268.883208) (xy 6.381956 -268.970358) (xy 6.30044 -269.0519)
			(xy 6.213314 -269.127419) (xy 6.121023 -269.196531) (xy 6.024036 -269.258882) (xy 5.922848 -269.314155)
			(xy 5.817976 -269.362069) (xy 5.709952 -269.402379) (xy 5.599327 -269.434881) (xy 5.486666 -269.459407)
			(xy 5.372543 -269.475834) (xy 5.257538 -269.484078) (xy 5.199888 -269.484602) (xy 5.199634 -269.484602)
			(xy 5.199634 -269.484348) (xy 5.142844 -269.483856) (xy 5.029546 -269.475875) (xy 4.917088 -269.459951)
			(xy 4.806028 -269.436163) (xy 4.696914 -269.404629) (xy 4.590286 -269.365505) (xy 4.486671 -269.318984)
			(xy 4.386581 -269.265297) (xy 4.290512 -269.204708) (xy 4.198938 -269.137518) (xy 4.112313 -269.064058)
			(xy 4.031064 -268.984693) (xy 3.955594 -268.899814) (xy 3.886275 -268.80984) (xy 3.82345 -268.715218)
			(xy 3.767431 -268.616415) (xy 3.718493 -268.513919) (xy 3.67688 -268.408238) (xy 3.642796 -268.299893)
			(xy 3.616411 -268.189421) (xy 3.597855 -268.077368) (xy 3.587219 -267.964287) (xy 3.584556 -267.850739)
			(xy 1.016 -267.850739) (xy 1.016 -273.61007) (xy 39.818564 -273.61007) (xy 39.819058 -273.552661)
			(xy 39.826902 -273.438113) (xy 39.842544 -273.324366) (xy 39.865911 -273.211952) (xy 39.896896 -273.101394)
			(xy 39.935352 -272.993209) (xy 39.981101 -272.8879) (xy 40.03393 -272.785958) (xy 40.093592 -272.687859)
			(xy 40.159809 -272.59406) (xy 40.232272 -272.504998) (xy 40.310645 -272.421089) (xy 40.39456 -272.342723)
			(xy 40.483627 -272.270266) (xy 40.577431 -272.204056) (xy 40.675535 -272.144402) (xy 40.777481 -272.091581)
			(xy 40.882793 -272.045839) (xy 40.990981 -272.007391) (xy 41.101541 -271.976415) (xy 41.213957 -271.953056)
			(xy 41.327705 -271.937423) (xy 41.442254 -271.929588) (xy 41.557072 -271.929588) (xy 41.671621 -271.937423)
			(xy 41.785369 -271.953056) (xy 41.897785 -271.976415) (xy 42.008345 -272.007391) (xy 42.116533 -272.045839)
			(xy 42.221845 -272.091581) (xy 42.323791 -272.144402) (xy 42.421895 -272.204056) (xy 42.515699 -272.270266)
			(xy 42.604766 -272.342723) (xy 42.688681 -272.421089) (xy 42.767054 -272.504998) (xy 42.839517 -272.59406)
			(xy 42.905734 -272.687859) (xy 42.965396 -272.785958) (xy 43.018225 -272.8879) (xy 43.063974 -272.993209)
			(xy 43.10243 -273.101394) (xy 43.133415 -273.211952) (xy 43.156782 -273.324366) (xy 43.172424 -273.438113)
			(xy 43.180268 -273.552661) (xy 43.180762 -273.61007) (xy 43.180576 -273.643253) (xy 43.177909 -273.709567)
			(xy 43.175428 -273.742658) (xy 43.170272 -273.800942) (xy 43.152948 -273.916671) (xy 43.127616 -274.030914)
			(xy 43.094401 -274.143119) (xy 43.053462 -274.252742) (xy 43.004999 -274.359253) (xy 42.949245 -274.462135)
			(xy 42.886471 -274.560891) (xy 42.816981 -274.655042) (xy 42.741111 -274.744132) (xy 42.659229 -274.827729)
			(xy 42.571732 -274.90543) (xy 42.500813 -274.96008) (xy 93.154506 -274.96008) (xy 93.158522 -274.84381)
			(xy 93.170549 -274.728095) (xy 93.190531 -274.613485) (xy 93.218373 -274.500526) (xy 93.253942 -274.389758)
			(xy 93.297068 -274.281707) (xy 93.347545 -274.176889) (xy 93.405134 -274.075804) (xy 93.46956 -273.978932)
			(xy 93.540515 -273.886736) (xy 93.617662 -273.799655) (xy 93.700633 -273.718104) (xy 93.789033 -273.642472)
			(xy 93.88244 -273.573118) (xy 93.980409 -273.510375) (xy 94.082473 -273.454539) (xy 94.188147 -273.405878)
			(xy 94.296926 -273.364624) (xy 94.408291 -273.330973) (xy 94.521714 -273.305085) (xy 94.636651 -273.287084)
			(xy 94.752557 -273.277055) (xy 94.868879 -273.275047) (xy 94.985062 -273.281069) (xy 95.100553 -273.295092)
			(xy 95.214801 -273.31705) (xy 95.327262 -273.346837) (xy 95.4374 -273.384312) (xy 95.54469 -273.429297)
			(xy 95.648621 -273.481576) (xy 95.748697 -273.540901) (xy 95.844443 -273.606989) (xy 95.9354 -273.679525)
			(xy 96.021136 -273.758164) (xy 96.101243 -273.84253) (xy 96.175339 -273.932222) (xy 96.243069 -274.026812)
			(xy 96.304113 -274.12585) (xy 96.358178 -274.228863) (xy 96.405008 -274.33536) (xy 96.444379 -274.444835)
			(xy 96.476103 -274.556765) (xy 96.500029 -274.670617) (xy 96.516043 -274.785849) (xy 96.52407 -274.901911)
			(xy 96.524572 -274.96008) (xy 96.52407 -275.018249) (xy 96.516043 -275.134311) (xy 96.500029 -275.249543)
			(xy 96.476103 -275.363395) (xy 96.444379 -275.475325) (xy 96.405008 -275.5848) (xy 96.358178 -275.691297)
			(xy 96.304113 -275.79431) (xy 96.243069 -275.893348) (xy 96.175339 -275.987938) (xy 96.101243 -276.07763)
			(xy 96.021136 -276.161996) (xy 95.9354 -276.240635) (xy 95.844443 -276.313171) (xy 95.748697 -276.379259)
			(xy 95.648621 -276.438584) (xy 95.54469 -276.490863) (xy 95.4374 -276.535848) (xy 95.327262 -276.573323)
			(xy 95.214801 -276.60311) (xy 95.100553 -276.625068) (xy 94.985062 -276.639091) (xy 94.868879 -276.645113)
			(xy 94.752557 -276.643105) (xy 94.636651 -276.633076) (xy 94.521714 -276.615075) (xy 94.408291 -276.589187)
			(xy 94.296926 -276.555536) (xy 94.188147 -276.514282) (xy 94.082473 -276.465621) (xy 93.980409 -276.409785)
			(xy 93.88244 -276.347042) (xy 93.789033 -276.277688) (xy 93.700633 -276.202056) (xy 93.617662 -276.120505)
			(xy 93.540515 -276.033424) (xy 93.46956 -275.941228) (xy 93.405134 -275.844356) (xy 93.347545 -275.743271)
			(xy 93.297068 -275.638453) (xy 93.253942 -275.530402) (xy 93.218373 -275.419634) (xy 93.190531 -275.306675)
			(xy 93.170549 -275.192065) (xy 93.158522 -275.07635) (xy 93.154506 -274.96008) (xy 42.500813 -274.96008)
			(xy 42.479042 -274.976857) (xy 42.381609 -275.041665) (xy 42.279905 -275.09954) (xy 42.174422 -275.150202)
			(xy 42.065671 -275.193404) (xy 41.954179 -275.228939) (xy 41.840485 -275.256634) (xy 41.725141 -275.276354)
			(xy 41.608704 -275.288005) (xy 41.491739 -275.29153) (xy 41.374812 -275.286912) (xy 41.258489 -275.274173)
			(xy 41.143334 -275.253375) (xy 41.029905 -275.224618) (xy 40.91875 -275.188042) (xy 40.810407 -275.143825)
			(xy 40.705403 -275.092179) (xy 40.604244 -275.033356) (xy 40.507421 -274.96764) (xy 40.415403 -274.895349)
			(xy 40.328636 -274.816834) (xy 40.247539 -274.732474) (xy 40.172506 -274.642679) (xy 40.103899 -274.547883)
			(xy 40.042051 -274.448544) (xy 39.987262 -274.345145) (xy 39.939796 -274.238186) (xy 39.899884 -274.128185)
			(xy 39.86772 -274.015674) (xy 39.843457 -273.901199) (xy 39.827215 -273.785313) (xy 39.819072 -273.668579)
			(xy 39.818564 -273.61007) (xy 1.016 -273.61007) (xy 1.016 -279.071578) (xy 1.016492 -279.086921)
			(xy 1.023881 -279.116707) (xy 1.038164 -279.14387) (xy 1.048004 -279.155652) (xy 1.065976 -279.176695)
			(xy 1.09629 -279.222991) (xy 1.119599 -279.27318) (xy 1.135415 -279.32621) (xy 1.143407 -279.380967)
			(xy 1.143407 -279.436305) (xy 1.135415 -279.491062) (xy 1.119599 -279.544092) (xy 1.09629 -279.594281)
			(xy 1.065976 -279.640577) (xy 1.048004 -279.66162) (xy 1.03813 -279.673379) (xy 1.023835 -279.700546)
			(xy 1.01646 -279.730345) (xy 1.016 -279.745694) (xy 1.016 -286.709866) (xy 86.877404 -286.709866)
			(xy 86.881424 -286.519215) (xy 86.893478 -286.328902) (xy 86.913544 -286.139267) (xy 86.941587 -285.950646)
			(xy 86.977556 -285.763376) (xy 87.021388 -285.577788) (xy 87.073005 -285.394213) (xy 87.132315 -285.212977)
			(xy 87.199213 -285.034402) (xy 87.273579 -284.858807) (xy 87.355281 -284.686502) (xy 87.444175 -284.517795)
			(xy 87.540101 -284.352985) (xy 87.64289 -284.192366) (xy 87.752359 -284.036223) (xy 87.868313 -283.884834)
			(xy 87.990547 -283.738467) (xy 88.118841 -283.597383) (xy 88.252969 -283.461834) (xy 88.392693 -283.332059)
			(xy 88.537763 -283.208289) (xy 88.687921 -283.090746) (xy 88.842902 -282.979637) (xy 89.002429 -282.87516)
			(xy 89.166218 -282.777501) (xy 89.333978 -282.686834) (xy 89.505412 -282.60332) (xy 89.680214 -282.527107)
			(xy 89.858073 -282.458331) (xy 90.038674 -282.397113) (xy 90.221694 -282.343564) (xy 90.40681 -282.297778)
			(xy 90.593691 -282.259836) (xy 90.782006 -282.229807) (xy 90.971419 -282.207742) (xy 91.161593 -282.193683)
			(xy 91.352192 -282.187653) (xy 91.542875 -282.189663) (xy 91.733304 -282.19971) (xy 91.92314 -282.217776)
			(xy 92.112046 -282.243829) (xy 92.299685 -282.277822) (xy 92.485725 -282.319695) (xy 92.669834 -282.369374)
			(xy 92.851685 -282.42677) (xy 93.030955 -282.491781) (xy 93.207325 -282.564292) (xy 93.380481 -282.644173)
			(xy 93.550116 -282.731283) (xy 93.715928 -282.825467) (xy 93.877622 -282.926558) (xy 94.03491 -283.034374)
			(xy 94.187513 -283.148726) (xy 94.335161 -283.269409) (xy 94.477589 -283.39621) (xy 94.614545 -283.528901)
			(xy 94.745786 -283.667249) (xy 94.871078 -283.811006) (xy 94.990198 -283.959917) (xy 95.102934 -284.113718)
			(xy 95.209087 -284.272134) (xy 95.308467 -284.434885) (xy 95.400897 -284.60168) (xy 95.486214 -284.772224)
			(xy 95.564266 -284.946212) (xy 95.634913 -285.123337) (xy 95.698031 -285.303282) (xy 95.753507 -285.485728)
			(xy 95.801242 -285.670351) (xy 95.841152 -285.856821) (xy 95.873165 -286.044809) (xy 95.897225 -286.233979)
			(xy 95.913288 -286.423995) (xy 95.921327 -286.614519) (xy 95.92183 -286.709866) (xy 95.921327 -286.805213)
			(xy 95.913288 -286.995737) (xy 95.897225 -287.185753) (xy 95.873165 -287.374923) (xy 95.841152 -287.562911)
			(xy 95.801242 -287.749381) (xy 95.753507 -287.934004) (xy 95.698031 -288.11645) (xy 95.634913 -288.296395)
			(xy 95.564266 -288.47352) (xy 95.486214 -288.647508) (xy 95.400897 -288.818052) (xy 95.308467 -288.984847)
			(xy 95.209087 -289.147598) (xy 95.102934 -289.306014) (xy 94.990198 -289.459815) (xy 94.871078 -289.608726)
			(xy 94.745786 -289.752483) (xy 94.614545 -289.890831) (xy 94.477589 -290.023522) (xy 94.335161 -290.150323)
			(xy 94.187513 -290.271006) (xy 94.03491 -290.385358) (xy 93.877622 -290.493174) (xy 93.715928 -290.594265)
			(xy 93.550116 -290.688449) (xy 93.380481 -290.775559) (xy 93.207325 -290.85544) (xy 93.030955 -290.927951)
			(xy 92.851685 -290.992962) (xy 92.669834 -291.050358) (xy 92.485725 -291.100037) (xy 92.299685 -291.14191)
			(xy 92.112046 -291.175903) (xy 91.92314 -291.201956) (xy 91.733304 -291.220022) (xy 91.542875 -291.230069)
			(xy 91.352192 -291.232079) (xy 91.161593 -291.226049) (xy 90.971419 -291.21199) (xy 90.782006 -291.189925)
			(xy 90.593691 -291.159896) (xy 90.40681 -291.121954) (xy 90.221694 -291.076168) (xy 90.038674 -291.022619)
			(xy 89.858073 -290.961401) (xy 89.680214 -290.892625) (xy 89.505412 -290.816412) (xy 89.333978 -290.732898)
			(xy 89.166218 -290.642231) (xy 89.002429 -290.544572) (xy 88.842902 -290.440095) (xy 88.687921 -290.328986)
			(xy 88.537763 -290.211443) (xy 88.392693 -290.087673) (xy 88.252969 -289.957898) (xy 88.118841 -289.822349)
			(xy 87.990547 -289.681265) (xy 87.868313 -289.534898) (xy 87.752359 -289.383509) (xy 87.64289 -289.227366)
			(xy 87.540101 -289.066747) (xy 87.444175 -288.901937) (xy 87.355281 -288.73323) (xy 87.273579 -288.560925)
			(xy 87.199213 -288.38533) (xy 87.132315 -288.206755) (xy 87.073005 -288.025519) (xy 87.021388 -287.841944)
			(xy 86.977556 -287.656356) (xy 86.941587 -287.469086) (xy 86.913544 -287.280465) (xy 86.893478 -287.09083)
			(xy 86.881424 -286.900517) (xy 86.877404 -286.709866) (xy 1.016 -286.709866) (xy 1.016 -291.771578)
			(xy 1.016492 -291.786921) (xy 1.023881 -291.816707) (xy 1.038164 -291.84387) (xy 1.048004 -291.855652)
			(xy 1.065976 -291.876695) (xy 1.09629 -291.922991) (xy 1.119599 -291.97318) (xy 1.135415 -292.02621)
			(xy 1.143407 -292.080967) (xy 1.143407 -292.136305) (xy 1.135415 -292.191062) (xy 1.119599 -292.244092)
			(xy 1.09629 -292.294281) (xy 1.065976 -292.340577) (xy 1.048004 -292.36162) (xy 1.03813 -292.373379)
			(xy 1.023835 -292.400546) (xy 1.01646 -292.430345) (xy 1.016 -292.445694) (xy 1.016 -295.89984) (xy 11.34441 -295.89984)
			(xy 11.348411 -295.694791) (xy 11.36041 -295.490054) (xy 11.380388 -295.285941) (xy 11.408314 -295.082762)
			(xy 11.444146 -294.880829) (xy 11.48783 -294.680446) (xy 11.539298 -294.481921) (xy 11.598473 -294.285555)
			(xy 11.665264 -294.091648) (xy 11.73957 -293.900494) (xy 11.821277 -293.712384) (xy 11.910262 -293.527606)
			(xy 12.006388 -293.34644) (xy 12.109509 -293.169163) (xy 12.219469 -292.996044) (xy 12.336099 -292.827347)
			(xy 12.459222 -292.663329) (xy 12.588651 -292.50424) (xy 12.724188 -292.350322) (xy 12.865627 -292.201808)
			(xy 13.012754 -292.058927) (xy 13.165342 -291.921894) (xy 13.323161 -291.79092) (xy 13.48597 -291.666202)
			(xy 13.653521 -291.547932) (xy 13.825559 -291.436288) (xy 14.001822 -291.331442) (xy 14.182041 -291.233553)
			(xy 14.365942 -291.14277) (xy 14.553246 -291.059232) (xy 14.743666 -290.983064) (xy 14.936912 -290.914384)
			(xy 15.132692 -290.853296) (xy 15.330705 -290.799894) (xy 15.530652 -290.754257) (xy 15.732226 -290.716457)
			(xy 15.935122 -290.686549) (xy 16.139031 -290.664581) (xy 16.343641 -290.650586) (xy 16.548641 -290.644584)
			(xy 16.75372 -290.646585) (xy 16.958564 -290.656585) (xy 17.162863 -290.674571) (xy 17.366304 -290.700513)
			(xy 17.568577 -290.734374) (xy 17.769376 -290.7761) (xy 17.968394 -290.825629) (xy 18.165328 -290.882885)
			(xy 18.359878 -290.947782) (xy 18.551748 -291.020219) (xy 18.740645 -291.100087) (xy 18.926283 -291.187265)
			(xy 19.108378 -291.281619) (xy 19.286653 -291.383006) (xy 19.460836 -291.491271) (xy 19.630663 -291.606249)
			(xy 19.795875 -291.727767) (xy 19.956219 -291.855637) (xy 20.111453 -291.989666) (xy 20.261339 -292.12965)
			(xy 20.405649 -292.275375) (xy 20.544163 -292.42662) (xy 20.676672 -292.583153) (xy 20.802972 -292.744738)
			(xy 20.922871 -292.911127) (xy 21.036188 -293.082067) (xy 21.142748 -293.257299) (xy 21.242391 -293.436554)
			(xy 21.334964 -293.619561) (xy 21.420326 -293.80604) (xy 21.498347 -293.995708) (xy 21.56891 -294.188276)
			(xy 21.631905 -294.38345) (xy 21.687237 -294.580933) (xy 21.734822 -294.780424) (xy 21.774587 -294.981621)
			(xy 21.806472 -295.184215) (xy 21.830429 -295.3879) (xy 21.84642 -295.592364) (xy 21.854422 -295.797296)
			(xy 21.854922 -295.89984) (xy 21.854422 -296.002384) (xy 21.84642 -296.207316) (xy 21.830429 -296.41178)
			(xy 21.806472 -296.615465) (xy 21.774587 -296.818059) (xy 21.734822 -297.019256) (xy 21.687237 -297.218747)
			(xy 21.631905 -297.41623) (xy 21.56891 -297.611404) (xy 21.498347 -297.803972) (xy 21.420326 -297.99364)
			(xy 21.334964 -298.180119) (xy 21.242391 -298.363126) (xy 21.142748 -298.542381) (xy 21.036188 -298.717613)
			(xy 20.922871 -298.888553) (xy 20.802972 -299.054942) (xy 20.676672 -299.216527) (xy 20.544163 -299.37306)
			(xy 20.405649 -299.524305) (xy 20.261339 -299.67003) (xy 20.111453 -299.810014) (xy 19.956219 -299.944043)
			(xy 19.795875 -300.071913) (xy 19.630663 -300.193431) (xy 19.460836 -300.308409) (xy 19.286653 -300.416674)
			(xy 19.108378 -300.518061) (xy 18.926283 -300.612415) (xy 18.740645 -300.699593) (xy 18.551748 -300.779461)
			(xy 18.359878 -300.851898) (xy 18.165328 -300.916795) (xy 17.968394 -300.974051) (xy 17.769376 -301.02358)
			(xy 17.568577 -301.065306) (xy 17.366304 -301.099167) (xy 17.162863 -301.125109) (xy 16.958564 -301.143095)
			(xy 16.75372 -301.153095) (xy 16.548641 -301.155096) (xy 16.343641 -301.149094) (xy 16.139031 -301.135099)
			(xy 15.935122 -301.113131) (xy 15.732226 -301.083223) (xy 15.530652 -301.045423) (xy 15.330705 -300.999786)
			(xy 15.132692 -300.946384) (xy 14.936912 -300.885296) (xy 14.743666 -300.816616) (xy 14.553246 -300.740448)
			(xy 14.365942 -300.65691) (xy 14.182041 -300.566127) (xy 14.001822 -300.468238) (xy 13.825559 -300.363392)
			(xy 13.653521 -300.251748) (xy 13.48597 -300.133478) (xy 13.323161 -300.00876) (xy 13.165342 -299.877786)
			(xy 13.012754 -299.740753) (xy 12.865627 -299.597872) (xy 12.724188 -299.449358) (xy 12.588651 -299.29544)
			(xy 12.459222 -299.136351) (xy 12.336099 -298.972333) (xy 12.219469 -298.803636) (xy 12.109509 -298.630517)
			(xy 12.006388 -298.45324) (xy 11.910262 -298.272074) (xy 11.821277 -298.087296) (xy 11.73957 -297.899186)
			(xy 11.665264 -297.708032) (xy 11.598473 -297.514125) (xy 11.539298 -297.317759) (xy 11.48783 -297.119234)
			(xy 11.444146 -296.918851) (xy 11.408314 -296.716918) (xy 11.380388 -296.513739) (xy 11.36041 -296.309626)
			(xy 11.348411 -296.104889) (xy 11.34441 -295.89984) (xy 1.016 -295.89984) (xy 1.016 -304.471578)
			(xy 1.016492 -304.486921) (xy 1.023881 -304.516707) (xy 1.038164 -304.54387) (xy 1.048004 -304.555652)
			(xy 1.065976 -304.576695) (xy 1.09629 -304.622991) (xy 1.119599 -304.67318) (xy 1.135415 -304.72621)
			(xy 1.143407 -304.780967) (xy 1.143407 -304.836305) (xy 1.135415 -304.891062) (xy 1.119599 -304.944092)
			(xy 1.09629 -304.994281) (xy 1.065976 -305.040577) (xy 1.048004 -305.06162) (xy 1.03813 -305.073379)
			(xy 1.023835 -305.100546) (xy 1.01646 -305.130345) (xy 1.016 -305.145694) (xy 1.016 -317.171578)
			(xy 1.016492 -317.186921) (xy 1.023881 -317.216707) (xy 1.038164 -317.24387) (xy 1.048004 -317.255652)
			(xy 1.065976 -317.276695) (xy 1.09629 -317.322991) (xy 1.119599 -317.37318) (xy 1.135415 -317.42621)
			(xy 1.143407 -317.480967) (xy 1.143407 -317.536305) (xy 1.135415 -317.591062) (xy 1.119599 -317.644092)
			(xy 1.09629 -317.694281) (xy 1.065976 -317.740577) (xy 1.048004 -317.76162) (xy 1.03813 -317.773379)
			(xy 1.023835 -317.800546) (xy 1.01646 -317.830345) (xy 1.016 -317.845694) (xy 1.016 -318.06007) (xy 39.818564 -318.06007)
			(xy 39.819058 -318.002661) (xy 39.826902 -317.888113) (xy 39.842544 -317.774366) (xy 39.865911 -317.661952)
			(xy 39.896896 -317.551394) (xy 39.935352 -317.443209) (xy 39.981101 -317.3379) (xy 40.03393 -317.235958)
			(xy 40.093592 -317.137859) (xy 40.159809 -317.04406) (xy 40.232272 -316.954998) (xy 40.310645 -316.871089)
			(xy 40.39456 -316.792723) (xy 40.483627 -316.720266) (xy 40.577431 -316.654056) (xy 40.675535 -316.594402)
			(xy 40.777481 -316.541581) (xy 40.882793 -316.495839) (xy 40.990981 -316.457391) (xy 41.101541 -316.426415)
			(xy 41.213957 -316.403056) (xy 41.327705 -316.387423) (xy 41.442254 -316.379588) (xy 41.557072 -316.379588)
			(xy 41.671621 -316.387423) (xy 41.785369 -316.403056) (xy 41.897785 -316.426415) (xy 42.008345 -316.457391)
			(xy 42.116533 -316.495839) (xy 42.221845 -316.541581) (xy 42.323791 -316.594402) (xy 42.421895 -316.654056)
			(xy 42.515699 -316.720266) (xy 42.604766 -316.792723) (xy 42.688681 -316.871089) (xy 42.767054 -316.954998)
			(xy 42.839517 -317.04406) (xy 42.905734 -317.137859) (xy 42.965396 -317.235958) (xy 43.018225 -317.3379)
			(xy 43.063974 -317.443209) (xy 43.10243 -317.551394) (xy 43.133415 -317.661952) (xy 43.156782 -317.774366)
			(xy 43.172424 -317.888113) (xy 43.180268 -318.002661) (xy 43.180762 -318.06007) (xy 43.180576 -318.093253)
			(xy 43.177909 -318.159567) (xy 43.175428 -318.192658) (xy 43.170272 -318.250942) (xy 43.152948 -318.366671)
			(xy 43.127616 -318.480914) (xy 43.094401 -318.593119) (xy 43.053462 -318.702742) (xy 43.004999 -318.809253)
			(xy 42.949245 -318.912135) (xy 42.886471 -319.010891) (xy 42.816981 -319.105042) (xy 42.741111 -319.194132)
			(xy 42.659229 -319.277729) (xy 42.571732 -319.35543) (xy 42.500813 -319.41008) (xy 93.154506 -319.41008)
			(xy 93.158522 -319.29381) (xy 93.170549 -319.178095) (xy 93.190531 -319.063485) (xy 93.218373 -318.950526)
			(xy 93.253942 -318.839758) (xy 93.297068 -318.731707) (xy 93.347545 -318.626889) (xy 93.405134 -318.525804)
			(xy 93.46956 -318.428932) (xy 93.540515 -318.336736) (xy 93.617662 -318.249655) (xy 93.700633 -318.168104)
			(xy 93.789033 -318.092472) (xy 93.88244 -318.023118) (xy 93.980409 -317.960375) (xy 94.082473 -317.904539)
			(xy 94.188147 -317.855878) (xy 94.296926 -317.814624) (xy 94.408291 -317.780973) (xy 94.521714 -317.755085)
			(xy 94.636651 -317.737084) (xy 94.752557 -317.727055) (xy 94.868879 -317.725047) (xy 94.985062 -317.731069)
			(xy 95.100553 -317.745092) (xy 95.214801 -317.76705) (xy 95.327262 -317.796837) (xy 95.4374 -317.834312)
			(xy 95.54469 -317.879297) (xy 95.648621 -317.931576) (xy 95.748697 -317.990901) (xy 95.844443 -318.056989)
			(xy 95.9354 -318.129525) (xy 96.021136 -318.208164) (xy 96.101243 -318.29253) (xy 96.175339 -318.382222)
			(xy 96.243069 -318.476812) (xy 96.304113 -318.57585) (xy 96.358178 -318.678863) (xy 96.405008 -318.78536)
			(xy 96.444379 -318.894835) (xy 96.476103 -319.006765) (xy 96.500029 -319.120617) (xy 96.516043 -319.235849)
			(xy 96.52407 -319.351911) (xy 96.524572 -319.41008) (xy 96.52407 -319.468249) (xy 96.516043 -319.584311)
			(xy 96.500029 -319.699543) (xy 96.476103 -319.813395) (xy 96.444379 -319.925325) (xy 96.405008 -320.0348)
			(xy 96.358178 -320.141297) (xy 96.304113 -320.24431) (xy 96.243069 -320.343348) (xy 96.175339 -320.437938)
			(xy 96.101243 -320.52763) (xy 96.021136 -320.611996) (xy 95.9354 -320.690635) (xy 95.844443 -320.763171)
			(xy 95.748697 -320.829259) (xy 95.648621 -320.888584) (xy 95.54469 -320.940863) (xy 95.4374 -320.985848)
			(xy 95.327262 -321.023323) (xy 95.214801 -321.05311) (xy 95.100553 -321.075068) (xy 94.985062 -321.089091)
			(xy 94.868879 -321.095113) (xy 94.752557 -321.093105) (xy 94.636651 -321.083076) (xy 94.521714 -321.065075)
			(xy 94.408291 -321.039187) (xy 94.296926 -321.005536) (xy 94.188147 -320.964282) (xy 94.082473 -320.915621)
			(xy 93.980409 -320.859785) (xy 93.88244 -320.797042) (xy 93.789033 -320.727688) (xy 93.700633 -320.652056)
			(xy 93.617662 -320.570505) (xy 93.540515 -320.483424) (xy 93.46956 -320.391228) (xy 93.405134 -320.294356)
			(xy 93.347545 -320.193271) (xy 93.297068 -320.088453) (xy 93.253942 -319.980402) (xy 93.218373 -319.869634)
			(xy 93.190531 -319.756675) (xy 93.170549 -319.642065) (xy 93.158522 -319.52635) (xy 93.154506 -319.41008)
			(xy 42.500813 -319.41008) (xy 42.479042 -319.426857) (xy 42.381609 -319.491665) (xy 42.279905 -319.54954)
			(xy 42.174422 -319.600202) (xy 42.065671 -319.643404) (xy 41.954179 -319.678939) (xy 41.840485 -319.706634)
			(xy 41.725141 -319.726354) (xy 41.608704 -319.738005) (xy 41.491739 -319.74153) (xy 41.374812 -319.736912)
			(xy 41.258489 -319.724173) (xy 41.143334 -319.703375) (xy 41.029905 -319.674618) (xy 40.91875 -319.638042)
			(xy 40.810407 -319.593825) (xy 40.705403 -319.542179) (xy 40.604244 -319.483356) (xy 40.507421 -319.41764)
			(xy 40.415403 -319.345349) (xy 40.328636 -319.266834) (xy 40.247539 -319.182474) (xy 40.172506 -319.092679)
			(xy 40.103899 -318.997883) (xy 40.042051 -318.898544) (xy 39.987262 -318.795145) (xy 39.939796 -318.688186)
			(xy 39.899884 -318.578185) (xy 39.86772 -318.465674) (xy 39.843457 -318.351199) (xy 39.827215 -318.235313)
			(xy 39.819072 -318.118579) (xy 39.818564 -318.06007) (xy 1.016 -318.06007) (xy 1.016 -329.871578)
			(xy 1.016492 -329.886921) (xy 1.023881 -329.916707) (xy 1.038164 -329.94387) (xy 1.048004 -329.955652)
			(xy 1.065976 -329.976695) (xy 1.09629 -330.022991) (xy 1.119599 -330.07318) (xy 1.135415 -330.12621)
			(xy 1.143407 -330.180967) (xy 1.143407 -330.236305) (xy 1.135415 -330.291062) (xy 1.119599 -330.344092)
			(xy 1.09629 -330.394281) (xy 1.065976 -330.440577) (xy 1.048004 -330.46162) (xy 1.03813 -330.473379)
			(xy 1.023835 -330.500546) (xy 1.01646 -330.530345) (xy 1.016 -330.545694) (xy 1.016 -331.16012) (xy 86.877404 -331.16012)
			(xy 86.881424 -330.969469) (xy 86.893478 -330.779156) (xy 86.913544 -330.589521) (xy 86.941587 -330.4009)
			(xy 86.977556 -330.21363) (xy 87.021388 -330.028042) (xy 87.073005 -329.844467) (xy 87.132315 -329.663231)
			(xy 87.199213 -329.484656) (xy 87.273579 -329.309061) (xy 87.355281 -329.136756) (xy 87.444175 -328.968049)
			(xy 87.540101 -328.803239) (xy 87.64289 -328.64262) (xy 87.752359 -328.486477) (xy 87.868313 -328.335088)
			(xy 87.990547 -328.188721) (xy 88.118841 -328.047637) (xy 88.252969 -327.912088) (xy 88.392693 -327.782313)
			(xy 88.537763 -327.658543) (xy 88.687921 -327.541) (xy 88.842902 -327.429891) (xy 89.002429 -327.325414)
			(xy 89.166218 -327.227755) (xy 89.333978 -327.137088) (xy 89.505412 -327.053574) (xy 89.680214 -326.977361)
			(xy 89.858073 -326.908585) (xy 90.038674 -326.847367) (xy 90.221694 -326.793818) (xy 90.40681 -326.748032)
			(xy 90.593691 -326.71009) (xy 90.782006 -326.680061) (xy 90.971419 -326.657996) (xy 91.161593 -326.643937)
			(xy 91.352192 -326.637907) (xy 91.542875 -326.639917) (xy 91.733304 -326.649964) (xy 91.92314 -326.66803)
			(xy 92.112046 -326.694083) (xy 92.299685 -326.728076) (xy 92.485725 -326.769949) (xy 92.669834 -326.819628)
			(xy 92.851685 -326.877024) (xy 93.030955 -326.942035) (xy 93.207325 -327.014546) (xy 93.380481 -327.094427)
			(xy 93.550116 -327.181537) (xy 93.715928 -327.275721) (xy 93.877622 -327.376812) (xy 94.03491 -327.484628)
			(xy 94.187513 -327.59898) (xy 94.335161 -327.719663) (xy 94.477589 -327.846464) (xy 94.614545 -327.979155)
			(xy 94.745786 -328.117503) (xy 94.871078 -328.26126) (xy 94.990198 -328.410171) (xy 95.102934 -328.563972)
			(xy 95.209087 -328.722388) (xy 95.308467 -328.885139) (xy 95.400897 -329.051934) (xy 95.486214 -329.222478)
			(xy 95.564266 -329.396466) (xy 95.634913 -329.573591) (xy 95.698031 -329.753536) (xy 95.753507 -329.935982)
			(xy 95.801242 -330.120605) (xy 95.841152 -330.307075) (xy 95.873165 -330.495063) (xy 95.897225 -330.684233)
			(xy 95.913288 -330.874249) (xy 95.921327 -331.064773) (xy 95.92183 -331.16012) (xy 95.921327 -331.255467)
			(xy 95.913288 -331.445991) (xy 95.897225 -331.636007) (xy 95.873165 -331.825177) (xy 95.841152 -332.013165)
			(xy 95.801242 -332.199635) (xy 95.753507 -332.384258) (xy 95.698031 -332.566704) (xy 95.634913 -332.746649)
			(xy 95.564266 -332.923774) (xy 95.486214 -333.097762) (xy 95.400897 -333.268306) (xy 95.308467 -333.435101)
			(xy 95.209087 -333.597852) (xy 95.102934 -333.756268) (xy 94.990198 -333.910069) (xy 94.871078 -334.05898)
			(xy 94.745786 -334.202737) (xy 94.614545 -334.341085) (xy 94.477589 -334.473776) (xy 94.335161 -334.600577)
			(xy 94.187513 -334.72126) (xy 94.03491 -334.835612) (xy 93.877622 -334.943428) (xy 93.715928 -335.044519)
			(xy 93.550116 -335.138703) (xy 93.380481 -335.225813) (xy 93.207325 -335.305694) (xy 93.030955 -335.378205)
			(xy 92.851685 -335.443216) (xy 92.669834 -335.500612) (xy 92.485725 -335.550291) (xy 92.299685 -335.592164)
			(xy 92.112046 -335.626157) (xy 91.92314 -335.65221) (xy 91.733304 -335.670276) (xy 91.542875 -335.680323)
			(xy 91.352192 -335.682333) (xy 91.161593 -335.676303) (xy 90.971419 -335.662244) (xy 90.782006 -335.640179)
			(xy 90.593691 -335.61015) (xy 90.40681 -335.572208) (xy 90.221694 -335.526422) (xy 90.038674 -335.472873)
			(xy 89.858073 -335.411655) (xy 89.680214 -335.342879) (xy 89.505412 -335.266666) (xy 89.333978 -335.183152)
			(xy 89.166218 -335.092485) (xy 89.002429 -334.994826) (xy 88.842902 -334.890349) (xy 88.687921 -334.77924)
			(xy 88.537763 -334.661697) (xy 88.392693 -334.537927) (xy 88.252969 -334.408152) (xy 88.118841 -334.272603)
			(xy 87.990547 -334.131519) (xy 87.868313 -333.985152) (xy 87.752359 -333.833763) (xy 87.64289 -333.67762)
			(xy 87.540101 -333.517001) (xy 87.444175 -333.352191) (xy 87.355281 -333.183484) (xy 87.273579 -333.011179)
			(xy 87.199213 -332.835584) (xy 87.132315 -332.657009) (xy 87.073005 -332.475773) (xy 87.021388 -332.292198)
			(xy 86.977556 -332.10661) (xy 86.941587 -331.91934) (xy 86.913544 -331.730719) (xy 86.893478 -331.541084)
			(xy 86.881424 -331.350771) (xy 86.877404 -331.16012) (xy 1.016 -331.16012) (xy 1.016 -341.019892)
			(xy 3.583178 -341.019892) (xy 3.583676 -340.962648) (xy 3.591778 -340.848447) (xy 3.607939 -340.735105)
			(xy 3.632078 -340.623191) (xy 3.664075 -340.513266) (xy 3.70377 -340.405879) (xy 3.750962 -340.30157)
			(xy 3.805417 -340.200862) (xy 3.86686 -340.104258) (xy 3.934984 -340.012244) (xy 4.009448 -339.92528)
			(xy 4.089877 -339.843803) (xy 4.17587 -339.76822) (xy 4.266995 -339.698911) (xy 4.362795 -339.636223)
			(xy 4.462791 -339.58047) (xy 4.56648 -339.531931) (xy 4.673344 -339.49085) (xy 4.782847 -339.457433)
			(xy 4.894439 -339.431847) (xy 5.007562 -339.414221) (xy 5.121648 -339.404642) (xy 5.236127 -339.40316)
			(xy 5.350423 -339.40978) (xy 5.463965 -339.42447) (xy 5.576183 -339.447157) (xy 5.686514 -339.477727)
			(xy 5.794406 -339.516026) (xy 5.899318 -339.561862) (xy 6.000724 -339.615007) (xy 6.098116 -339.675192)
			(xy 6.191005 -339.742118) (xy 6.278927 -339.815448) (xy 6.36144 -339.894815) (xy 6.438131 -339.97982)
			(xy 6.508616 -340.070039) (xy 6.57254 -340.165019) (xy 6.629585 -340.264283) (xy 6.679464 -340.367335)
			(xy 6.721926 -340.473657) (xy 6.75676 -340.582717) (xy 6.78379 -340.693968) (xy 6.802882 -340.806853)
			(xy 6.813939 -340.920806) (xy 6.816905 -341.035256) (xy 6.811767 -341.149628) (xy 6.800129 -341.249762)
			(xy 72.864987 -341.249762) (xy 72.868996 -341.046891) (xy 72.881016 -340.844337) (xy 72.90103 -340.642416)
			(xy 72.929005 -340.441443) (xy 72.964898 -340.241733) (xy 73.008652 -340.043596) (xy 73.060201 -339.847343)
			(xy 73.119462 -339.653279) (xy 73.186344 -339.461708) (xy 73.260742 -339.272929) (xy 73.34254 -339.087236)
			(xy 73.43161 -338.90492) (xy 73.527813 -338.726265) (xy 73.631 -338.551551) (xy 73.741008 -338.381049)
			(xy 73.857666 -338.215026) (xy 73.980792 -338.053742) (xy 74.110194 -337.897448) (xy 74.245669 -337.746388)
			(xy 74.387006 -337.600798) (xy 74.533985 -337.460906) (xy 74.686376 -337.32693) (xy 74.843941 -337.199078)
			(xy 75.006434 -337.077552) (xy 75.173601 -336.962539) (xy 75.345181 -336.854221) (xy 75.520906 -336.752766)
			(xy 75.700503 -336.658332) (xy 75.88369 -336.571067) (xy 76.070182 -336.491108) (xy 76.259687 -336.418579)
			(xy 76.451909 -336.353593) (xy 76.646549 -336.296251) (xy 76.843302 -336.246644) (xy 77.041861 -336.204849)
			(xy 77.241917 -336.170931) (xy 77.443156 -336.144943) (xy 77.645265 -336.126925) (xy 77.847928 -336.116906)
			(xy 78.050828 -336.114902) (xy 78.253649 -336.120914) (xy 78.456075 -336.134935) (xy 78.657788 -336.156943)
			(xy 78.858475 -336.186902) (xy 79.057821 -336.224766) (xy 79.255516 -336.270476) (xy 79.45125 -336.32396)
			(xy 79.644719 -336.385136) (xy 79.83562 -336.453907) (xy 80.023655 -336.530167) (xy 80.208531 -336.613795)
			(xy 80.389958 -336.704662) (xy 80.567654 -336.802625) (xy 80.74134 -336.907533) (xy 80.910747 -337.01922)
			(xy 81.075609 -337.137512) (xy 81.235669 -337.262226) (xy 81.390677 -337.393165) (xy 81.540391 -337.530126)
			(xy 81.684577 -337.672895) (xy 81.823011 -337.821249) (xy 81.955475 -337.974956) (xy 82.081764 -338.133776)
			(xy 82.201679 -338.297461) (xy 82.315035 -338.465756) (xy 82.421653 -338.638398) (xy 82.521367 -338.815118)
			(xy 82.614022 -338.995638) (xy 82.699472 -339.179678) (xy 82.777586 -339.366951) (xy 82.848239 -339.557163)
			(xy 82.911323 -339.750018) (xy 82.966739 -339.945215) (xy 83.0144 -340.142448) (xy 83.054231 -340.341411)
			(xy 83.086171 -340.541792) (xy 83.11017 -340.743278) (xy 83.12619 -340.945555) (xy 83.134207 -341.148307)
			(xy 83.134708 -341.249762) (xy 83.134207 -341.351217) (xy 83.12619 -341.553969) (xy 83.11017 -341.756246)
			(xy 83.086171 -341.957732) (xy 83.054231 -342.158113) (xy 83.0144 -342.357076) (xy 82.966739 -342.554309)
			(xy 82.911323 -342.749506) (xy 82.848239 -342.942361) (xy 82.777586 -343.132573) (xy 82.699472 -343.319846)
			(xy 82.614022 -343.503886) (xy 82.521367 -343.684406) (xy 82.421653 -343.861126) (xy 82.315035 -344.033768)
			(xy 82.201679 -344.202063) (xy 82.081764 -344.365748) (xy 81.955475 -344.524568) (xy 81.823011 -344.678275)
			(xy 81.684577 -344.826629) (xy 81.540391 -344.969398) (xy 81.390677 -345.106359) (xy 81.235669 -345.237298)
			(xy 81.075609 -345.362012) (xy 80.910747 -345.480304) (xy 80.74134 -345.591991) (xy 80.567654 -345.696899)
			(xy 80.389958 -345.794862) (xy 80.208531 -345.885729) (xy 80.023655 -345.969357) (xy 79.83562 -346.045617)
			(xy 79.644719 -346.114388) (xy 79.45125 -346.175564) (xy 79.255516 -346.229048) (xy 79.057821 -346.274758)
			(xy 78.858475 -346.312622) (xy 78.657788 -346.342581) (xy 78.456075 -346.364589) (xy 78.253649 -346.37861)
			(xy 78.050828 -346.384622) (xy 77.847928 -346.382618) (xy 77.645265 -346.372599) (xy 77.443156 -346.354581)
			(xy 77.241917 -346.328593) (xy 77.041861 -346.294675) (xy 76.843302 -346.25288) (xy 76.646549 -346.203273)
			(xy 76.451909 -346.145931) (xy 76.259687 -346.080945) (xy 76.070182 -346.008416) (xy 75.88369 -345.928457)
			(xy 75.700503 -345.841192) (xy 75.520906 -345.746758) (xy 75.345181 -345.645303) (xy 75.173601 -345.536985)
			(xy 75.006434 -345.421972) (xy 74.843941 -345.300446) (xy 74.686376 -345.172594) (xy 74.533985 -345.038618)
			(xy 74.387006 -344.898726) (xy 74.245669 -344.753136) (xy 74.110194 -344.602076) (xy 73.980792 -344.445782)
			(xy 73.857666 -344.284498) (xy 73.741008 -344.118475) (xy 73.631 -343.947973) (xy 73.527813 -343.773259)
			(xy 73.43161 -343.594604) (xy 73.34254 -343.412288) (xy 73.260742 -343.226595) (xy 73.186344 -343.037816)
			(xy 73.119462 -342.846245) (xy 73.060201 -342.652181) (xy 73.008652 -342.455928) (xy 72.964898 -342.257791)
			(xy 72.929005 -342.058081) (xy 72.90103 -341.857108) (xy 72.881016 -341.655187) (xy 72.868996 -341.452633)
			(xy 72.864987 -341.249762) (xy 6.800129 -341.249762) (xy 6.79855 -341.263351) (xy 6.77732 -341.375853)
			(xy 6.748183 -341.486571) (xy 6.711286 -341.594951) (xy 6.666813 -341.700448) (xy 6.614988 -341.802534)
			(xy 6.556069 -341.900698) (xy 6.490353 -341.994448) (xy 6.454648 -342.039194) (xy 6.454394 -342.039448)
			(xy 6.060186 -342.039448) (xy 6.021179 -342.071737) (xy 5.939048 -342.130983) (xy 5.896102 -342.157812)
			(xy 5.882524 -342.166761) (xy 5.860006 -342.190206) (xy 5.844123 -342.218568) (xy 5.8359 -342.250017)
			(xy 5.835396 -342.26627) (xy 5.835396 -342.5063) (xy 5.835142 -342.5063) (xy 5.780469 -342.529093)
			(xy 5.668424 -342.567559) (xy 5.553864 -342.597719) (xy 5.437404 -342.619413) (xy 5.319668 -342.632524)
			(xy 5.201288 -342.636981) (xy 5.0829 -342.632761) (xy 4.965138 -342.619886) (xy 4.848635 -342.598425)
			(xy 4.734015 -342.568494) (xy 4.621893 -342.530253) (xy 4.567174 -342.50757) (xy 4.56692 -342.50757)
			(xy 4.56692 -342.26754) (xy 4.566441 -342.251261) (xy 4.558186 -342.219766) (xy 4.542229 -342.191387)
			(xy 4.519608 -342.167969) (xy 4.50596 -342.159082) (xy 4.459776 -342.130343) (xy 4.371783 -342.066378)
			(xy 4.330192 -342.03132) (xy 3.938778 -342.03132) (xy 3.904941 -341.988409) (xy 3.842477 -341.898728)
			(xy 3.78621 -341.805035) (xy 3.736399 -341.707756) (xy 3.69327 -341.607335) (xy 3.657021 -341.504231)
			(xy 3.627816 -341.398915) (xy 3.60579 -341.291867) (xy 3.591042 -341.183577) (xy 3.583641 -341.074537)
			(xy 3.583178 -341.019892) (xy 1.016 -341.019892) (xy 1.016 -342.571578) (xy 1.016492 -342.586921)
			(xy 1.023881 -342.616707) (xy 1.038164 -342.64387) (xy 1.048004 -342.655652) (xy 1.065976 -342.676695)
			(xy 1.09629 -342.722991) (xy 1.119599 -342.77318) (xy 1.135415 -342.82621) (xy 1.143407 -342.880967)
			(xy 1.143407 -342.936305) (xy 1.135415 -342.991062) (xy 1.119599 -343.044092) (xy 1.09629 -343.094281)
			(xy 1.065976 -343.140577) (xy 1.048004 -343.16162) (xy 1.03813 -343.173379) (xy 1.023835 -343.200546)
			(xy 1.01646 -343.230345) (xy 1.016 -343.245694) (xy 1.016 -355.271578) (xy 1.016492 -355.286921)
			(xy 1.023881 -355.316707) (xy 1.038164 -355.34387) (xy 1.048004 -355.355652) (xy 1.065976 -355.376695)
			(xy 1.09629 -355.422991) (xy 1.119599 -355.47318) (xy 1.135415 -355.52621) (xy 1.143407 -355.580967)
			(xy 1.143407 -355.636305) (xy 1.135415 -355.691062) (xy 1.119599 -355.744092) (xy 1.09629 -355.794281)
			(xy 1.065976 -355.840577) (xy 1.048004 -355.86162) (xy 1.03813 -355.873379) (xy 1.023835 -355.900546)
			(xy 1.01646 -355.930345) (xy 1.016 -355.945694) (xy 1.016 -362.51007) (xy 39.818564 -362.51007) (xy 39.819058 -362.452661)
			(xy 39.826902 -362.338113) (xy 39.842544 -362.224366) (xy 39.865911 -362.111952) (xy 39.896896 -362.001394)
			(xy 39.935352 -361.893209) (xy 39.981101 -361.7879) (xy 40.03393 -361.685958) (xy 40.093592 -361.587859)
			(xy 40.159809 -361.49406) (xy 40.232272 -361.404998) (xy 40.310645 -361.321089) (xy 40.39456 -361.242723)
			(xy 40.483627 -361.170266) (xy 40.577431 -361.104056) (xy 40.675535 -361.044402) (xy 40.777481 -360.991581)
			(xy 40.882793 -360.945839) (xy 40.990981 -360.907391) (xy 41.101541 -360.876415) (xy 41.213957 -360.853056)
			(xy 41.327705 -360.837423) (xy 41.442254 -360.829588) (xy 41.557072 -360.829588) (xy 41.671621 -360.837423)
			(xy 41.785369 -360.853056) (xy 41.897785 -360.876415) (xy 42.008345 -360.907391) (xy 42.116533 -360.945839)
			(xy 42.221845 -360.991581) (xy 42.323791 -361.044402) (xy 42.421895 -361.104056) (xy 42.515699 -361.170266)
			(xy 42.604766 -361.242723) (xy 42.688681 -361.321089) (xy 42.767054 -361.404998) (xy 42.839517 -361.49406)
			(xy 42.905734 -361.587859) (xy 42.965396 -361.685958) (xy 43.018225 -361.7879) (xy 43.063974 -361.893209)
			(xy 43.10243 -362.001394) (xy 43.133415 -362.111952) (xy 43.156782 -362.224366) (xy 43.172424 -362.338113)
			(xy 43.180268 -362.452661) (xy 43.180762 -362.51007) (xy 43.180576 -362.543253) (xy 43.177909 -362.609567)
			(xy 43.175428 -362.642658) (xy 43.170272 -362.700942) (xy 43.152948 -362.816671) (xy 43.127616 -362.930914)
			(xy 43.094401 -363.043119) (xy 43.053462 -363.152742) (xy 43.004999 -363.259253) (xy 42.949245 -363.362135)
			(xy 42.886471 -363.460891) (xy 42.816981 -363.555042) (xy 42.741111 -363.644132) (xy 42.659229 -363.727729)
			(xy 42.571732 -363.80543) (xy 42.500813 -363.86008) (xy 93.154506 -363.86008) (xy 93.158522 -363.74381)
			(xy 93.170549 -363.628095) (xy 93.190531 -363.513485) (xy 93.218373 -363.400526) (xy 93.253942 -363.289758)
			(xy 93.297068 -363.181707) (xy 93.347545 -363.076889) (xy 93.405134 -362.975804) (xy 93.46956 -362.878932)
			(xy 93.540515 -362.786736) (xy 93.617662 -362.699655) (xy 93.700633 -362.618104) (xy 93.789033 -362.542472)
			(xy 93.88244 -362.473118) (xy 93.980409 -362.410375) (xy 94.082473 -362.354539) (xy 94.188147 -362.305878)
			(xy 94.296926 -362.264624) (xy 94.408291 -362.230973) (xy 94.521714 -362.205085) (xy 94.636651 -362.187084)
			(xy 94.752557 -362.177055) (xy 94.868879 -362.175047) (xy 94.985062 -362.181069) (xy 95.100553 -362.195092)
			(xy 95.214801 -362.21705) (xy 95.327262 -362.246837) (xy 95.4374 -362.284312) (xy 95.54469 -362.329297)
			(xy 95.648621 -362.381576) (xy 95.748697 -362.440901) (xy 95.844443 -362.506989) (xy 95.9354 -362.579525)
			(xy 96.021136 -362.658164) (xy 96.101243 -362.74253) (xy 96.175339 -362.832222) (xy 96.243069 -362.926812)
			(xy 96.304113 -363.02585) (xy 96.358178 -363.128863) (xy 96.405008 -363.23536) (xy 96.444379 -363.344835)
			(xy 96.476103 -363.456765) (xy 96.500029 -363.570617) (xy 96.516043 -363.685849) (xy 96.52407 -363.801911)
			(xy 96.524572 -363.86008) (xy 96.52407 -363.918249) (xy 96.516043 -364.034311) (xy 96.500029 -364.149543)
			(xy 96.476103 -364.263395) (xy 96.444379 -364.375325) (xy 96.405008 -364.4848) (xy 96.358178 -364.591297)
			(xy 96.304113 -364.69431) (xy 96.243069 -364.793348) (xy 96.175339 -364.887938) (xy 96.101243 -364.97763)
			(xy 96.021136 -365.061996) (xy 95.9354 -365.140635) (xy 95.844443 -365.213171) (xy 95.748697 -365.279259)
			(xy 95.648621 -365.338584) (xy 95.54469 -365.390863) (xy 95.4374 -365.435848) (xy 95.327262 -365.473323)
			(xy 95.214801 -365.50311) (xy 95.100553 -365.525068) (xy 94.985062 -365.539091) (xy 94.868879 -365.545113)
			(xy 94.752557 -365.543105) (xy 94.636651 -365.533076) (xy 94.521714 -365.515075) (xy 94.408291 -365.489187)
			(xy 94.296926 -365.455536) (xy 94.188147 -365.414282) (xy 94.082473 -365.365621) (xy 93.980409 -365.309785)
			(xy 93.88244 -365.247042) (xy 93.789033 -365.177688) (xy 93.700633 -365.102056) (xy 93.617662 -365.020505)
			(xy 93.540515 -364.933424) (xy 93.46956 -364.841228) (xy 93.405134 -364.744356) (xy 93.347545 -364.643271)
			(xy 93.297068 -364.538453) (xy 93.253942 -364.430402) (xy 93.218373 -364.319634) (xy 93.190531 -364.206675)
			(xy 93.170549 -364.092065) (xy 93.158522 -363.97635) (xy 93.154506 -363.86008) (xy 42.500813 -363.86008)
			(xy 42.479042 -363.876857) (xy 42.381609 -363.941665) (xy 42.279905 -363.99954) (xy 42.174422 -364.050202)
			(xy 42.065671 -364.093404) (xy 41.954179 -364.128939) (xy 41.840485 -364.156634) (xy 41.725141 -364.176354)
			(xy 41.608704 -364.188005) (xy 41.491739 -364.19153) (xy 41.374812 -364.186912) (xy 41.258489 -364.174173)
			(xy 41.143334 -364.153375) (xy 41.029905 -364.124618) (xy 40.91875 -364.088042) (xy 40.810407 -364.043825)
			(xy 40.705403 -363.992179) (xy 40.604244 -363.933356) (xy 40.507421 -363.86764) (xy 40.415403 -363.795349)
			(xy 40.328636 -363.716834) (xy 40.247539 -363.632474) (xy 40.172506 -363.542679) (xy 40.103899 -363.447883)
			(xy 40.042051 -363.348544) (xy 39.987262 -363.245145) (xy 39.939796 -363.138186) (xy 39.899884 -363.028185)
			(xy 39.86772 -362.915674) (xy 39.843457 -362.801199) (xy 39.827215 -362.685313) (xy 39.819072 -362.568579)
			(xy 39.818564 -362.51007) (xy 1.016 -362.51007) (xy 1.016 -367.971578) (xy 1.016492 -367.986921)
			(xy 1.023881 -368.016707) (xy 1.038164 -368.04387) (xy 1.048004 -368.055652) (xy 1.065976 -368.076695)
			(xy 1.09629 -368.122991) (xy 1.119599 -368.17318) (xy 1.135415 -368.22621) (xy 1.143407 -368.280967)
			(xy 1.143407 -368.336305) (xy 1.135415 -368.391062) (xy 1.119599 -368.444092) (xy 1.09629 -368.494281)
			(xy 1.065976 -368.540577) (xy 1.048004 -368.56162) (xy 1.03813 -368.573379) (xy 1.023835 -368.600546)
			(xy 1.01646 -368.630345) (xy 1.016 -368.645694) (xy 1.016 -375.61012) (xy 86.877404 -375.61012) (xy 86.881424 -375.419469)
			(xy 86.893478 -375.229156) (xy 86.913544 -375.039521) (xy 86.941587 -374.8509) (xy 86.977556 -374.66363)
			(xy 87.021388 -374.478042) (xy 87.073005 -374.294467) (xy 87.132315 -374.113231) (xy 87.199213 -373.934656)
			(xy 87.273579 -373.759061) (xy 87.355281 -373.586756) (xy 87.444175 -373.418049) (xy 87.540101 -373.253239)
			(xy 87.64289 -373.09262) (xy 87.752359 -372.936477) (xy 87.868313 -372.785088) (xy 87.990547 -372.638721)
			(xy 88.118841 -372.497637) (xy 88.252969 -372.362088) (xy 88.392693 -372.232313) (xy 88.537763 -372.108543)
			(xy 88.687921 -371.991) (xy 88.842902 -371.879891) (xy 89.002429 -371.775414) (xy 89.166218 -371.677755)
			(xy 89.333978 -371.587088) (xy 89.505412 -371.503574) (xy 89.680214 -371.427361) (xy 89.858073 -371.358585)
			(xy 90.038674 -371.297367) (xy 90.221694 -371.243818) (xy 90.40681 -371.198032) (xy 90.593691 -371.16009)
			(xy 90.782006 -371.130061) (xy 90.971419 -371.107996) (xy 91.161593 -371.093937) (xy 91.352192 -371.087907)
			(xy 91.542875 -371.089917) (xy 91.733304 -371.099964) (xy 91.92314 -371.11803) (xy 92.112046 -371.144083)
			(xy 92.299685 -371.178076) (xy 92.485725 -371.219949) (xy 92.669834 -371.269628) (xy 92.851685 -371.327024)
			(xy 93.030955 -371.392035) (xy 93.207325 -371.464546) (xy 93.380481 -371.544427) (xy 93.550116 -371.631537)
			(xy 93.715928 -371.725721) (xy 93.877622 -371.826812) (xy 94.03491 -371.934628) (xy 94.187513 -372.04898)
			(xy 94.335161 -372.169663) (xy 94.477589 -372.296464) (xy 94.614545 -372.429155) (xy 94.745786 -372.567503)
			(xy 94.871078 -372.71126) (xy 94.990198 -372.860171) (xy 95.102934 -373.013972) (xy 95.209087 -373.172388)
			(xy 95.308467 -373.335139) (xy 95.400897 -373.501934) (xy 95.486214 -373.672478) (xy 95.564266 -373.846466)
			(xy 95.634913 -374.023591) (xy 95.698031 -374.203536) (xy 95.753507 -374.385982) (xy 95.801242 -374.570605)
			(xy 95.841152 -374.757075) (xy 95.873165 -374.945063) (xy 95.897225 -375.134233) (xy 95.913288 -375.324249)
			(xy 95.921327 -375.514773) (xy 95.92183 -375.61012) (xy 95.921327 -375.705467) (xy 95.913288 -375.895991)
			(xy 95.897225 -376.086007) (xy 95.873165 -376.275177) (xy 95.841152 -376.463165) (xy 95.801242 -376.649635)
			(xy 95.753507 -376.834258) (xy 95.698031 -377.016704) (xy 95.634913 -377.196649) (xy 95.564266 -377.373774)
			(xy 95.486214 -377.547762) (xy 95.400897 -377.718306) (xy 95.308467 -377.885101) (xy 95.209087 -378.047852)
			(xy 95.102934 -378.206268) (xy 94.990198 -378.360069) (xy 94.871078 -378.50898) (xy 94.745786 -378.652737)
			(xy 94.614545 -378.791085) (xy 94.477589 -378.923776) (xy 94.335161 -379.050577) (xy 94.187513 -379.17126)
			(xy 94.03491 -379.285612) (xy 93.877622 -379.393428) (xy 93.715928 -379.494519) (xy 93.550116 -379.588703)
			(xy 93.380481 -379.675813) (xy 93.207325 -379.755694) (xy 93.030955 -379.828205) (xy 92.851685 -379.893216)
			(xy 92.669834 -379.950612) (xy 92.485725 -380.000291) (xy 92.299685 -380.042164) (xy 92.112046 -380.076157)
			(xy 91.92314 -380.10221) (xy 91.733304 -380.120276) (xy 91.542875 -380.130323) (xy 91.352192 -380.132333)
			(xy 91.161593 -380.126303) (xy 90.971419 -380.112244) (xy 90.782006 -380.090179) (xy 90.593691 -380.06015)
			(xy 90.40681 -380.022208) (xy 90.221694 -379.976422) (xy 90.038674 -379.922873) (xy 89.858073 -379.861655)
			(xy 89.680214 -379.792879) (xy 89.505412 -379.716666) (xy 89.333978 -379.633152) (xy 89.166218 -379.542485)
			(xy 89.002429 -379.444826) (xy 88.842902 -379.340349) (xy 88.687921 -379.22924) (xy 88.537763 -379.111697)
			(xy 88.392693 -378.987927) (xy 88.252969 -378.858152) (xy 88.118841 -378.722603) (xy 87.990547 -378.581519)
			(xy 87.868313 -378.435152) (xy 87.752359 -378.283763) (xy 87.64289 -378.12762) (xy 87.540101 -377.967001)
			(xy 87.444175 -377.802191) (xy 87.355281 -377.633484) (xy 87.273579 -377.461179) (xy 87.199213 -377.285584)
			(xy 87.132315 -377.107009) (xy 87.073005 -376.925773) (xy 87.021388 -376.742198) (xy 86.977556 -376.55661)
			(xy 86.941587 -376.36934) (xy 86.913544 -376.180719) (xy 86.893478 -375.991084) (xy 86.881424 -375.800771)
			(xy 86.877404 -375.61012) (xy 1.016 -375.61012) (xy 1.016 -380.671578) (xy 1.016492 -380.686921)
			(xy 1.023881 -380.716707) (xy 1.038164 -380.74387) (xy 1.048004 -380.755652) (xy 1.065976 -380.776695)
			(xy 1.09629 -380.822991) (xy 1.119599 -380.87318) (xy 1.135415 -380.92621) (xy 1.143407 -380.980967)
			(xy 1.143407 -381.036305) (xy 1.135415 -381.091062) (xy 1.119599 -381.144092) (xy 1.09629 -381.194281)
			(xy 1.065976 -381.240577) (xy 1.048004 -381.26162) (xy 1.03813 -381.273379) (xy 1.023835 -381.300546)
			(xy 1.01646 -381.330345) (xy 1.016 -381.345694) (xy 1.016 -384.79984) (xy 11.34441 -384.79984) (xy 11.348411 -384.594791)
			(xy 11.36041 -384.390054) (xy 11.380388 -384.185941) (xy 11.408314 -383.982762) (xy 11.444146 -383.780829)
			(xy 11.48783 -383.580446) (xy 11.539298 -383.381921) (xy 11.598473 -383.185555) (xy 11.665264 -382.991648)
			(xy 11.73957 -382.800494) (xy 11.821277 -382.612384) (xy 11.910262 -382.427606) (xy 12.006388 -382.24644)
			(xy 12.109509 -382.069163) (xy 12.219469 -381.896044) (xy 12.336099 -381.727347) (xy 12.459222 -381.563329)
			(xy 12.588651 -381.40424) (xy 12.724188 -381.250322) (xy 12.865627 -381.101808) (xy 13.012754 -380.958927)
			(xy 13.165342 -380.821894) (xy 13.323161 -380.69092) (xy 13.48597 -380.566202) (xy 13.653521 -380.447932)
			(xy 13.825559 -380.336288) (xy 14.001822 -380.231442) (xy 14.182041 -380.133553) (xy 14.365942 -380.04277)
			(xy 14.553246 -379.959232) (xy 14.743666 -379.883064) (xy 14.936912 -379.814384) (xy 15.132692 -379.753296)
			(xy 15.330705 -379.699894) (xy 15.530652 -379.654257) (xy 15.732226 -379.616457) (xy 15.935122 -379.586549)
			(xy 16.139031 -379.564581) (xy 16.343641 -379.550586) (xy 16.548641 -379.544584) (xy 16.75372 -379.546585)
			(xy 16.958564 -379.556585) (xy 17.162863 -379.574571) (xy 17.366304 -379.600513) (xy 17.568577 -379.634374)
			(xy 17.769376 -379.6761) (xy 17.968394 -379.725629) (xy 18.165328 -379.782885) (xy 18.359878 -379.847782)
			(xy 18.551748 -379.920219) (xy 18.740645 -380.000087) (xy 18.926283 -380.087265) (xy 19.108378 -380.181619)
			(xy 19.286653 -380.283006) (xy 19.460836 -380.391271) (xy 19.630663 -380.506249) (xy 19.795875 -380.627767)
			(xy 19.956219 -380.755637) (xy 20.111453 -380.889666) (xy 20.261339 -381.02965) (xy 20.405649 -381.175375)
			(xy 20.544163 -381.32662) (xy 20.676672 -381.483153) (xy 20.802972 -381.644738) (xy 20.922871 -381.811127)
			(xy 21.036188 -381.982067) (xy 21.142748 -382.157299) (xy 21.242391 -382.336554) (xy 21.334964 -382.519561)
			(xy 21.420326 -382.70604) (xy 21.498347 -382.895708) (xy 21.56891 -383.088276) (xy 21.631905 -383.28345)
			(xy 21.687237 -383.480933) (xy 21.734822 -383.680424) (xy 21.774587 -383.881621) (xy 21.806472 -384.084215)
			(xy 21.830429 -384.2879) (xy 21.84642 -384.492364) (xy 21.854422 -384.697296) (xy 21.854922 -384.79984)
			(xy 21.854422 -384.902384) (xy 21.84642 -385.107316) (xy 21.830429 -385.31178) (xy 21.806472 -385.515465)
			(xy 21.774587 -385.718059) (xy 21.734822 -385.919256) (xy 21.687237 -386.118747) (xy 21.631905 -386.31623)
			(xy 21.56891 -386.511404) (xy 21.498347 -386.703972) (xy 21.420326 -386.89364) (xy 21.334964 -387.080119)
			(xy 21.242391 -387.263126) (xy 21.142748 -387.442381) (xy 21.036188 -387.617613) (xy 20.922871 -387.788553)
			(xy 20.802972 -387.954942) (xy 20.676672 -388.116527) (xy 20.544163 -388.27306) (xy 20.405649 -388.424305)
			(xy 20.261339 -388.57003) (xy 20.111453 -388.710014) (xy 19.956219 -388.844043) (xy 19.795875 -388.971913)
			(xy 19.630663 -389.093431) (xy 19.460836 -389.208409) (xy 19.286653 -389.316674) (xy 19.108378 -389.418061)
			(xy 18.926283 -389.512415) (xy 18.740645 -389.599593) (xy 18.551748 -389.679461) (xy 18.359878 -389.751898)
			(xy 18.165328 -389.816795) (xy 17.968394 -389.874051) (xy 17.769376 -389.92358) (xy 17.568577 -389.965306)
			(xy 17.366304 -389.999167) (xy 17.162863 -390.025109) (xy 16.958564 -390.043095) (xy 16.75372 -390.053095)
			(xy 16.548641 -390.055096) (xy 16.343641 -390.049094) (xy 16.139031 -390.035099) (xy 15.935122 -390.013131)
			(xy 15.732226 -389.983223) (xy 15.530652 -389.945423) (xy 15.330705 -389.899786) (xy 15.132692 -389.846384)
			(xy 14.936912 -389.785296) (xy 14.743666 -389.716616) (xy 14.553246 -389.640448) (xy 14.365942 -389.55691)
			(xy 14.182041 -389.466127) (xy 14.001822 -389.368238) (xy 13.825559 -389.263392) (xy 13.653521 -389.151748)
			(xy 13.48597 -389.033478) (xy 13.323161 -388.90876) (xy 13.165342 -388.777786) (xy 13.012754 -388.640753)
			(xy 12.865627 -388.497872) (xy 12.724188 -388.349358) (xy 12.588651 -388.19544) (xy 12.459222 -388.036351)
			(xy 12.336099 -387.872333) (xy 12.219469 -387.703636) (xy 12.109509 -387.530517) (xy 12.006388 -387.35324)
			(xy 11.910262 -387.172074) (xy 11.821277 -386.987296) (xy 11.73957 -386.799186) (xy 11.665264 -386.608032)
			(xy 11.598473 -386.414125) (xy 11.539298 -386.217759) (xy 11.48783 -386.019234) (xy 11.444146 -385.818851)
			(xy 11.408314 -385.616918) (xy 11.380388 -385.413739) (xy 11.36041 -385.209626) (xy 11.348411 -385.004889)
			(xy 11.34441 -384.79984) (xy 1.016 -384.79984) (xy 1.016 -393.371578) (xy 1.016492 -393.386921) (xy 1.023881 -393.416707)
			(xy 1.038164 -393.44387) (xy 1.048004 -393.455652) (xy 1.065976 -393.476695) (xy 1.09629 -393.522991)
			(xy 1.119599 -393.57318) (xy 1.135415 -393.62621) (xy 1.143407 -393.680967) (xy 1.143407 -393.736305)
			(xy 1.135415 -393.791062) (xy 1.119599 -393.844092) (xy 1.09629 -393.894281) (xy 1.065976 -393.940577)
			(xy 1.048004 -393.96162) (xy 1.03813 -393.973379) (xy 1.023835 -394.000546) (xy 1.01646 -394.030345)
			(xy 1.016 -394.045694) (xy 1.016 -399.479084) (xy 5.677649 -399.479084) (xy 5.677649 -399.352948)
			(xy 5.685569 -399.22706) (xy 5.701379 -399.101918) (xy 5.725014 -398.978015) (xy 5.756383 -398.855842)
			(xy 5.795361 -398.735879) (xy 5.841795 -398.6186) (xy 5.895502 -398.504468) (xy 5.956269 -398.393933)
			(xy 6.023856 -398.287433) (xy 6.097997 -398.185386) (xy 6.1784 -398.088196) (xy 6.264746 -397.996246)
			(xy 6.356696 -397.9099) (xy 6.453886 -397.829497) (xy 6.555933 -397.755356) (xy 6.662433 -397.687769)
			(xy 6.772968 -397.627002) (xy 6.8871 -397.573295) (xy 7.004379 -397.526861) (xy 7.124342 -397.487883)
			(xy 7.246515 -397.456514) (xy 7.370418 -397.432879) (xy 7.49556 -397.417069) (xy 7.621448 -397.409149)
			(xy 7.747584 -397.409149) (xy 7.873472 -397.417069) (xy 7.998614 -397.432879) (xy 8.122517 -397.456514)
			(xy 8.24469 -397.487883) (xy 8.364653 -397.526861) (xy 8.481932 -397.573295) (xy 8.596064 -397.627002)
			(xy 8.706599 -397.687769) (xy 8.813099 -397.755356) (xy 8.915146 -397.829497) (xy 9.012336 -397.9099)
			(xy 9.104286 -397.996246) (xy 9.190632 -398.088196) (xy 9.271035 -398.185386) (xy 9.345176 -398.287433)
			(xy 9.412763 -398.393933) (xy 9.47353 -398.504468) (xy 9.527237 -398.6186) (xy 9.573671 -398.735879)
			(xy 9.612649 -398.855842) (xy 9.644018 -398.978015) (xy 9.667653 -399.101918) (xy 9.683463 -399.22706)
			(xy 9.691383 -399.352948) (xy 9.691878 -399.416016) (xy 9.691383 -399.479084) (xy 9.683463 -399.604972)
			(xy 9.667653 -399.730114) (xy 9.644018 -399.854017) (xy 9.612649 -399.97619) (xy 9.573671 -400.096153)
			(xy 9.527237 -400.213432) (xy 9.47353 -400.327564) (xy 9.412763 -400.438099) (xy 9.345176 -400.544599)
			(xy 9.271035 -400.646646) (xy 9.190632 -400.743836) (xy 9.104286 -400.835786) (xy 9.012336 -400.922132)
			(xy 8.915146 -401.002535) (xy 8.813099 -401.076676) (xy 8.706599 -401.144263) (xy 8.596064 -401.20503)
			(xy 8.481932 -401.258737) (xy 8.364653 -401.305171) (xy 8.24469 -401.344149) (xy 8.122517 -401.375518)
			(xy 7.998614 -401.399153) (xy 7.873472 -401.414963) (xy 7.747584 -401.422883) (xy 7.621448 -401.422883)
			(xy 7.49556 -401.414963) (xy 7.370418 -401.399153) (xy 7.246515 -401.375518) (xy 7.124342 -401.344149)
			(xy 7.004379 -401.305171) (xy 6.8871 -401.258737) (xy 6.772968 -401.20503) (xy 6.662433 -401.144263)
			(xy 6.555933 -401.076676) (xy 6.453886 -401.002535) (xy 6.356696 -400.922132) (xy 6.264746 -400.835786)
			(xy 6.1784 -400.743836) (xy 6.097997 -400.646646) (xy 6.023856 -400.544599) (xy 5.956269 -400.438099)
			(xy 5.895502 -400.327564) (xy 5.841795 -400.213432) (xy 5.795361 -400.096153) (xy 5.756383 -399.97619)
			(xy 5.725014 -399.854017) (xy 5.701379 -399.730114) (xy 5.685569 -399.604972) (xy 5.677649 -399.479084)
			(xy 1.016 -399.479084) (xy 1.016 -404.690326) (xy 1.016438 -404.705774) (xy 1.023876 -404.735763)
			(xy 1.038309 -404.763081) (xy 1.048258 -404.774908) (xy 1.066393 -404.795992) (xy 1.096996 -404.842427)
			(xy 1.120535 -404.892811) (xy 1.13651 -404.94608) (xy 1.144583 -405.001102) (xy 1.144584 -405.056715)
			(xy 1.136511 -405.111738) (xy 1.120536 -405.165006) (xy 1.096998 -405.215391) (xy 1.066395 -405.261825)
			(xy 1.048258 -405.282908) (xy 1.038292 -405.294723) (xy 1.02386 -405.322047) (xy 1.016425 -405.35204)
			(xy 1.016 -405.36749) (xy 1.016 -406.96007) (xy 39.818564 -406.96007) (xy 39.819058 -406.902661)
			(xy 39.826902 -406.788113) (xy 39.842544 -406.674366) (xy 39.865911 -406.561952) (xy 39.896896 -406.451394)
			(xy 39.935352 -406.343209) (xy 39.981101 -406.2379) (xy 40.03393 -406.135958) (xy 40.093592 -406.037859)
			(xy 40.159809 -405.94406) (xy 40.232272 -405.854998) (xy 40.310645 -405.771089) (xy 40.39456 -405.692723)
			(xy 40.483627 -405.620266) (xy 40.577431 -405.554056) (xy 40.675535 -405.494402) (xy 40.777481 -405.441581)
			(xy 40.882793 -405.395839) (xy 40.990981 -405.357391) (xy 41.101541 -405.326415) (xy 41.213957 -405.303056)
			(xy 41.327705 -405.287423) (xy 41.442254 -405.279588) (xy 41.557072 -405.279588) (xy 41.671621 -405.287423)
			(xy 41.785369 -405.303056) (xy 41.897785 -405.326415) (xy 42.008345 -405.357391) (xy 42.116533 -405.395839)
			(xy 42.221845 -405.441581) (xy 42.323791 -405.494402) (xy 42.421895 -405.554056) (xy 42.515699 -405.620266)
			(xy 42.604766 -405.692723) (xy 42.688681 -405.771089) (xy 42.767054 -405.854998) (xy 42.839517 -405.94406)
			(xy 42.905734 -406.037859) (xy 42.965396 -406.135958) (xy 43.018225 -406.2379) (xy 43.063974 -406.343209)
			(xy 43.10243 -406.451394) (xy 43.133415 -406.561952) (xy 43.156782 -406.674366) (xy 43.172424 -406.788113)
			(xy 43.180268 -406.902661) (xy 43.180762 -406.96007) (xy 43.180576 -406.993253) (xy 43.177909 -407.059567)
			(xy 43.175428 -407.092658) (xy 43.170272 -407.150942) (xy 43.152948 -407.266671) (xy 43.127616 -407.380914)
			(xy 43.094401 -407.493119) (xy 43.053462 -407.602742) (xy 43.004999 -407.709253) (xy 42.949245 -407.812135)
			(xy 42.886471 -407.910891) (xy 42.816981 -408.005042) (xy 42.741111 -408.094132) (xy 42.659229 -408.177729)
			(xy 42.571732 -408.25543) (xy 42.500813 -408.31008) (xy 93.154506 -408.31008) (xy 93.158522 -408.19381)
			(xy 93.170549 -408.078095) (xy 93.190531 -407.963485) (xy 93.218373 -407.850526) (xy 93.253942 -407.739758)
			(xy 93.297068 -407.631707) (xy 93.347545 -407.526889) (xy 93.405134 -407.425804) (xy 93.46956 -407.328932)
			(xy 93.540515 -407.236736) (xy 93.617662 -407.149655) (xy 93.700633 -407.068104) (xy 93.789033 -406.992472)
			(xy 93.88244 -406.923118) (xy 93.980409 -406.860375) (xy 94.082473 -406.804539) (xy 94.188147 -406.755878)
			(xy 94.296926 -406.714624) (xy 94.408291 -406.680973) (xy 94.521714 -406.655085) (xy 94.636651 -406.637084)
			(xy 94.752557 -406.627055) (xy 94.868879 -406.625047) (xy 94.985062 -406.631069) (xy 95.100553 -406.645092)
			(xy 95.214801 -406.66705) (xy 95.327262 -406.696837) (xy 95.4374 -406.734312) (xy 95.54469 -406.779297)
			(xy 95.648621 -406.831576) (xy 95.748697 -406.890901) (xy 95.844443 -406.956989) (xy 95.9354 -407.029525)
			(xy 96.021136 -407.108164) (xy 96.101243 -407.19253) (xy 96.175339 -407.282222) (xy 96.243069 -407.376812)
			(xy 96.304113 -407.47585) (xy 96.358178 -407.578863) (xy 96.405008 -407.68536) (xy 96.444379 -407.794835)
			(xy 96.476103 -407.906765) (xy 96.500029 -408.020617) (xy 96.516043 -408.135849) (xy 96.52407 -408.251911)
			(xy 96.524572 -408.31008) (xy 96.52407 -408.368249) (xy 96.516043 -408.484311) (xy 96.500029 -408.599543)
			(xy 96.476103 -408.713395) (xy 96.444379 -408.825325) (xy 96.405008 -408.9348) (xy 96.358178 -409.041297)
			(xy 96.304113 -409.14431) (xy 96.243069 -409.243348) (xy 96.175339 -409.337938) (xy 96.101243 -409.42763)
			(xy 96.021136 -409.511996) (xy 95.9354 -409.590635) (xy 95.844443 -409.663171) (xy 95.748697 -409.729259)
			(xy 95.648621 -409.788584) (xy 95.54469 -409.840863) (xy 95.4374 -409.885848) (xy 95.327262 -409.923323)
			(xy 95.214801 -409.95311) (xy 95.100553 -409.975068) (xy 94.985062 -409.989091) (xy 94.868879 -409.995113)
			(xy 94.752557 -409.993105) (xy 94.636651 -409.983076) (xy 94.521714 -409.965075) (xy 94.408291 -409.939187)
			(xy 94.296926 -409.905536) (xy 94.188147 -409.864282) (xy 94.082473 -409.815621) (xy 93.980409 -409.759785)
			(xy 93.88244 -409.697042) (xy 93.789033 -409.627688) (xy 93.700633 -409.552056) (xy 93.617662 -409.470505)
			(xy 93.540515 -409.383424) (xy 93.46956 -409.291228) (xy 93.405134 -409.194356) (xy 93.347545 -409.093271)
			(xy 93.297068 -408.988453) (xy 93.253942 -408.880402) (xy 93.218373 -408.769634) (xy 93.190531 -408.656675)
			(xy 93.170549 -408.542065) (xy 93.158522 -408.42635) (xy 93.154506 -408.31008) (xy 42.500813 -408.31008)
			(xy 42.479042 -408.326857) (xy 42.381609 -408.391665) (xy 42.279905 -408.44954) (xy 42.174422 -408.500202)
			(xy 42.065671 -408.543404) (xy 41.954179 -408.578939) (xy 41.840485 -408.606634) (xy 41.725141 -408.626354)
			(xy 41.608704 -408.638005) (xy 41.491739 -408.64153) (xy 41.374812 -408.636912) (xy 41.258489 -408.624173)
			(xy 41.143334 -408.603375) (xy 41.029905 -408.574618) (xy 40.91875 -408.538042) (xy 40.810407 -408.493825)
			(xy 40.705403 -408.442179) (xy 40.604244 -408.383356) (xy 40.507421 -408.31764) (xy 40.415403 -408.245349)
			(xy 40.328636 -408.166834) (xy 40.247539 -408.082474) (xy 40.172506 -407.992679) (xy 40.103899 -407.897883)
			(xy 40.042051 -407.798544) (xy 39.987262 -407.695145) (xy 39.939796 -407.588186) (xy 39.899884 -407.478185)
			(xy 39.86772 -407.365674) (xy 39.843457 -407.251199) (xy 39.827215 -407.135313) (xy 39.819072 -407.018579)
			(xy 39.818564 -406.96007) (xy 1.016 -406.96007) (xy 1.016 -408.641804) (xy 1.01644 -408.657313) (xy 1.023931 -408.687413)
			(xy 1.038474 -408.71481) (xy 1.048512 -408.72664) (xy 1.066871 -408.74776) (xy 1.097841 -408.794368)
			(xy 1.12167 -408.845001) (xy 1.137846 -408.898571) (xy 1.146021 -408.95393) (xy 1.146021 -409.00989)
			(xy 1.137846 -409.065249) (xy 1.12167 -409.118819) (xy 1.097841 -409.169452) (xy 1.066871 -409.21606)
			(xy 1.048512 -409.23718) (xy 1.038479 -409.249015) (xy 1.023938 -409.276412) (xy 1.016436 -409.306508)
			(xy 1.016 -409.322016) (xy 1.016 -410.909084) (xy 5.677649 -410.909084) (xy 5.677649 -410.782948)
			(xy 5.685569 -410.65706) (xy 5.701379 -410.531918) (xy 5.725014 -410.408015) (xy 5.756383 -410.285842)
			(xy 5.795361 -410.165879) (xy 5.841795 -410.0486) (xy 5.895502 -409.934468) (xy 5.956269 -409.823933)
			(xy 6.023856 -409.717433) (xy 6.097997 -409.615386) (xy 6.1784 -409.518196) (xy 6.264746 -409.426246)
			(xy 6.356696 -409.3399) (xy 6.453886 -409.259497) (xy 6.555933 -409.185356) (xy 6.662433 -409.117769)
			(xy 6.772968 -409.057002) (xy 6.8871 -409.003295) (xy 7.004379 -408.956861) (xy 7.124342 -408.917883)
			(xy 7.246515 -408.886514) (xy 7.370418 -408.862879) (xy 7.49556 -408.847069) (xy 7.621448 -408.839149)
			(xy 7.747584 -408.839149) (xy 7.873472 -408.847069) (xy 7.998614 -408.862879) (xy 8.122517 -408.886514)
			(xy 8.24469 -408.917883) (xy 8.364653 -408.956861) (xy 8.481932 -409.003295) (xy 8.596064 -409.057002)
			(xy 8.706599 -409.117769) (xy 8.813099 -409.185356) (xy 8.915146 -409.259497) (xy 9.012336 -409.3399)
			(xy 9.104286 -409.426246) (xy 9.190632 -409.518196) (xy 9.271035 -409.615386) (xy 9.345176 -409.717433)
			(xy 9.412763 -409.823933) (xy 9.47353 -409.934468) (xy 9.527237 -410.0486) (xy 9.573671 -410.165879)
			(xy 9.612649 -410.285842) (xy 9.644018 -410.408015) (xy 9.667653 -410.531918) (xy 9.683463 -410.65706)
			(xy 9.691383 -410.782948) (xy 9.691878 -410.846016) (xy 9.691383 -410.909084) (xy 9.683463 -411.034972)
			(xy 9.667653 -411.160114) (xy 9.644018 -411.284017) (xy 9.612649 -411.40619) (xy 9.573671 -411.526153)
			(xy 9.527237 -411.643432) (xy 9.47353 -411.757564) (xy 9.412763 -411.868099) (xy 9.345176 -411.974599)
			(xy 9.271035 -412.076646) (xy 9.190632 -412.173836) (xy 9.104286 -412.265786) (xy 9.012336 -412.352132)
			(xy 8.915146 -412.432535) (xy 8.813099 -412.506676) (xy 8.706599 -412.574263) (xy 8.596064 -412.63503)
			(xy 8.481932 -412.688737) (xy 8.364653 -412.735171) (xy 8.24469 -412.774149) (xy 8.122517 -412.805518)
			(xy 7.998614 -412.829153) (xy 7.873472 -412.844963) (xy 7.747584 -412.852883) (xy 7.621448 -412.852883)
			(xy 7.49556 -412.844963) (xy 7.370418 -412.829153) (xy 7.246515 -412.805518) (xy 7.124342 -412.774149)
			(xy 7.004379 -412.735171) (xy 6.8871 -412.688737) (xy 6.772968 -412.63503) (xy 6.662433 -412.574263)
			(xy 6.555933 -412.506676) (xy 6.453886 -412.432535) (xy 6.356696 -412.352132) (xy 6.264746 -412.265786)
			(xy 6.1784 -412.173836) (xy 6.097997 -412.076646) (xy 6.023856 -411.974599) (xy 5.956269 -411.868099)
			(xy 5.895502 -411.757564) (xy 5.841795 -411.643432) (xy 5.795361 -411.526153) (xy 5.756383 -411.40619)
			(xy 5.725014 -411.284017) (xy 5.701379 -411.160114) (xy 5.685569 -411.034972) (xy 5.677649 -410.909084)
			(xy 1.016 -410.909084) (xy 1.016 -418.771578) (xy 1.016492 -418.786921) (xy 1.023881 -418.816707)
			(xy 1.038164 -418.84387) (xy 1.048004 -418.855652) (xy 1.065976 -418.876695) (xy 1.09629 -418.922991)
			(xy 1.119599 -418.97318) (xy 1.135415 -419.02621) (xy 1.143407 -419.080967) (xy 1.143407 -419.136305)
			(xy 1.135415 -419.191062) (xy 1.119599 -419.244092) (xy 1.09629 -419.294281) (xy 1.065976 -419.340577)
			(xy 1.048004 -419.36162) (xy 1.03813 -419.373379) (xy 1.023835 -419.400546) (xy 1.01646 -419.430345)
			(xy 1.016 -419.445694) (xy 1.016 -420.06012) (xy 86.877404 -420.06012) (xy 86.881424 -419.869469)
			(xy 86.893478 -419.679156) (xy 86.913544 -419.489521) (xy 86.941587 -419.3009) (xy 86.977556 -419.11363)
			(xy 87.021388 -418.928042) (xy 87.073005 -418.744467) (xy 87.132315 -418.563231) (xy 87.199213 -418.384656)
			(xy 87.273579 -418.209061) (xy 87.355281 -418.036756) (xy 87.444175 -417.868049) (xy 87.540101 -417.703239)
			(xy 87.64289 -417.54262) (xy 87.752359 -417.386477) (xy 87.868313 -417.235088) (xy 87.990547 -417.088721)
			(xy 88.118841 -416.947637) (xy 88.252969 -416.812088) (xy 88.392693 -416.682313) (xy 88.537763 -416.558543)
			(xy 88.687921 -416.441) (xy 88.842902 -416.329891) (xy 89.002429 -416.225414) (xy 89.166218 -416.127755)
			(xy 89.333978 -416.037088) (xy 89.505412 -415.953574) (xy 89.680214 -415.877361) (xy 89.858073 -415.808585)
			(xy 90.038674 -415.747367) (xy 90.221694 -415.693818) (xy 90.40681 -415.648032) (xy 90.593691 -415.61009)
			(xy 90.782006 -415.580061) (xy 90.971419 -415.557996) (xy 91.161593 -415.543937) (xy 91.352192 -415.537907)
			(xy 91.542875 -415.539917) (xy 91.733304 -415.549964) (xy 91.92314 -415.56803) (xy 92.112046 -415.594083)
			(xy 92.299685 -415.628076) (xy 92.485725 -415.669949) (xy 92.669834 -415.719628) (xy 92.851685 -415.777024)
			(xy 93.030955 -415.842035) (xy 93.207325 -415.914546) (xy 93.380481 -415.994427) (xy 93.550116 -416.081537)
			(xy 93.715928 -416.175721) (xy 93.877622 -416.276812) (xy 94.03491 -416.384628) (xy 94.187513 -416.49898)
			(xy 94.335161 -416.619663) (xy 94.477589 -416.746464) (xy 94.614545 -416.879155) (xy 94.745786 -417.017503)
			(xy 94.871078 -417.16126) (xy 94.990198 -417.310171) (xy 95.102934 -417.463972) (xy 95.209087 -417.622388)
			(xy 95.308467 -417.785139) (xy 95.400897 -417.951934) (xy 95.486214 -418.122478) (xy 95.564266 -418.296466)
			(xy 95.634913 -418.473591) (xy 95.698031 -418.653536) (xy 95.753507 -418.835982) (xy 95.801242 -419.020605)
			(xy 95.841152 -419.207075) (xy 95.873165 -419.395063) (xy 95.897225 -419.584233) (xy 95.913288 -419.774249)
			(xy 95.921327 -419.964773) (xy 95.92183 -420.06012) (xy 95.921327 -420.155467) (xy 95.913288 -420.345991)
			(xy 95.897225 -420.536007) (xy 95.873165 -420.725177) (xy 95.841152 -420.913165) (xy 95.801242 -421.099635)
			(xy 95.753507 -421.284258) (xy 95.698031 -421.466704) (xy 95.634913 -421.646649) (xy 95.564266 -421.823774)
			(xy 95.486214 -421.997762) (xy 95.400897 -422.168306) (xy 95.308467 -422.335101) (xy 95.209087 -422.497852)
			(xy 95.102934 -422.656268) (xy 94.990198 -422.810069) (xy 94.871078 -422.95898) (xy 94.745786 -423.102737)
			(xy 94.614545 -423.241085) (xy 94.477589 -423.373776) (xy 94.335161 -423.500577) (xy 94.187513 -423.62126)
			(xy 94.03491 -423.735612) (xy 93.877622 -423.843428) (xy 93.715928 -423.944519) (xy 93.550116 -424.038703)
			(xy 93.380481 -424.125813) (xy 93.207325 -424.205694) (xy 93.030955 -424.278205) (xy 92.851685 -424.343216)
			(xy 92.669834 -424.400612) (xy 92.485725 -424.450291) (xy 92.299685 -424.492164) (xy 92.112046 -424.526157)
			(xy 91.92314 -424.55221) (xy 91.733304 -424.570276) (xy 91.542875 -424.580323) (xy 91.352192 -424.582333)
			(xy 91.161593 -424.576303) (xy 90.971419 -424.562244) (xy 90.782006 -424.540179) (xy 90.593691 -424.51015)
			(xy 90.40681 -424.472208) (xy 90.221694 -424.426422) (xy 90.038674 -424.372873) (xy 89.858073 -424.311655)
			(xy 89.680214 -424.242879) (xy 89.505412 -424.166666) (xy 89.333978 -424.083152) (xy 89.166218 -423.992485)
			(xy 89.002429 -423.894826) (xy 88.842902 -423.790349) (xy 88.687921 -423.67924) (xy 88.537763 -423.561697)
			(xy 88.392693 -423.437927) (xy 88.252969 -423.308152) (xy 88.118841 -423.172603) (xy 87.990547 -423.031519)
			(xy 87.868313 -422.885152) (xy 87.752359 -422.733763) (xy 87.64289 -422.57762) (xy 87.540101 -422.417001)
			(xy 87.444175 -422.252191) (xy 87.355281 -422.083484) (xy 87.273579 -421.911179) (xy 87.199213 -421.735584)
			(xy 87.132315 -421.557009) (xy 87.073005 -421.375773) (xy 87.021388 -421.192198) (xy 86.977556 -421.00661)
			(xy 86.941587 -420.81934) (xy 86.913544 -420.630719) (xy 86.893478 -420.441084) (xy 86.881424 -420.250771)
			(xy 86.877404 -420.06012) (xy 1.016 -420.06012) (xy 1.016 -430.149762) (xy 72.864987 -430.149762)
			(xy 72.868996 -429.946891) (xy 72.881016 -429.744337) (xy 72.90103 -429.542416) (xy 72.929005 -429.341443)
			(xy 72.964898 -429.141733) (xy 73.008652 -428.943596) (xy 73.060201 -428.747343) (xy 73.119462 -428.553279)
			(xy 73.186344 -428.361708) (xy 73.260742 -428.172929) (xy 73.34254 -427.987236) (xy 73.43161 -427.80492)
			(xy 73.527813 -427.626265) (xy 73.631 -427.451551) (xy 73.741008 -427.281049) (xy 73.857666 -427.115026)
			(xy 73.980792 -426.953742) (xy 74.110194 -426.797448) (xy 74.245669 -426.646388) (xy 74.387006 -426.500798)
			(xy 74.533985 -426.360906) (xy 74.686376 -426.22693) (xy 74.843941 -426.099078) (xy 75.006434 -425.977552)
			(xy 75.173601 -425.862539) (xy 75.345181 -425.754221) (xy 75.520906 -425.652766) (xy 75.700503 -425.558332)
			(xy 75.88369 -425.471067) (xy 76.070182 -425.391108) (xy 76.259687 -425.318579) (xy 76.451909 -425.253593)
			(xy 76.646549 -425.196251) (xy 76.843302 -425.146644) (xy 77.041861 -425.104849) (xy 77.241917 -425.070931)
			(xy 77.443156 -425.044943) (xy 77.645265 -425.026925) (xy 77.847928 -425.016906) (xy 78.050828 -425.014902)
			(xy 78.253649 -425.020914) (xy 78.456075 -425.034935) (xy 78.657788 -425.056943) (xy 78.858475 -425.086902)
			(xy 79.057821 -425.124766) (xy 79.255516 -425.170476) (xy 79.45125 -425.22396) (xy 79.644719 -425.285136)
			(xy 79.83562 -425.353907) (xy 80.023655 -425.430167) (xy 80.208531 -425.513795) (xy 80.389958 -425.604662)
			(xy 80.567654 -425.702625) (xy 80.74134 -425.807533) (xy 80.910747 -425.91922) (xy 81.075609 -426.037512)
			(xy 81.235669 -426.162226) (xy 81.390677 -426.293165) (xy 81.540391 -426.430126) (xy 81.684577 -426.572895)
			(xy 81.823011 -426.721249) (xy 81.955475 -426.874956) (xy 82.081764 -427.033776) (xy 82.201679 -427.197461)
			(xy 82.315035 -427.365756) (xy 82.421653 -427.538398) (xy 82.521367 -427.715118) (xy 82.614022 -427.895638)
			(xy 82.699472 -428.079678) (xy 82.777586 -428.266951) (xy 82.848239 -428.457163) (xy 82.911323 -428.650018)
			(xy 82.966739 -428.845215) (xy 83.0144 -429.042448) (xy 83.054231 -429.241411) (xy 83.086171 -429.441792)
			(xy 83.11017 -429.643278) (xy 83.12619 -429.845555) (xy 83.134207 -430.048307) (xy 83.134708 -430.149762)
			(xy 83.134207 -430.251217) (xy 83.12619 -430.453969) (xy 83.11017 -430.656246) (xy 83.086171 -430.857732)
			(xy 83.054231 -431.058113) (xy 83.0144 -431.257076) (xy 82.966739 -431.454309) (xy 82.911323 -431.649506)
			(xy 82.848239 -431.842361) (xy 82.777586 -432.032573) (xy 82.699472 -432.219846) (xy 82.614022 -432.403886)
			(xy 82.521367 -432.584406) (xy 82.421653 -432.761126) (xy 82.315035 -432.933768) (xy 82.201679 -433.102063)
			(xy 82.081764 -433.265748) (xy 81.955475 -433.424568) (xy 81.823011 -433.578275) (xy 81.684577 -433.726629)
			(xy 81.540391 -433.869398) (xy 81.390677 -434.006359) (xy 81.235669 -434.137298) (xy 81.075609 -434.262012)
			(xy 80.910747 -434.380304) (xy 80.74134 -434.491991) (xy 80.567654 -434.596899) (xy 80.389958 -434.694862)
			(xy 80.208531 -434.785729) (xy 80.023655 -434.869357) (xy 79.83562 -434.945617) (xy 79.644719 -435.014388)
			(xy 79.45125 -435.075564) (xy 79.255516 -435.129048) (xy 79.057821 -435.174758) (xy 78.858475 -435.212622)
			(xy 78.657788 -435.242581) (xy 78.456075 -435.264589) (xy 78.253649 -435.27861) (xy 78.050828 -435.284622)
			(xy 77.847928 -435.282618) (xy 77.645265 -435.272599) (xy 77.443156 -435.254581) (xy 77.241917 -435.228593)
			(xy 77.041861 -435.194675) (xy 76.843302 -435.15288) (xy 76.646549 -435.103273) (xy 76.451909 -435.045931)
			(xy 76.259687 -434.980945) (xy 76.070182 -434.908416) (xy 75.88369 -434.828457) (xy 75.700503 -434.741192)
			(xy 75.520906 -434.646758) (xy 75.345181 -434.545303) (xy 75.173601 -434.436985) (xy 75.006434 -434.321972)
			(xy 74.843941 -434.200446) (xy 74.686376 -434.072594) (xy 74.533985 -433.938618) (xy 74.387006 -433.798726)
			(xy 74.245669 -433.653136) (xy 74.110194 -433.502076) (xy 73.980792 -433.345782) (xy 73.857666 -433.184498)
			(xy 73.741008 -433.018475) (xy 73.631 -432.847973) (xy 73.527813 -432.673259) (xy 73.43161 -432.494604)
			(xy 73.34254 -432.312288) (xy 73.260742 -432.126595) (xy 73.186344 -431.937816) (xy 73.119462 -431.746245)
			(xy 73.060201 -431.552181) (xy 73.008652 -431.355928) (xy 72.964898 -431.157791) (xy 72.929005 -430.958081)
			(xy 72.90103 -430.757108) (xy 72.881016 -430.555187) (xy 72.868996 -430.352633) (xy 72.864987 -430.149762)
			(xy 1.016 -430.149762) (xy 1.016 -431.471578) (xy 1.016492 -431.486921) (xy 1.023881 -431.516707)
			(xy 1.038164 -431.54387) (xy 1.048004 -431.555652) (xy 1.065976 -431.576695) (xy 1.09629 -431.622991)
			(xy 1.119599 -431.67318) (xy 1.135415 -431.72621) (xy 1.143407 -431.780967) (xy 1.143407 -431.836305)
			(xy 1.135415 -431.891062) (xy 1.119599 -431.944092) (xy 1.09629 -431.994281) (xy 1.065976 -432.040577)
			(xy 1.048004 -432.06162) (xy 1.03813 -432.073379) (xy 1.023835 -432.100546) (xy 1.01646 -432.130345)
			(xy 1.016 -432.145694) (xy 1.016 -444.171578) (xy 1.016492 -444.186921) (xy 1.023881 -444.216707)
			(xy 1.038164 -444.24387) (xy 1.048004 -444.255652) (xy 1.065976 -444.276695) (xy 1.09629 -444.322991)
			(xy 1.119599 -444.37318) (xy 1.135415 -444.42621) (xy 1.143407 -444.480967) (xy 1.143407 -444.536305)
			(xy 1.135415 -444.591062) (xy 1.119599 -444.644092) (xy 1.09629 -444.694281) (xy 1.065976 -444.740577)
			(xy 1.048004 -444.76162) (xy 1.03813 -444.773379) (xy 1.023835 -444.800546) (xy 1.01646 -444.830345)
			(xy 1.016 -444.845694) (xy 1.016 -451.41007) (xy 39.818564 -451.41007) (xy 39.819058 -451.352661)
			(xy 39.826902 -451.238113) (xy 39.842544 -451.124366) (xy 39.865911 -451.011952) (xy 39.896896 -450.901394)
			(xy 39.935352 -450.793209) (xy 39.981101 -450.6879) (xy 40.03393 -450.585958) (xy 40.093592 -450.487859)
			(xy 40.159809 -450.39406) (xy 40.232272 -450.304998) (xy 40.310645 -450.221089) (xy 40.39456 -450.142723)
			(xy 40.483627 -450.070266) (xy 40.577431 -450.004056) (xy 40.675535 -449.944402) (xy 40.777481 -449.891581)
			(xy 40.882793 -449.845839) (xy 40.990981 -449.807391) (xy 41.101541 -449.776415) (xy 41.213957 -449.753056)
			(xy 41.327705 -449.737423) (xy 41.442254 -449.729588) (xy 41.557072 -449.729588) (xy 41.671621 -449.737423)
			(xy 41.785369 -449.753056) (xy 41.897785 -449.776415) (xy 42.008345 -449.807391) (xy 42.116533 -449.845839)
			(xy 42.221845 -449.891581) (xy 42.323791 -449.944402) (xy 42.421895 -450.004056) (xy 42.515699 -450.070266)
			(xy 42.604766 -450.142723) (xy 42.688681 -450.221089) (xy 42.767054 -450.304998) (xy 42.839517 -450.39406)
			(xy 42.905734 -450.487859) (xy 42.965396 -450.585958) (xy 43.018225 -450.6879) (xy 43.063974 -450.793209)
			(xy 43.10243 -450.901394) (xy 43.133415 -451.011952) (xy 43.156782 -451.124366) (xy 43.172424 -451.238113)
			(xy 43.180268 -451.352661) (xy 43.180762 -451.41007) (xy 43.180576 -451.443253) (xy 43.177909 -451.509567)
			(xy 43.175428 -451.542658) (xy 43.170272 -451.600942) (xy 43.152948 -451.716671) (xy 43.127616 -451.830914)
			(xy 43.094401 -451.943119) (xy 43.053462 -452.052742) (xy 43.004999 -452.159253) (xy 42.949245 -452.262135)
			(xy 42.886471 -452.360891) (xy 42.816981 -452.455042) (xy 42.741111 -452.544132) (xy 42.659229 -452.627729)
			(xy 42.571732 -452.70543) (xy 42.500813 -452.76008) (xy 93.154506 -452.76008) (xy 93.158522 -452.64381)
			(xy 93.170549 -452.528095) (xy 93.190531 -452.413485) (xy 93.218373 -452.300526) (xy 93.253942 -452.189758)
			(xy 93.297068 -452.081707) (xy 93.347545 -451.976889) (xy 93.405134 -451.875804) (xy 93.46956 -451.778932)
			(xy 93.540515 -451.686736) (xy 93.617662 -451.599655) (xy 93.700633 -451.518104) (xy 93.789033 -451.442472)
			(xy 93.88244 -451.373118) (xy 93.980409 -451.310375) (xy 94.082473 -451.254539) (xy 94.188147 -451.205878)
			(xy 94.296926 -451.164624) (xy 94.408291 -451.130973) (xy 94.521714 -451.105085) (xy 94.636651 -451.087084)
			(xy 94.752557 -451.077055) (xy 94.868879 -451.075047) (xy 94.985062 -451.081069) (xy 95.100553 -451.095092)
			(xy 95.214801 -451.11705) (xy 95.327262 -451.146837) (xy 95.4374 -451.184312) (xy 95.54469 -451.229297)
			(xy 95.648621 -451.281576) (xy 95.748697 -451.340901) (xy 95.844443 -451.406989) (xy 95.9354 -451.479525)
			(xy 96.021136 -451.558164) (xy 96.101243 -451.64253) (xy 96.175339 -451.732222) (xy 96.243069 -451.826812)
			(xy 96.304113 -451.92585) (xy 96.358178 -452.028863) (xy 96.405008 -452.13536) (xy 96.444379 -452.244835)
			(xy 96.476103 -452.356765) (xy 96.500029 -452.470617) (xy 96.516043 -452.585849) (xy 96.52407 -452.701911)
			(xy 96.524572 -452.76008) (xy 96.52407 -452.818249) (xy 96.516043 -452.934311) (xy 96.500029 -453.049543)
			(xy 96.476103 -453.163395) (xy 96.444379 -453.275325) (xy 96.405008 -453.3848) (xy 96.358178 -453.491297)
			(xy 96.304113 -453.59431) (xy 96.243069 -453.693348) (xy 96.175339 -453.787938) (xy 96.101243 -453.87763)
			(xy 96.021136 -453.961996) (xy 95.9354 -454.040635) (xy 95.844443 -454.113171) (xy 95.748697 -454.179259)
			(xy 95.648621 -454.238584) (xy 95.54469 -454.290863) (xy 95.4374 -454.335848) (xy 95.327262 -454.373323)
			(xy 95.214801 -454.40311) (xy 95.100553 -454.425068) (xy 94.985062 -454.439091) (xy 94.868879 -454.445113)
			(xy 94.752557 -454.443105) (xy 94.636651 -454.433076) (xy 94.521714 -454.415075) (xy 94.408291 -454.389187)
			(xy 94.296926 -454.355536) (xy 94.188147 -454.314282) (xy 94.082473 -454.265621) (xy 93.980409 -454.209785)
			(xy 93.88244 -454.147042) (xy 93.789033 -454.077688) (xy 93.700633 -454.002056) (xy 93.617662 -453.920505)
			(xy 93.540515 -453.833424) (xy 93.46956 -453.741228) (xy 93.405134 -453.644356) (xy 93.347545 -453.543271)
			(xy 93.297068 -453.438453) (xy 93.253942 -453.330402) (xy 93.218373 -453.219634) (xy 93.190531 -453.106675)
			(xy 93.170549 -452.992065) (xy 93.158522 -452.87635) (xy 93.154506 -452.76008) (xy 42.500813 -452.76008)
			(xy 42.479042 -452.776857) (xy 42.381609 -452.841665) (xy 42.279905 -452.89954) (xy 42.174422 -452.950202)
			(xy 42.065671 -452.993404) (xy 41.954179 -453.028939) (xy 41.840485 -453.056634) (xy 41.725141 -453.076354)
			(xy 41.608704 -453.088005) (xy 41.491739 -453.09153) (xy 41.374812 -453.086912) (xy 41.258489 -453.074173)
			(xy 41.143334 -453.053375) (xy 41.029905 -453.024618) (xy 40.91875 -452.988042) (xy 40.810407 -452.943825)
			(xy 40.705403 -452.892179) (xy 40.604244 -452.833356) (xy 40.507421 -452.76764) (xy 40.415403 -452.695349)
			(xy 40.328636 -452.616834) (xy 40.247539 -452.532474) (xy 40.172506 -452.442679) (xy 40.103899 -452.347883)
			(xy 40.042051 -452.248544) (xy 39.987262 -452.145145) (xy 39.939796 -452.038186) (xy 39.899884 -451.928185)
			(xy 39.86772 -451.815674) (xy 39.843457 -451.701199) (xy 39.827215 -451.585313) (xy 39.819072 -451.468579)
			(xy 39.818564 -451.41007) (xy 1.016 -451.41007) (xy 1.016 -456.871578) (xy 1.016492 -456.886921)
			(xy 1.023881 -456.916707) (xy 1.038164 -456.94387) (xy 1.048004 -456.955652) (xy 1.065976 -456.976695)
			(xy 1.09629 -457.022991) (xy 1.119599 -457.07318) (xy 1.135415 -457.12621) (xy 1.143407 -457.180967)
			(xy 1.143407 -457.236305) (xy 1.135415 -457.291062) (xy 1.119599 -457.344092) (xy 1.09629 -457.394281)
			(xy 1.065976 -457.440577) (xy 1.048004 -457.46162) (xy 1.03813 -457.473379) (xy 1.023835 -457.500546)
			(xy 1.01646 -457.530345) (xy 1.016 -457.545694) (xy 1.016 -464.509866) (xy 86.877404 -464.509866)
			(xy 86.881424 -464.319215) (xy 86.893478 -464.128902) (xy 86.913544 -463.939267) (xy 86.941587 -463.750646)
			(xy 86.977556 -463.563376) (xy 87.021388 -463.377788) (xy 87.073005 -463.194213) (xy 87.132315 -463.012977)
			(xy 87.199213 -462.834402) (xy 87.273579 -462.658807) (xy 87.355281 -462.486502) (xy 87.444175 -462.317795)
			(xy 87.540101 -462.152985) (xy 87.64289 -461.992366) (xy 87.752359 -461.836223) (xy 87.868313 -461.684834)
			(xy 87.990547 -461.538467) (xy 88.118841 -461.397383) (xy 88.252969 -461.261834) (xy 88.392693 -461.132059)
			(xy 88.537763 -461.008289) (xy 88.687921 -460.890746) (xy 88.842902 -460.779637) (xy 89.002429 -460.67516)
			(xy 89.166218 -460.577501) (xy 89.333978 -460.486834) (xy 89.505412 -460.40332) (xy 89.680214 -460.327107)
			(xy 89.858073 -460.258331) (xy 90.038674 -460.197113) (xy 90.221694 -460.143564) (xy 90.40681 -460.097778)
			(xy 90.593691 -460.059836) (xy 90.782006 -460.029807) (xy 90.971419 -460.007742) (xy 91.161593 -459.993683)
			(xy 91.352192 -459.987653) (xy 91.542875 -459.989663) (xy 91.733304 -459.99971) (xy 91.92314 -460.017776)
			(xy 92.112046 -460.043829) (xy 92.299685 -460.077822) (xy 92.485725 -460.119695) (xy 92.669834 -460.169374)
			(xy 92.851685 -460.22677) (xy 93.030955 -460.291781) (xy 93.207325 -460.364292) (xy 93.380481 -460.444173)
			(xy 93.550116 -460.531283) (xy 93.715928 -460.625467) (xy 93.877622 -460.726558) (xy 94.03491 -460.834374)
			(xy 94.187513 -460.948726) (xy 94.335161 -461.069409) (xy 94.477589 -461.19621) (xy 94.614545 -461.328901)
			(xy 94.745786 -461.467249) (xy 94.871078 -461.611006) (xy 94.990198 -461.759917) (xy 95.102934 -461.913718)
			(xy 95.209087 -462.072134) (xy 95.308467 -462.234885) (xy 95.400897 -462.40168) (xy 95.486214 -462.572224)
			(xy 95.564266 -462.746212) (xy 95.634913 -462.923337) (xy 95.698031 -463.103282) (xy 95.753507 -463.285728)
			(xy 95.801242 -463.470351) (xy 95.841152 -463.656821) (xy 95.873165 -463.844809) (xy 95.897225 -464.033979)
			(xy 95.913288 -464.223995) (xy 95.921327 -464.414519) (xy 95.92183 -464.509866) (xy 95.921327 -464.605213)
			(xy 95.913288 -464.795737) (xy 95.897225 -464.985753) (xy 95.873165 -465.174923) (xy 95.841152 -465.362911)
			(xy 95.801242 -465.549381) (xy 95.753507 -465.734004) (xy 95.698031 -465.91645) (xy 95.634913 -466.096395)
			(xy 95.564266 -466.27352) (xy 95.486214 -466.447508) (xy 95.400897 -466.618052) (xy 95.308467 -466.784847)
			(xy 95.209087 -466.947598) (xy 95.102934 -467.106014) (xy 94.990198 -467.259815) (xy 94.871078 -467.408726)
			(xy 94.745786 -467.552483) (xy 94.614545 -467.690831) (xy 94.477589 -467.823522) (xy 94.335161 -467.950323)
			(xy 94.187513 -468.071006) (xy 94.03491 -468.185358) (xy 93.877622 -468.293174) (xy 93.715928 -468.394265)
			(xy 93.550116 -468.488449) (xy 93.380481 -468.575559) (xy 93.207325 -468.65544) (xy 93.030955 -468.727951)
			(xy 92.851685 -468.792962) (xy 92.669834 -468.850358) (xy 92.485725 -468.900037) (xy 92.299685 -468.94191)
			(xy 92.112046 -468.975903) (xy 91.92314 -469.001956) (xy 91.733304 -469.020022) (xy 91.542875 -469.030069)
			(xy 91.352192 -469.032079) (xy 91.161593 -469.026049) (xy 90.971419 -469.01199) (xy 90.782006 -468.989925)
			(xy 90.593691 -468.959896) (xy 90.40681 -468.921954) (xy 90.221694 -468.876168) (xy 90.038674 -468.822619)
			(xy 89.858073 -468.761401) (xy 89.680214 -468.692625) (xy 89.505412 -468.616412) (xy 89.333978 -468.532898)
			(xy 89.166218 -468.442231) (xy 89.002429 -468.344572) (xy 88.842902 -468.240095) (xy 88.687921 -468.128986)
			(xy 88.537763 -468.011443) (xy 88.392693 -467.887673) (xy 88.252969 -467.757898) (xy 88.118841 -467.622349)
			(xy 87.990547 -467.481265) (xy 87.868313 -467.334898) (xy 87.752359 -467.183509) (xy 87.64289 -467.027366)
			(xy 87.540101 -466.866747) (xy 87.444175 -466.701937) (xy 87.355281 -466.53323) (xy 87.273579 -466.360925)
			(xy 87.199213 -466.18533) (xy 87.132315 -466.006755) (xy 87.073005 -465.825519) (xy 87.021388 -465.641944)
			(xy 86.977556 -465.456356) (xy 86.941587 -465.269086) (xy 86.913544 -465.080465) (xy 86.893478 -464.89083)
			(xy 86.881424 -464.700517) (xy 86.877404 -464.509866) (xy 1.016 -464.509866) (xy 1.016 -469.571578)
			(xy 1.016492 -469.586921) (xy 1.023881 -469.616707) (xy 1.038164 -469.64387) (xy 1.048004 -469.655652)
			(xy 1.065976 -469.676695) (xy 1.09629 -469.722991) (xy 1.119599 -469.77318) (xy 1.135415 -469.82621)
			(xy 1.143407 -469.880967) (xy 1.143407 -469.936305) (xy 1.135415 -469.991062) (xy 1.119599 -470.044092)
			(xy 1.09629 -470.094281) (xy 1.065976 -470.140577) (xy 1.048004 -470.16162) (xy 1.03813 -470.173379)
			(xy 1.023835 -470.200546) (xy 1.01646 -470.230345) (xy 1.016 -470.245694) (xy 1.016 -471.172032)
			(xy 6.671831 -471.172032) (xy 6.675786 -471.080195) (xy 6.687621 -470.989038) (xy 6.707248 -470.899235)
			(xy 6.734522 -470.811453) (xy 6.769242 -470.726339) (xy 6.81115 -470.644526) (xy 6.859936 -470.566618)
			(xy 6.915239 -470.493193) (xy 6.976649 -470.424793) (xy 7.043711 -470.361926) (xy 7.11593 -470.305056)
			(xy 7.19277 -470.254605) (xy 7.273663 -470.210946) (xy 7.358009 -470.174403) (xy 7.445185 -470.145246)
			(xy 7.534544 -470.123692) (xy 7.625425 -470.109898) (xy 7.717156 -470.103968) (xy 7.809057 -470.105946)
			(xy 7.900448 -470.115817) (xy 7.990652 -470.133507) (xy 8.079001 -470.158887) (xy 8.164841 -470.191767)
			(xy 8.247537 -470.231905) (xy 8.326477 -470.279004) (xy 8.401075 -470.332714) (xy 8.470781 -470.392638)
			(xy 8.535076 -470.458332) (xy 8.593487 -470.52931) (xy 8.645579 -470.605047) (xy 8.690968 -470.684982)
			(xy 8.729318 -470.768522) (xy 8.760343 -470.85505) (xy 8.783816 -470.943925) (xy 8.799562 -471.034489)
			(xy 8.807464 -471.126071) (xy 8.807958 -471.172032) (xy 8.807464 -471.217993) (xy 8.799562 -471.309575)
			(xy 8.783816 -471.400139) (xy 8.760343 -471.489014) (xy 8.729318 -471.575542) (xy 8.690968 -471.659082)
			(xy 8.645579 -471.739017) (xy 8.593487 -471.814754) (xy 8.535076 -471.885732) (xy 8.470781 -471.951426)
			(xy 8.401075 -472.01135) (xy 8.326477 -472.06506) (xy 8.247537 -472.112159) (xy 8.164841 -472.152297)
			(xy 8.079001 -472.185177) (xy 7.990652 -472.210557) (xy 7.900448 -472.228247) (xy 7.809057 -472.238118)
			(xy 7.717156 -472.240096) (xy 7.625425 -472.234166) (xy 7.534544 -472.220372) (xy 7.445185 -472.198818)
			(xy 7.358009 -472.169661) (xy 7.273663 -472.133118) (xy 7.19277 -472.089459) (xy 7.11593 -472.039008)
			(xy 7.043711 -471.982138) (xy 6.976649 -471.919271) (xy 6.915239 -471.850871) (xy 6.859936 -471.777446)
			(xy 6.81115 -471.699538) (xy 6.769242 -471.617725) (xy 6.734522 -471.532611) (xy 6.707248 -471.444829)
			(xy 6.687621 -471.355026) (xy 6.675786 -471.263869) (xy 6.671831 -471.172032) (xy 1.016 -471.172032)
			(xy 1.016 -473.758104) (xy 11.344959 -473.758104) (xy 11.346673 -473.553483) (xy 11.35635 -473.349084)
			(xy 11.373978 -473.145217) (xy 11.399529 -472.942191) (xy 11.432964 -472.740314) (xy 11.474234 -472.539891)
			(xy 11.523275 -472.341226) (xy 11.580012 -472.144622) (xy 11.644361 -471.950375) (xy 11.716222 -471.758781)
			(xy 11.795488 -471.570129) (xy 11.882039 -471.384706) (xy 11.975742 -471.202794) (xy 12.076456 -471.024667)
			(xy 12.184029 -470.850596) (xy 12.298296 -470.680845) (xy 12.419086 -470.515671) (xy 12.546214 -470.355325)
			(xy 12.679488 -470.200049) (xy 12.818706 -470.050079) (xy 12.963657 -469.905643) (xy 13.114121 -469.76696)
			(xy 13.26987 -469.634239) (xy 13.430667 -469.507682) (xy 13.59627 -469.387481) (xy 13.766427 -469.273819)
			(xy 13.940879 -469.166866) (xy 14.119363 -469.066786) (xy 14.301608 -468.973731) (xy 14.487338 -468.887841)
			(xy 14.67627 -468.809247) (xy 14.868119 -468.738067) (xy 15.062593 -468.67441) (xy 15.259399 -468.618373)
			(xy 15.458236 -468.570039) (xy 15.658805 -468.529483) (xy 15.8608 -468.496766) (xy 16.063916 -468.471938)
			(xy 16.267844 -468.455036) (xy 16.472276 -468.446085) (xy 16.676902 -468.4451) (xy 16.88141 -468.452082)
			(xy 17.085492 -468.46702) (xy 17.288838 -468.489892) (xy 17.491139 -468.520663) (xy 17.692088 -468.559287)
			(xy 17.891382 -468.605704) (xy 18.088717 -468.659844) (xy 18.283796 -468.721626) (xy 18.476321 -468.790955)
			(xy 18.666001 -468.867727) (xy 18.852549 -468.951825) (xy 18.944336 -468.99703) (xy 19.037192 -469.043882)
			(xy 19.21954 -469.143972) (xy 19.397783 -469.2512) (xy 19.571643 -469.365399) (xy 19.740847 -469.48639)
			(xy 19.90513 -469.613982) (xy 20.064235 -469.747975) (xy 20.217912 -469.888161) (xy 20.36592 -470.034319)
			(xy 20.508028 -470.18622) (xy 20.644013 -470.343627) (xy 20.773661 -470.506292) (xy 20.89677 -470.673961)
			(xy 21.013147 -470.84637) (xy 21.122609 -471.02325) (xy 21.224985 -471.204324) (xy 21.320115 -471.389308)
			(xy 21.407849 -471.577912) (xy 21.48805 -471.76984) (xy 21.560592 -471.964792) (xy 21.625361 -472.162463)
			(xy 21.682257 -472.362541) (xy 21.731189 -472.564715) (xy 21.772082 -472.768667) (xy 21.804871 -472.974078)
			(xy 21.829504 -473.180625) (xy 21.845944 -473.387986) (xy 21.854164 -473.595834) (xy 21.854668 -473.69984)
			(xy 21.854163 -473.801745) (xy 21.846266 -474.005403) (xy 21.830477 -474.208601) (xy 21.806821 -474.411034)
			(xy 21.775332 -474.612398) (xy 21.736059 -474.812389) (xy 21.68906 -475.010707) (xy 21.634406 -475.207053)
			(xy 21.572179 -475.401132) (xy 21.502473 -475.592651) (xy 21.425392 -475.781324) (xy 21.341054 -475.966866)
			(xy 21.249584 -476.148998) (xy 21.151119 -476.327446) (xy 21.045809 -476.501941) (xy 20.933812 -476.672222)
			(xy 20.815296 -476.838031) (xy 20.690439 -476.99912) (xy 20.55943 -477.155245) (xy 20.422464 -477.306174)
			(xy 20.279749 -477.451677) (xy 20.131499 -477.591537) (xy 19.977937 -477.725543) (xy 19.819295 -477.853493)
			(xy 19.655809 -477.975195) (xy 19.487728 -478.090466) (xy 19.315303 -478.199132) (xy 19.227292 -478.250504)
			(xy 19.138436 -478.301228) (xy 18.957375 -478.396567) (xy 18.77274 -478.484785) (xy 18.58481 -478.565748)
			(xy 18.393871 -478.639333) (xy 18.200212 -478.70543) (xy 18.004127 -478.763937) (xy 17.863861 -478.799906)
			(xy 74.3839 -478.799906) (xy 74.3839 -477.799908) (xy 74.384397 -477.715129) (xy 74.392344 -477.545758)
			(xy 74.408222 -477.376946) (xy 74.431995 -477.209063) (xy 74.46361 -477.04248) (xy 74.503 -476.877561)
			(xy 74.550075 -476.71467) (xy 74.604735 -476.554164) (xy 74.666857 -476.396397) (xy 74.736306 -476.241715)
			(xy 74.812929 -476.090458) (xy 74.896558 -475.942959) (xy 74.987008 -475.799542) (xy 75.084081 -475.660522)
			(xy 75.187564 -475.526205) (xy 75.297228 -475.396886) (xy 75.412834 -475.27285) (xy 75.534126 -475.154368)
			(xy 75.660839 -475.041702) (xy 75.792693 -474.935099) (xy 75.929399 -474.834794) (xy 76.070656 -474.741006)
			(xy 76.216154 -474.653943) (xy 76.365573 -474.573795) (xy 76.518585 -474.500739) (xy 76.674852 -474.434935)
			(xy 76.834032 -474.376528) (xy 76.995775 -474.325647) (xy 77.159725 -474.282402) (xy 77.325522 -474.24689)
			(xy 77.492801 -474.219188) (xy 77.661195 -474.199358) (xy 77.830333 -474.187442) (xy 77.999844 -474.183467)
			(xy 78.169355 -474.187442) (xy 78.338493 -474.199358) (xy 78.506887 -474.219188) (xy 78.674166 -474.24689)
			(xy 78.839963 -474.282402) (xy 79.003913 -474.325647) (xy 79.165656 -474.376528) (xy 79.324836 -474.434935)
			(xy 79.481103 -474.500739) (xy 79.634115 -474.573795) (xy 79.783534 -474.653943) (xy 79.929032 -474.741006)
			(xy 80.070289 -474.834794) (xy 80.206995 -474.935099) (xy 80.338849 -475.041702) (xy 80.465562 -475.154368)
			(xy 80.586854 -475.27285) (xy 80.70246 -475.396886) (xy 80.812124 -475.526205) (xy 80.915607 -475.660522)
			(xy 81.01268 -475.799542) (xy 81.10313 -475.942959) (xy 81.186759 -476.090458) (xy 81.263382 -476.241715)
			(xy 81.332831 -476.396397) (xy 81.394953 -476.554164) (xy 81.449613 -476.71467) (xy 81.496688 -476.877561)
			(xy 81.536078 -477.04248) (xy 81.567693 -477.209063) (xy 81.591466 -477.376946) (xy 81.607344 -477.545758)
			(xy 81.615291 -477.715129) (xy 81.615788 -477.799908) (xy 81.615788 -478.799906) (xy 81.615291 -478.884685)
			(xy 81.607344 -479.054056) (xy 81.591466 -479.222868) (xy 81.567693 -479.390751) (xy 81.536078 -479.557334)
			(xy 81.496688 -479.722253) (xy 81.449613 -479.885144) (xy 81.394953 -480.04565) (xy 81.332831 -480.203417)
			(xy 81.263382 -480.358099) (xy 81.186759 -480.509356) (xy 81.10313 -480.656855) (xy 81.01268 -480.800272)
			(xy 80.915607 -480.939292) (xy 80.812124 -481.073609) (xy 80.70246 -481.202928) (xy 80.586854 -481.326964)
			(xy 80.465562 -481.445446) (xy 80.338849 -481.558112) (xy 80.206995 -481.664715) (xy 80.070289 -481.76502)
			(xy 79.929032 -481.858808) (xy 79.783534 -481.945871) (xy 79.634115 -482.026019) (xy 79.481103 -482.099075)
			(xy 79.324836 -482.164879) (xy 79.165656 -482.223286) (xy 79.003913 -482.274167) (xy 78.839963 -482.317412)
			(xy 78.674166 -482.352924) (xy 78.506887 -482.380626) (xy 78.338493 -482.400456) (xy 78.169355 -482.412372)
			(xy 77.999844 -482.416347) (xy 77.830333 -482.412372) (xy 77.661195 -482.400456) (xy 77.492801 -482.380626)
			(xy 77.325522 -482.352924) (xy 77.159725 -482.317412) (xy 76.995775 -482.274167) (xy 76.834032 -482.223286)
			(xy 76.674852 -482.164879) (xy 76.518585 -482.099075) (xy 76.365573 -482.026019) (xy 76.216154 -481.945871)
			(xy 76.070656 -481.858808) (xy 75.929399 -481.76502) (xy 75.792693 -481.664715) (xy 75.660839 -481.558112)
			(xy 75.534126 -481.445446) (xy 75.412834 -481.326964) (xy 75.297228 -481.202928) (xy 75.187564 -481.073609)
			(xy 75.084081 -480.939292) (xy 74.987008 -480.800272) (xy 74.896558 -480.656855) (xy 74.812929 -480.509356)
			(xy 74.736306 -480.358099) (xy 74.666857 -480.203417) (xy 74.604735 -480.04565) (xy 74.550075 -479.885144)
			(xy 74.503 -479.722253) (xy 74.46361 -479.557334) (xy 74.431995 -479.390751) (xy 74.408222 -479.222868)
			(xy 74.392344 -479.054056) (xy 74.384397 -478.884685) (xy 74.3839 -478.799906) (xy 17.863861 -478.799906)
			(xy 17.805913 -478.814766) (xy 17.60587 -478.857839) (xy 17.404302 -478.893093) (xy 17.201514 -478.920472)
			(xy 16.997814 -478.939937) (xy 16.793511 -478.951456) (xy 16.588914 -478.955013) (xy 16.384334 -478.950602)
			(xy 16.18008 -478.93823) (xy 15.976463 -478.917916) (xy 15.773792 -478.88969) (xy 15.572372 -478.853596)
			(xy 15.372511 -478.809688) (xy 15.17451 -478.758032) (xy 14.978671 -478.698707) (xy 14.78529 -478.631803)
			(xy 14.594659 -478.557422) (xy 14.407069 -478.475675) (xy 14.222804 -478.386687) (xy 14.042143 -478.290594)
			(xy 13.865359 -478.18754) (xy 13.692722 -478.077682) (xy 13.524492 -477.961186) (xy 13.360925 -477.838229)
			(xy 13.202269 -477.708998) (xy 13.048764 -477.573688) (xy 12.900643 -477.432505) (xy 12.75813 -477.285662)
			(xy 12.621443 -477.133383) (xy 12.490787 -476.975898) (xy 12.366361 -476.813445) (xy 12.248354 -476.646272)
			(xy 12.136945 -476.474632) (xy 12.032302 -476.298784) (xy 11.934584 -476.118996) (xy 11.84394 -475.93554)
			(xy 11.760506 -475.748694) (xy 11.684409 -475.558742) (xy 11.615765 -475.365972) (xy 11.554678 -475.170675)
			(xy 11.50124 -474.973148) (xy 11.455533 -474.77369) (xy 11.417625 -474.572604) (xy 11.387574 -474.370195)
			(xy 11.365426 -474.16677) (xy 11.351214 -473.962636) (xy 11.344959 -473.758104) (xy 1.016 -473.758104)
			(xy 1.016 -480.172014) (xy 6.671831 -480.172014) (xy 6.675786 -480.080177) (xy 6.687621 -479.98902)
			(xy 6.707248 -479.899217) (xy 6.734522 -479.811435) (xy 6.769242 -479.726321) (xy 6.81115 -479.644508)
			(xy 6.859936 -479.5666) (xy 6.915239 -479.493175) (xy 6.976649 -479.424775) (xy 7.043711 -479.361908)
			(xy 7.11593 -479.305038) (xy 7.19277 -479.254587) (xy 7.273663 -479.210928) (xy 7.358009 -479.174385)
			(xy 7.445185 -479.145228) (xy 7.534544 -479.123674) (xy 7.625425 -479.10988) (xy 7.717156 -479.10395)
			(xy 7.809057 -479.105928) (xy 7.900448 -479.115799) (xy 7.990652 -479.133489) (xy 8.079001 -479.158869)
			(xy 8.164841 -479.191749) (xy 8.247537 -479.231887) (xy 8.326477 -479.278986) (xy 8.401075 -479.332696)
			(xy 8.470781 -479.39262) (xy 8.535076 -479.458314) (xy 8.593487 -479.529292) (xy 8.645579 -479.605029)
			(xy 8.690968 -479.684964) (xy 8.729318 -479.768504) (xy 8.760343 -479.855032) (xy 8.783816 -479.943907)
			(xy 8.799562 -480.034471) (xy 8.807464 -480.126053) (xy 8.807958 -480.172014) (xy 8.807464 -480.217975)
			(xy 8.799562 -480.309557) (xy 8.783816 -480.400121) (xy 8.760343 -480.488996) (xy 8.729318 -480.575524)
			(xy 8.690968 -480.659064) (xy 8.645579 -480.738999) (xy 8.593487 -480.814736) (xy 8.535076 -480.885714)
			(xy 8.470781 -480.951408) (xy 8.401075 -481.011332) (xy 8.326477 -481.065042) (xy 8.247537 -481.112141)
			(xy 8.164841 -481.152279) (xy 8.079001 -481.185159) (xy 7.990652 -481.210539) (xy 7.900448 -481.228229)
			(xy 7.809057 -481.2381) (xy 7.717156 -481.240078) (xy 7.625425 -481.234148) (xy 7.534544 -481.220354)
			(xy 7.445185 -481.1988) (xy 7.358009 -481.169643) (xy 7.273663 -481.1331) (xy 7.19277 -481.089441)
			(xy 7.11593 -481.03899) (xy 7.043711 -480.98212) (xy 6.976649 -480.919253) (xy 6.915239 -480.850853)
			(xy 6.859936 -480.777428) (xy 6.81115 -480.69952) (xy 6.769242 -480.617707) (xy 6.734522 -480.532593)
			(xy 6.707248 -480.444811) (xy 6.687621 -480.355008) (xy 6.675786 -480.263851) (xy 6.671831 -480.172014)
			(xy 1.016 -480.172014) (xy 1.016 -482.271578) (xy 1.016492 -482.286921) (xy 1.023881 -482.316707)
			(xy 1.038164 -482.34387) (xy 1.048004 -482.355652) (xy 1.065976 -482.376695) (xy 1.09629 -482.422991)
			(xy 1.119599 -482.47318) (xy 1.135415 -482.52621) (xy 1.143407 -482.580967) (xy 1.143407 -482.636305)
			(xy 1.135415 -482.691062) (xy 1.119599 -482.744092) (xy 1.09629 -482.794281) (xy 1.065976 -482.840577)
			(xy 1.048004 -482.86162) (xy 1.03813 -482.873379) (xy 1.023835 -482.900546) (xy 1.01646 -482.930345)
			(xy 1.016 -482.945694) (xy 1.016 -491.999778) (xy 6.671831 -491.999778) (xy 6.675786 -491.907941)
			(xy 6.687621 -491.816784) (xy 6.707248 -491.726981) (xy 6.734522 -491.639199) (xy 6.769242 -491.554085)
			(xy 6.81115 -491.472272) (xy 6.859936 -491.394364) (xy 6.915239 -491.320939) (xy 6.976649 -491.252539)
			(xy 7.043711 -491.189672) (xy 7.11593 -491.132802) (xy 7.19277 -491.082351) (xy 7.273663 -491.038692)
			(xy 7.358009 -491.002149) (xy 7.445185 -490.972992) (xy 7.534544 -490.951438) (xy 7.625425 -490.937644)
			(xy 7.717156 -490.931714) (xy 7.809057 -490.933692) (xy 7.900448 -490.943563) (xy 7.990652 -490.961253)
			(xy 8.079001 -490.986633) (xy 8.164841 -491.019513) (xy 8.247537 -491.059651) (xy 8.326477 -491.10675)
			(xy 8.401075 -491.16046) (xy 8.470781 -491.220384) (xy 8.535076 -491.286078) (xy 8.593487 -491.357056)
			(xy 8.645579 -491.432793) (xy 8.690968 -491.512728) (xy 8.729318 -491.596268) (xy 8.760343 -491.682796)
			(xy 8.783816 -491.771671) (xy 8.799562 -491.862235) (xy 8.807464 -491.953817) (xy 8.807958 -491.999778)
			(xy 8.807464 -492.045739) (xy 8.799562 -492.137321) (xy 8.783816 -492.227885) (xy 8.760343 -492.31676)
			(xy 8.729318 -492.403288) (xy 8.690968 -492.486828) (xy 8.645579 -492.566763) (xy 8.593487 -492.6425)
			(xy 8.535076 -492.713478) (xy 8.470781 -492.779172) (xy 8.401075 -492.839096) (xy 8.326477 -492.892806)
			(xy 8.247537 -492.939905) (xy 8.164841 -492.980043) (xy 8.079001 -493.012923) (xy 7.990652 -493.038303)
			(xy 7.900448 -493.055993) (xy 7.809057 -493.065864) (xy 7.717156 -493.067842) (xy 7.625425 -493.061912)
			(xy 7.534544 -493.048118) (xy 7.445185 -493.026564) (xy 7.358009 -492.997407) (xy 7.273663 -492.960864)
			(xy 7.19277 -492.917205) (xy 7.11593 -492.866754) (xy 7.043711 -492.809884) (xy 6.976649 -492.747017)
			(xy 6.915239 -492.678617) (xy 6.859936 -492.605192) (xy 6.81115 -492.527284) (xy 6.769242 -492.445471)
			(xy 6.734522 -492.360357) (xy 6.707248 -492.272575) (xy 6.687621 -492.182772) (xy 6.675786 -492.091615)
			(xy 6.671831 -491.999778) (xy 1.016 -491.999778) (xy 1.016 -494.971578) (xy 1.016492 -494.986921)
			(xy 1.023881 -495.016707) (xy 1.038164 -495.04387) (xy 1.048004 -495.055652) (xy 1.065976 -495.076695)
			(xy 1.09629 -495.122991) (xy 1.119599 -495.17318) (xy 1.135415 -495.22621) (xy 1.143407 -495.280967)
			(xy 1.143407 -495.336305) (xy 1.135415 -495.391062) (xy 1.119599 -495.444092) (xy 1.09629 -495.494281)
			(xy 1.065976 -495.540577) (xy 1.048004 -495.56162) (xy 1.03813 -495.573379) (xy 1.023835 -495.600546)
			(xy 1.01646 -495.630345) (xy 1.016 -495.645694) (xy 1.016 -495.86007) (xy 39.818564 -495.86007) (xy 39.819058 -495.802661)
			(xy 39.826902 -495.688113) (xy 39.842544 -495.574366) (xy 39.865911 -495.461952) (xy 39.896896 -495.351394)
			(xy 39.935352 -495.243209) (xy 39.981101 -495.1379) (xy 40.03393 -495.035958) (xy 40.093592 -494.937859)
			(xy 40.159809 -494.84406) (xy 40.232272 -494.754998) (xy 40.310645 -494.671089) (xy 40.39456 -494.592723)
			(xy 40.483627 -494.520266) (xy 40.577431 -494.454056) (xy 40.675535 -494.394402) (xy 40.777481 -494.341581)
			(xy 40.882793 -494.295839) (xy 40.990981 -494.257391) (xy 41.101541 -494.226415) (xy 41.213957 -494.203056)
			(xy 41.327705 -494.187423) (xy 41.442254 -494.179588) (xy 41.557072 -494.179588) (xy 41.671621 -494.187423)
			(xy 41.785369 -494.203056) (xy 41.897785 -494.226415) (xy 42.008345 -494.257391) (xy 42.116533 -494.295839)
			(xy 42.221845 -494.341581) (xy 42.323791 -494.394402) (xy 42.421895 -494.454056) (xy 42.515699 -494.520266)
			(xy 42.604766 -494.592723) (xy 42.688681 -494.671089) (xy 42.767054 -494.754998) (xy 42.839517 -494.84406)
			(xy 42.905734 -494.937859) (xy 42.965396 -495.035958) (xy 43.018225 -495.1379) (xy 43.063974 -495.243209)
			(xy 43.10243 -495.351394) (xy 43.133415 -495.461952) (xy 43.156782 -495.574366) (xy 43.172424 -495.688113)
			(xy 43.180268 -495.802661) (xy 43.180762 -495.86007) (xy 43.180576 -495.893253) (xy 43.177909 -495.959567)
			(xy 43.175428 -495.992658) (xy 43.170272 -496.050942) (xy 43.152948 -496.166671) (xy 43.127616 -496.280914)
			(xy 43.094401 -496.393119) (xy 43.053462 -496.502742) (xy 43.004999 -496.609253) (xy 42.949245 -496.712135)
			(xy 42.886471 -496.810891) (xy 42.816981 -496.905042) (xy 42.741111 -496.994132) (xy 42.659229 -497.077729)
			(xy 42.571732 -497.15543) (xy 42.500813 -497.21008) (xy 93.154506 -497.21008) (xy 93.158522 -497.09381)
			(xy 93.170549 -496.978095) (xy 93.190531 -496.863485) (xy 93.218373 -496.750526) (xy 93.253942 -496.639758)
			(xy 93.297068 -496.531707) (xy 93.347545 -496.426889) (xy 93.405134 -496.325804) (xy 93.46956 -496.228932)
			(xy 93.540515 -496.136736) (xy 93.617662 -496.049655) (xy 93.700633 -495.968104) (xy 93.789033 -495.892472)
			(xy 93.88244 -495.823118) (xy 93.980409 -495.760375) (xy 94.082473 -495.704539) (xy 94.188147 -495.655878)
			(xy 94.296926 -495.614624) (xy 94.408291 -495.580973) (xy 94.521714 -495.555085) (xy 94.636651 -495.537084)
			(xy 94.752557 -495.527055) (xy 94.868879 -495.525047) (xy 94.985062 -495.531069) (xy 95.100553 -495.545092)
			(xy 95.214801 -495.56705) (xy 95.327262 -495.596837) (xy 95.4374 -495.634312) (xy 95.54469 -495.679297)
			(xy 95.648621 -495.731576) (xy 95.748697 -495.790901) (xy 95.844443 -495.856989) (xy 95.9354 -495.929525)
			(xy 96.021136 -496.008164) (xy 96.101243 -496.09253) (xy 96.175339 -496.182222) (xy 96.243069 -496.276812)
			(xy 96.304113 -496.37585) (xy 96.358178 -496.478863) (xy 96.405008 -496.58536) (xy 96.444379 -496.694835)
			(xy 96.476103 -496.806765) (xy 96.500029 -496.920617) (xy 96.516043 -497.035849) (xy 96.52407 -497.151911)
			(xy 96.524572 -497.21008) (xy 96.52407 -497.268249) (xy 96.516043 -497.384311) (xy 96.500029 -497.499543)
			(xy 96.476103 -497.613395) (xy 96.444379 -497.725325) (xy 96.405008 -497.8348) (xy 96.358178 -497.941297)
			(xy 96.304113 -498.04431) (xy 96.243069 -498.143348) (xy 96.175339 -498.237938) (xy 96.101243 -498.32763)
			(xy 96.021136 -498.411996) (xy 95.9354 -498.490635) (xy 95.844443 -498.563171) (xy 95.748697 -498.629259)
			(xy 95.648621 -498.688584) (xy 95.54469 -498.740863) (xy 95.4374 -498.785848) (xy 95.327262 -498.823323)
			(xy 95.214801 -498.85311) (xy 95.100553 -498.875068) (xy 94.985062 -498.889091) (xy 94.868879 -498.895113)
			(xy 94.752557 -498.893105) (xy 94.636651 -498.883076) (xy 94.521714 -498.865075) (xy 94.408291 -498.839187)
			(xy 94.296926 -498.805536) (xy 94.188147 -498.764282) (xy 94.082473 -498.715621) (xy 93.980409 -498.659785)
			(xy 93.88244 -498.597042) (xy 93.789033 -498.527688) (xy 93.700633 -498.452056) (xy 93.617662 -498.370505)
			(xy 93.540515 -498.283424) (xy 93.46956 -498.191228) (xy 93.405134 -498.094356) (xy 93.347545 -497.993271)
			(xy 93.297068 -497.888453) (xy 93.253942 -497.780402) (xy 93.218373 -497.669634) (xy 93.190531 -497.556675)
			(xy 93.170549 -497.442065) (xy 93.158522 -497.32635) (xy 93.154506 -497.21008) (xy 42.500813 -497.21008)
			(xy 42.479042 -497.226857) (xy 42.381609 -497.291665) (xy 42.279905 -497.34954) (xy 42.174422 -497.400202)
			(xy 42.065671 -497.443404) (xy 41.954179 -497.478939) (xy 41.840485 -497.506634) (xy 41.725141 -497.526354)
			(xy 41.608704 -497.538005) (xy 41.491739 -497.54153) (xy 41.374812 -497.536912) (xy 41.258489 -497.524173)
			(xy 41.143334 -497.503375) (xy 41.029905 -497.474618) (xy 40.91875 -497.438042) (xy 40.810407 -497.393825)
			(xy 40.705403 -497.342179) (xy 40.604244 -497.283356) (xy 40.507421 -497.21764) (xy 40.415403 -497.145349)
			(xy 40.328636 -497.066834) (xy 40.247539 -496.982474) (xy 40.172506 -496.892679) (xy 40.103899 -496.797883)
			(xy 40.042051 -496.698544) (xy 39.987262 -496.595145) (xy 39.939796 -496.488186) (xy 39.899884 -496.378185)
			(xy 39.86772 -496.265674) (xy 39.843457 -496.151199) (xy 39.827215 -496.035313) (xy 39.819072 -495.918579)
			(xy 39.818564 -495.86007) (xy 1.016 -495.86007) (xy 1.016 -500.99976) (xy 6.671831 -500.99976) (xy 6.675786 -500.907923)
			(xy 6.687621 -500.816766) (xy 6.707248 -500.726963) (xy 6.734522 -500.639181) (xy 6.769242 -500.554067)
			(xy 6.81115 -500.472254) (xy 6.859936 -500.394346) (xy 6.915239 -500.320921) (xy 6.976649 -500.252521)
			(xy 7.043711 -500.189654) (xy 7.11593 -500.132784) (xy 7.19277 -500.082333) (xy 7.273663 -500.038674)
			(xy 7.358009 -500.002131) (xy 7.445185 -499.972974) (xy 7.534544 -499.95142) (xy 7.625425 -499.937626)
			(xy 7.717156 -499.931696) (xy 7.809057 -499.933674) (xy 7.900448 -499.943545) (xy 7.990652 -499.961235)
			(xy 8.079001 -499.986615) (xy 8.164841 -500.019495) (xy 8.247537 -500.059633) (xy 8.326477 -500.106732)
			(xy 8.401075 -500.160442) (xy 8.470781 -500.220366) (xy 8.535076 -500.28606) (xy 8.593487 -500.357038)
			(xy 8.645579 -500.432775) (xy 8.690968 -500.51271) (xy 8.729318 -500.59625) (xy 8.760343 -500.682778)
			(xy 8.783816 -500.771653) (xy 8.799562 -500.862217) (xy 8.807464 -500.953799) (xy 8.807958 -500.99976)
			(xy 8.807464 -501.045721) (xy 8.799562 -501.137303) (xy 8.783816 -501.227867) (xy 8.760343 -501.316742)
			(xy 8.729318 -501.40327) (xy 8.690968 -501.48681) (xy 8.645579 -501.566745) (xy 8.593487 -501.642482)
			(xy 8.535076 -501.71346) (xy 8.470781 -501.779154) (xy 8.401075 -501.839078) (xy 8.326477 -501.892788)
			(xy 8.247537 -501.939887) (xy 8.164841 -501.980025) (xy 8.079001 -502.012905) (xy 7.990652 -502.038285)
			(xy 7.900448 -502.055975) (xy 7.809057 -502.065846) (xy 7.717156 -502.067824) (xy 7.625425 -502.061894)
			(xy 7.534544 -502.0481) (xy 7.445185 -502.026546) (xy 7.358009 -501.997389) (xy 7.273663 -501.960846)
			(xy 7.19277 -501.917187) (xy 7.11593 -501.866736) (xy 7.043711 -501.809866) (xy 6.976649 -501.746999)
			(xy 6.915239 -501.678599) (xy 6.859936 -501.605174) (xy 6.81115 -501.527266) (xy 6.769242 -501.445453)
			(xy 6.734522 -501.360339) (xy 6.707248 -501.272557) (xy 6.687621 -501.182754) (xy 6.675786 -501.091597)
			(xy 6.671831 -500.99976) (xy 1.016 -500.99976) (xy 1.016 -507.671578) (xy 1.016492 -507.686921) (xy 1.023881 -507.716707)
			(xy 1.038164 -507.74387) (xy 1.048004 -507.755652) (xy 1.065976 -507.776695) (xy 1.09629 -507.822991)
			(xy 1.119599 -507.87318) (xy 1.135415 -507.92621) (xy 1.143407 -507.980967) (xy 1.143407 -508.036305)
			(xy 1.135415 -508.091062) (xy 1.119599 -508.144092) (xy 1.09629 -508.194281) (xy 1.065976 -508.240577)
			(xy 1.048004 -508.26162) (xy 1.03813 -508.273379) (xy 1.023835 -508.300546) (xy 1.01646 -508.330345)
			(xy 1.016 -508.345694) (xy 1.016 -508.96012) (xy 86.877404 -508.96012) (xy 86.881424 -508.769469)
			(xy 86.893478 -508.579156) (xy 86.913544 -508.389521) (xy 86.941587 -508.2009) (xy 86.977556 -508.01363)
			(xy 87.021388 -507.828042) (xy 87.073005 -507.644467) (xy 87.132315 -507.463231) (xy 87.199213 -507.284656)
			(xy 87.273579 -507.109061) (xy 87.355281 -506.936756) (xy 87.444175 -506.768049) (xy 87.540101 -506.603239)
			(xy 87.64289 -506.44262) (xy 87.752359 -506.286477) (xy 87.868313 -506.135088) (xy 87.990547 -505.988721)
			(xy 88.118841 -505.847637) (xy 88.252969 -505.712088) (xy 88.392693 -505.582313) (xy 88.537763 -505.458543)
			(xy 88.687921 -505.341) (xy 88.842902 -505.229891) (xy 89.002429 -505.125414) (xy 89.166218 -505.027755)
			(xy 89.333978 -504.937088) (xy 89.505412 -504.853574) (xy 89.680214 -504.777361) (xy 89.858073 -504.708585)
			(xy 90.038674 -504.647367) (xy 90.221694 -504.593818) (xy 90.40681 -504.548032) (xy 90.593691 -504.51009)
			(xy 90.782006 -504.480061) (xy 90.971419 -504.457996) (xy 91.161593 -504.443937) (xy 91.352192 -504.437907)
			(xy 91.542875 -504.439917) (xy 91.733304 -504.449964) (xy 91.92314 -504.46803) (xy 92.112046 -504.494083)
			(xy 92.299685 -504.528076) (xy 92.485725 -504.569949) (xy 92.669834 -504.619628) (xy 92.851685 -504.677024)
			(xy 93.030955 -504.742035) (xy 93.207325 -504.814546) (xy 93.380481 -504.894427) (xy 93.550116 -504.981537)
			(xy 93.715928 -505.075721) (xy 93.877622 -505.176812) (xy 94.03491 -505.284628) (xy 94.187513 -505.39898)
			(xy 94.335161 -505.519663) (xy 94.477589 -505.646464) (xy 94.614545 -505.779155) (xy 94.745786 -505.917503)
			(xy 94.871078 -506.06126) (xy 94.990198 -506.210171) (xy 95.102934 -506.363972) (xy 95.209087 -506.522388)
			(xy 95.308467 -506.685139) (xy 95.400897 -506.851934) (xy 95.486214 -507.022478) (xy 95.564266 -507.196466)
			(xy 95.634913 -507.373591) (xy 95.698031 -507.553536) (xy 95.753507 -507.735982) (xy 95.801242 -507.920605)
			(xy 95.841152 -508.107075) (xy 95.873165 -508.295063) (xy 95.897225 -508.484233) (xy 95.913288 -508.674249)
			(xy 95.921327 -508.864773) (xy 95.92183 -508.96012) (xy 95.921327 -509.055467) (xy 95.913288 -509.245991)
			(xy 95.897225 -509.436007) (xy 95.873165 -509.625177) (xy 95.841152 -509.813165) (xy 95.801242 -509.999635)
			(xy 95.753507 -510.184258) (xy 95.698031 -510.366704) (xy 95.634913 -510.546649) (xy 95.564266 -510.723774)
			(xy 95.486214 -510.897762) (xy 95.400897 -511.068306) (xy 95.308467 -511.235101) (xy 95.209087 -511.397852)
			(xy 95.102934 -511.556268) (xy 94.990198 -511.710069) (xy 94.871078 -511.85898) (xy 94.745786 -512.002737)
			(xy 94.614545 -512.141085) (xy 94.477589 -512.273776) (xy 94.335161 -512.400577) (xy 94.187513 -512.52126)
			(xy 94.03491 -512.635612) (xy 93.877622 -512.743428) (xy 93.715928 -512.844519) (xy 93.550116 -512.938703)
			(xy 93.380481 -513.025813) (xy 93.207325 -513.105694) (xy 93.030955 -513.178205) (xy 92.851685 -513.243216)
			(xy 92.669834 -513.300612) (xy 92.485725 -513.350291) (xy 92.299685 -513.392164) (xy 92.112046 -513.426157)
			(xy 91.92314 -513.45221) (xy 91.733304 -513.470276) (xy 91.542875 -513.480323) (xy 91.352192 -513.482333)
			(xy 91.161593 -513.476303) (xy 90.971419 -513.462244) (xy 90.782006 -513.440179) (xy 90.593691 -513.41015)
			(xy 90.40681 -513.372208) (xy 90.221694 -513.326422) (xy 90.038674 -513.272873) (xy 89.858073 -513.211655)
			(xy 89.680214 -513.142879) (xy 89.505412 -513.066666) (xy 89.333978 -512.983152) (xy 89.166218 -512.892485)
			(xy 89.002429 -512.794826) (xy 88.842902 -512.690349) (xy 88.687921 -512.57924) (xy 88.537763 -512.461697)
			(xy 88.392693 -512.337927) (xy 88.252969 -512.208152) (xy 88.118841 -512.072603) (xy 87.990547 -511.931519)
			(xy 87.868313 -511.785152) (xy 87.752359 -511.633763) (xy 87.64289 -511.47762) (xy 87.540101 -511.317001)
			(xy 87.444175 -511.152191) (xy 87.355281 -510.983484) (xy 87.273579 -510.811179) (xy 87.199213 -510.635584)
			(xy 87.132315 -510.457009) (xy 87.073005 -510.275773) (xy 87.021388 -510.092198) (xy 86.977556 -509.90661)
			(xy 86.941587 -509.71934) (xy 86.913544 -509.530719) (xy 86.893478 -509.341084) (xy 86.881424 -509.150771)
			(xy 86.877404 -508.96012) (xy 1.016 -508.96012) (xy 1.016 -511.049778) (xy 6.671831 -511.049778)
			(xy 6.675786 -510.957941) (xy 6.687621 -510.866784) (xy 6.707248 -510.776981) (xy 6.734522 -510.689199)
			(xy 6.769242 -510.604085) (xy 6.81115 -510.522272) (xy 6.859936 -510.444364) (xy 6.915239 -510.370939)
			(xy 6.976649 -510.302539) (xy 7.043711 -510.239672) (xy 7.11593 -510.182802) (xy 7.19277 -510.132351)
			(xy 7.273663 -510.088692) (xy 7.358009 -510.052149) (xy 7.445185 -510.022992) (xy 7.534544 -510.001438)
			(xy 7.625425 -509.987644) (xy 7.717156 -509.981714) (xy 7.809057 -509.983692) (xy 7.900448 -509.993563)
			(xy 7.990652 -510.011253) (xy 8.079001 -510.036633) (xy 8.164841 -510.069513) (xy 8.247537 -510.109651)
			(xy 8.326477 -510.15675) (xy 8.401075 -510.21046) (xy 8.470781 -510.270384) (xy 8.535076 -510.336078)
			(xy 8.593487 -510.407056) (xy 8.645579 -510.482793) (xy 8.690968 -510.562728) (xy 8.729318 -510.646268)
			(xy 8.760343 -510.732796) (xy 8.783816 -510.821671) (xy 8.799562 -510.912235) (xy 8.807464 -511.003817)
			(xy 8.807958 -511.049778) (xy 8.807464 -511.095739) (xy 8.799562 -511.187321) (xy 8.783816 -511.277885)
			(xy 8.760343 -511.36676) (xy 8.729318 -511.453288) (xy 8.690968 -511.536828) (xy 8.645579 -511.616763)
			(xy 8.593487 -511.6925) (xy 8.535076 -511.763478) (xy 8.470781 -511.829172) (xy 8.401075 -511.889096)
			(xy 8.326477 -511.942806) (xy 8.247537 -511.989905) (xy 8.164841 -512.030043) (xy 8.079001 -512.062923)
			(xy 7.990652 -512.088303) (xy 7.900448 -512.105993) (xy 7.809057 -512.115864) (xy 7.717156 -512.117842)
			(xy 7.625425 -512.111912) (xy 7.534544 -512.098118) (xy 7.445185 -512.076564) (xy 7.358009 -512.047407)
			(xy 7.273663 -512.010864) (xy 7.19277 -511.967205) (xy 7.11593 -511.916754) (xy 7.043711 -511.859884)
			(xy 6.976649 -511.797017) (xy 6.915239 -511.728617) (xy 6.859936 -511.655192) (xy 6.81115 -511.577284)
			(xy 6.769242 -511.495471) (xy 6.734522 -511.410357) (xy 6.707248 -511.322575) (xy 6.687621 -511.232772)
			(xy 6.675786 -511.141615) (xy 6.671831 -511.049778) (xy 1.016 -511.049778) (xy 1.016 -520.04976)
			(xy 6.671831 -520.04976) (xy 6.675786 -519.957923) (xy 6.687621 -519.866766) (xy 6.707248 -519.776963)
			(xy 6.734522 -519.689181) (xy 6.769242 -519.604067) (xy 6.81115 -519.522254) (xy 6.859936 -519.444346)
			(xy 6.915239 -519.370921) (xy 6.976649 -519.302521) (xy 7.043711 -519.239654) (xy 7.11593 -519.182784)
			(xy 7.19277 -519.132333) (xy 7.273663 -519.088674) (xy 7.358009 -519.052131) (xy 7.445185 -519.022974)
			(xy 7.534544 -519.00142) (xy 7.625425 -518.987626) (xy 7.717156 -518.981696) (xy 7.809057 -518.983674)
			(xy 7.900448 -518.993545) (xy 7.990652 -519.011235) (xy 8.079001 -519.036615) (xy 8.113324 -519.049762)
			(xy 72.864987 -519.049762) (xy 72.868996 -518.846891) (xy 72.881016 -518.644337) (xy 72.90103 -518.442416)
			(xy 72.929005 -518.241443) (xy 72.964898 -518.041733) (xy 73.008652 -517.843596) (xy 73.060201 -517.647343)
			(xy 73.119462 -517.453279) (xy 73.186344 -517.261708) (xy 73.260742 -517.072929) (xy 73.34254 -516.887236)
			(xy 73.43161 -516.70492) (xy 73.527813 -516.526265) (xy 73.631 -516.351551) (xy 73.741008 -516.181049)
			(xy 73.857666 -516.015026) (xy 73.980792 -515.853742) (xy 74.110194 -515.697448) (xy 74.245669 -515.546388)
			(xy 74.387006 -515.400798) (xy 74.533985 -515.260906) (xy 74.686376 -515.12693) (xy 74.843941 -514.999078)
			(xy 75.006434 -514.877552) (xy 75.173601 -514.762539) (xy 75.345181 -514.654221) (xy 75.520906 -514.552766)
			(xy 75.700503 -514.458332) (xy 75.88369 -514.371067) (xy 76.070182 -514.291108) (xy 76.259687 -514.218579)
			(xy 76.451909 -514.153593) (xy 76.646549 -514.096251) (xy 76.843302 -514.046644) (xy 77.041861 -514.004849)
			(xy 77.241917 -513.970931) (xy 77.443156 -513.944943) (xy 77.645265 -513.926925) (xy 77.847928 -513.916906)
			(xy 78.050828 -513.914902) (xy 78.253649 -513.920914) (xy 78.456075 -513.934935) (xy 78.657788 -513.956943)
			(xy 78.858475 -513.986902) (xy 79.057821 -514.024766) (xy 79.255516 -514.070476) (xy 79.45125 -514.12396)
			(xy 79.644719 -514.185136) (xy 79.83562 -514.253907) (xy 80.023655 -514.330167) (xy 80.208531 -514.413795)
			(xy 80.389958 -514.504662) (xy 80.567654 -514.602625) (xy 80.74134 -514.707533) (xy 80.910747 -514.81922)
			(xy 81.075609 -514.937512) (xy 81.235669 -515.062226) (xy 81.390677 -515.193165) (xy 81.540391 -515.330126)
			(xy 81.684577 -515.472895) (xy 81.823011 -515.621249) (xy 81.955475 -515.774956) (xy 82.081764 -515.933776)
			(xy 82.201679 -516.097461) (xy 82.315035 -516.265756) (xy 82.421653 -516.438398) (xy 82.521367 -516.615118)
			(xy 82.614022 -516.795638) (xy 82.699472 -516.979678) (xy 82.777586 -517.166951) (xy 82.848239 -517.357163)
			(xy 82.911323 -517.550018) (xy 82.966739 -517.745215) (xy 83.0144 -517.942448) (xy 83.054231 -518.141411)
			(xy 83.086171 -518.341792) (xy 83.11017 -518.543278) (xy 83.12619 -518.745555) (xy 83.134207 -518.948307)
			(xy 83.134708 -519.049762) (xy 83.134207 -519.151217) (xy 83.12619 -519.353969) (xy 83.11017 -519.556246)
			(xy 83.086171 -519.757732) (xy 83.054231 -519.958113) (xy 83.0144 -520.157076) (xy 82.966739 -520.354309)
			(xy 82.911323 -520.549506) (xy 82.848239 -520.742361) (xy 82.777586 -520.932573) (xy 82.699472 -521.119846)
			(xy 82.614022 -521.303886) (xy 82.521367 -521.484406) (xy 82.421653 -521.661126) (xy 82.315035 -521.833768)
			(xy 82.201679 -522.002063) (xy 82.081764 -522.165748) (xy 81.955475 -522.324568) (xy 81.823011 -522.478275)
			(xy 81.684577 -522.626629) (xy 81.540391 -522.769398) (xy 81.390677 -522.906359) (xy 81.235669 -523.037298)
			(xy 81.075609 -523.162012) (xy 80.910747 -523.280304) (xy 80.74134 -523.391991) (xy 80.567654 -523.496899)
			(xy 80.389958 -523.594862) (xy 80.208531 -523.685729) (xy 80.023655 -523.769357) (xy 79.83562 -523.845617)
			(xy 79.644719 -523.914388) (xy 79.45125 -523.975564) (xy 79.255516 -524.029048) (xy 79.057821 -524.074758)
			(xy 78.858475 -524.112622) (xy 78.657788 -524.142581) (xy 78.456075 -524.164589) (xy 78.253649 -524.17861)
			(xy 78.050828 -524.184622) (xy 77.847928 -524.182618) (xy 77.645265 -524.172599) (xy 77.443156 -524.154581)
			(xy 77.241917 -524.128593) (xy 77.041861 -524.094675) (xy 76.843302 -524.05288) (xy 76.646549 -524.003273)
			(xy 76.451909 -523.945931) (xy 76.259687 -523.880945) (xy 76.070182 -523.808416) (xy 75.88369 -523.728457)
			(xy 75.700503 -523.641192) (xy 75.520906 -523.546758) (xy 75.345181 -523.445303) (xy 75.173601 -523.336985)
			(xy 75.006434 -523.221972) (xy 74.843941 -523.100446) (xy 74.686376 -522.972594) (xy 74.533985 -522.838618)
			(xy 74.387006 -522.698726) (xy 74.245669 -522.553136) (xy 74.110194 -522.402076) (xy 73.980792 -522.245782)
			(xy 73.857666 -522.084498) (xy 73.741008 -521.918475) (xy 73.631 -521.747973) (xy 73.527813 -521.573259)
			(xy 73.43161 -521.394604) (xy 73.34254 -521.212288) (xy 73.260742 -521.026595) (xy 73.186344 -520.837816)
			(xy 73.119462 -520.646245) (xy 73.060201 -520.452181) (xy 73.008652 -520.255928) (xy 72.964898 -520.057791)
			(xy 72.929005 -519.858081) (xy 72.90103 -519.657108) (xy 72.881016 -519.455187) (xy 72.868996 -519.252633)
			(xy 72.864987 -519.049762) (xy 8.113324 -519.049762) (xy 8.164841 -519.069495) (xy 8.247537 -519.109633)
			(xy 8.326477 -519.156732) (xy 8.401075 -519.210442) (xy 8.470781 -519.270366) (xy 8.535076 -519.33606)
			(xy 8.593487 -519.407038) (xy 8.645579 -519.482775) (xy 8.690968 -519.56271) (xy 8.729318 -519.64625)
			(xy 8.760343 -519.732778) (xy 8.783816 -519.821653) (xy 8.799562 -519.912217) (xy 8.807464 -520.003799)
			(xy 8.807958 -520.04976) (xy 8.807464 -520.095721) (xy 8.799562 -520.187303) (xy 8.783816 -520.277867)
			(xy 8.760343 -520.366742) (xy 8.729318 -520.45327) (xy 8.690968 -520.53681) (xy 8.645579 -520.616745)
			(xy 8.593487 -520.692482) (xy 8.535076 -520.76346) (xy 8.470781 -520.829154) (xy 8.401075 -520.889078)
			(xy 8.326477 -520.942788) (xy 8.247537 -520.989887) (xy 8.164841 -521.030025) (xy 8.079001 -521.062905)
			(xy 7.990652 -521.088285) (xy 7.900448 -521.105975) (xy 7.809057 -521.115846) (xy 7.717156 -521.117824)
			(xy 7.625425 -521.111894) (xy 7.534544 -521.0981) (xy 7.445185 -521.076546) (xy 7.358009 -521.047389)
			(xy 7.273663 -521.010846) (xy 7.19277 -520.967187) (xy 7.11593 -520.916736) (xy 7.043711 -520.859866)
			(xy 6.976649 -520.796999) (xy 6.915239 -520.728599) (xy 6.859936 -520.655174) (xy 6.81115 -520.577266)
			(xy 6.769242 -520.495453) (xy 6.734522 -520.410339) (xy 6.707248 -520.322557) (xy 6.687621 -520.232754)
			(xy 6.675786 -520.141597) (xy 6.671831 -520.04976) (xy 1.016 -520.04976) (xy 1.016 -520.371578) (xy 1.016492 -520.386921)
			(xy 1.023881 -520.416707) (xy 1.038164 -520.44387) (xy 1.048004 -520.455652) (xy 1.065976 -520.476695)
			(xy 1.09629 -520.522991) (xy 1.119599 -520.57318) (xy 1.135415 -520.62621) (xy 1.143407 -520.680967)
			(xy 1.143407 -520.736305) (xy 1.135415 -520.791062) (xy 1.119599 -520.844092) (xy 1.09629 -520.894281)
			(xy 1.065976 -520.940577) (xy 1.048004 -520.96162) (xy 1.03813 -520.973379) (xy 1.023835 -521.000546)
			(xy 1.01646 -521.030345) (xy 1.016 -521.045694) (xy 1.016 -524.500094) (xy 1.016496 -524.531776)
			(xy 1.024766 -524.594598) (xy 1.041166 -524.655803) (xy 1.065414 -524.714344) (xy 1.097096 -524.769219)
			(xy 1.13567 -524.819489) (xy 1.180475 -524.864294) (xy 1.230745 -524.902868) (xy 1.28562 -524.93455)
			(xy 1.344161 -524.958798) (xy 1.405366 -524.975198) (xy 1.468188 -524.983468) (xy 1.49987 -524.983964)
			(xy 6.478778 -524.983964) (xy 6.494104 -524.9835) (xy 6.523871 -524.976184) (xy 6.551041 -524.961993)
			(xy 6.562852 -524.952214) (xy 6.58388 -524.934272) (xy 6.630136 -524.904011) (xy 6.680275 -524.880743)
			(xy 6.733248 -524.864955) (xy 6.787944 -524.856977) (xy 6.84322 -524.856977) (xy 6.897916 -524.864955)
			(xy 6.950889 -524.880743) (xy 7.001028 -524.904011) (xy 7.047284 -524.934272) (xy 7.068312 -524.952214)
			(xy 7.080084 -524.962052) (xy 7.10726 -524.976271) (xy 7.13705 -524.98357) (xy 7.152386 -524.983964)
			(xy 19.178778 -524.983964) (xy 19.194104 -524.9835) (xy 19.223871 -524.976184) (xy 19.251041 -524.961993)
			(xy 19.262852 -524.952214) (xy 19.28388 -524.934272) (xy 19.330136 -524.904011) (xy 19.380275 -524.880743)
			(xy 19.433248 -524.864955) (xy 19.487944 -524.856977) (xy 19.54322 -524.856977) (xy 19.597916 -524.864955)
			(xy 19.650889 -524.880743) (xy 19.701028 -524.904011) (xy 19.747284 -524.934272) (xy 19.768312 -524.952214)
			(xy 19.780084 -524.962052) (xy 19.80726 -524.976271) (xy 19.83705 -524.98357) (xy 19.852386 -524.983964)
			(xy 23.50008 -524.983964) (xy 23.570659 -524.984449) (xy 23.711596 -524.992364) (xy 23.851867 -525.008169)
			(xy 23.991032 -525.031814) (xy 24.128651 -525.063226) (xy 24.264293 -525.102306) (xy 24.397529 -525.14893)
			(xy 24.527942 -525.202952) (xy 24.65512 -525.264202) (xy 24.778663 -525.332488) (xy 24.898183 -525.407593)
			(xy 25.013303 -525.489282) (xy 25.123662 -525.577298) (xy 25.228911 -525.671364) (xy 25.32872 -525.771184)
			(xy 25.422775 -525.876443) (xy 25.510779 -525.986811) (xy 25.592456 -526.10194) (xy 25.667549 -526.221468)
			(xy 25.735821 -526.345018) (xy 25.797057 -526.472203) (xy 25.851065 -526.602621) (xy 25.897675 -526.735863)
			(xy 25.93674 -526.871508) (xy 25.968138 -527.009131) (xy 25.991769 -527.148298) (xy 26.007559 -527.288571)
			(xy 26.015458 -527.429509) (xy 26.01595 -527.500088) (xy 26.01595 -528.500086) (xy 26.016486 -528.531772)
			(xy 26.024792 -528.594597) (xy 26.041223 -528.655801) (xy 26.065499 -528.714339) (xy 26.097206 -528.769209)
			(xy 26.135801 -528.819472) (xy 26.180623 -528.864271) (xy 26.230908 -528.902839) (xy 26.285794 -528.934516)
			(xy 26.344345 -528.958761) (xy 26.405558 -528.975159) (xy 26.468388 -528.983431) (xy 26.500074 -528.983956)
		)
		(stroke
			(width 0)
			(type solid)
		)
		(fill yes)
		(layer "In3.Cu")
		(net "P12V")
	)
	(gr_arc
		(start 1.500124 -3.999992)
		(mid 0.439376 -4.439368)
		(end 0 -5.500116)
		(stroke
			(width 2.032)
			(type default)
		)
		(layer "In3.Cu")
	)
	(gr_line
		(start 1.500124 -3.999992)
		(end 23.50008 -3.999992)
		(stroke
			(width 2.032)
			(type default)
		)
		(layer "In3.Cu")
	)
	(gr_line
		(start 16.578834 -384.960876)
		(end 16.578834 -384.927094)
		(stroke
			(width 2.54)
			(type default)
		)
		(layer "In3.Cu")
	)
	(gr_line
		(start 16.578834 -384.927094)
		(end 16.64716 -384.858768)
		(stroke
			(width 2.54)
			(type default)
		)
		(layer "In3.Cu")
	)
	(gr_line
		(start 16.578834 -29.360876)
		(end 16.578834 -29.327094)
		(stroke
			(width 2.54)
			(type default)
		)
		(layer "In3.Cu")
	)
	(gr_line
		(start 16.578834 -29.327094)
		(end 16.64716 -29.258768)
		(stroke
			(width 2.54)
			(type default)
		)
		(layer "In3.Cu")
	)
	(gr_line
		(start 16.579088 -473.860876)
		(end 16.579088 -473.827094)
		(stroke
			(width 2.54)
			(type default)
		)
		(layer "In3.Cu")
	)
	(gr_line
		(start 16.579088 -473.827094)
		(end 16.647414 -473.758768)
		(stroke
			(width 2.54)
			(type default)
		)
		(layer "In3.Cu")
	)
	(gr_line
		(start 16.579088 -296.060876)
		(end 16.579088 -296.027094)
		(stroke
			(width 2.54)
			(type default)
		)
		(layer "In3.Cu")
	)
	(gr_line
		(start 16.579088 -296.027094)
		(end 16.647414 -295.958768)
		(stroke
			(width 2.54)
			(type default)
		)
		(layer "In3.Cu")
	)
	(gr_line
		(start 16.579088 -207.160876)
		(end 16.579088 -207.127094)
		(stroke
			(width 2.54)
			(type default)
		)
		(layer "In3.Cu")
	)
	(gr_line
		(start 16.579088 -207.127094)
		(end 16.647414 -207.058768)
		(stroke
			(width 2.54)
			(type default)
		)
		(layer "In3.Cu")
	)
	(gr_line
		(start 16.579088 -118.260876)
		(end 16.579088 -118.227094)
		(stroke
			(width 2.54)
			(type default)
		)
		(layer "In3.Cu")
	)
	(gr_line
		(start 16.579088 -118.227094)
		(end 16.647414 -118.158768)
		(stroke
			(width 2.54)
			(type default)
		)
		(layer "In3.Cu")
	)
	(gr_circle
		(center 16.599662 -384.800094)
		(end 19.329908 -384.800094)
		(stroke
			(width 3.81)
			(type default)
		)
		(fill no)
		(layer "In3.Cu")
	)
	(gr_circle
		(center 16.599662 -384.800094)
		(end 21.480272 -384.800094)
		(stroke
			(width 0.508)
			(type default)
		)
		(fill no)
		(layer "In3.Cu")
	)
	(gr_circle
		(center 16.599662 -29.200094)
		(end 19.329908 -29.200094)
		(stroke
			(width 3.81)
			(type default)
		)
		(fill no)
		(layer "In3.Cu")
	)
	(gr_circle
		(center 16.599662 -29.200094)
		(end 21.480272 -29.200094)
		(stroke
			(width 0.508)
			(type default)
		)
		(fill no)
		(layer "In3.Cu")
	)
	(gr_circle
		(center 16.599916 -473.700094)
		(end 19.330162 -473.700094)
		(stroke
			(width 3.81)
			(type default)
		)
		(fill no)
		(layer "In3.Cu")
	)
	(gr_circle
		(center 16.599916 -473.700094)
		(end 21.480526 -473.700094)
		(stroke
			(width 0.508)
			(type default)
		)
		(fill no)
		(layer "In3.Cu")
	)
	(gr_circle
		(center 16.599916 -473.69984)
		(end 21.791168 -473.69984)
		(stroke
			(width 0.127)
			(type default)
		)
		(fill no)
		(layer "In3.Cu")
	)
	(gr_circle
		(center 16.599916 -384.79984)
		(end 21.791422 -384.79984)
		(stroke
			(width 0.127)
			(type default)
		)
		(fill no)
		(layer "In3.Cu")
	)
	(gr_circle
		(center 16.599916 -295.900094)
		(end 19.330162 -295.900094)
		(stroke
			(width 3.81)
			(type default)
		)
		(fill no)
		(layer "In3.Cu")
	)
	(gr_circle
		(center 16.599916 -295.900094)
		(end 21.480526 -295.900094)
		(stroke
			(width 0.508)
			(type default)
		)
		(fill no)
		(layer "In3.Cu")
	)
	(gr_circle
		(center 16.599916 -295.89984)
		(end 21.791422 -295.89984)
		(stroke
			(width 0.127)
			(type default)
		)
		(fill no)
		(layer "In3.Cu")
	)
	(gr_circle
		(center 16.599916 -207.000094)
		(end 19.330162 -207.000094)
		(stroke
			(width 3.81)
			(type default)
		)
		(fill no)
		(layer "In3.Cu")
	)
	(gr_circle
		(center 16.599916 -207.000094)
		(end 21.480526 -207.000094)
		(stroke
			(width 0.508)
			(type default)
		)
		(fill no)
		(layer "In3.Cu")
	)
	(gr_circle
		(center 16.599916 -206.99984)
		(end 21.791422 -206.99984)
		(stroke
			(width 0.127)
			(type default)
		)
		(fill no)
		(layer "In3.Cu")
	)
	(gr_circle
		(center 16.599916 -118.100094)
		(end 19.330162 -118.100094)
		(stroke
			(width 3.81)
			(type default)
		)
		(fill no)
		(layer "In3.Cu")
	)
	(gr_circle
		(center 16.599916 -118.100094)
		(end 21.480526 -118.100094)
		(stroke
			(width 0.508)
			(type default)
		)
		(fill no)
		(layer "In3.Cu")
	)
	(gr_circle
		(center 16.599916 -118.09984)
		(end 21.791422 -118.09984)
		(stroke
			(width 0.127)
			(type default)
		)
		(fill no)
		(layer "In3.Cu")
	)
	(gr_circle
		(center 16.599916 -29.19984)
		(end 21.79447 -29.19984)
		(stroke
			(width 0.127)
			(type default)
		)
		(fill no)
		(layer "In3.Cu")
	)
	(gr_line
		(start 23.50008 -525.999964)
		(end 1.500124 -525.999964)
		(stroke
			(width 2.032)
			(type default)
		)
		(layer "In3.Cu")
	)
	(gr_arc
		(start 23.50008 -3.999992)
		(mid 24.560648 -3.56069)
		(end 24.99995 -2.500122)
		(stroke
			(width 2.032)
			(type default)
		)
		(layer "In3.Cu")
	)
	(gr_line
		(start 24.99995 -528.500086)
		(end 24.99995 -527.500088)
		(stroke
			(width 2.032)
			(type default)
		)
		(layer "In3.Cu")
	)
	(gr_arc
		(start 24.99995 -528.500086)
		(mid 25.439426 -529.560658)
		(end 26.500074 -529.999956)
		(stroke
			(width 2.032)
			(type default)
		)
		(layer "In3.Cu")
	)
	(gr_arc
		(start 24.99995 -527.500088)
		(mid 24.560738 -526.439356)
		(end 23.50008 -525.999964)
		(stroke
			(width 2.032)
			(type default)
		)
		(layer "In3.Cu")
	)
	(gr_line
		(start 24.99995 -2.500122)
		(end 24.99995 -1.500124)
		(stroke
			(width 2.032)
			(type default)
		)
		(layer "In3.Cu")
	)
	(gr_arc
		(start 26.500074 0)
		(mid 25.439325 -0.439375)
		(end 24.99995 -1.500124)
		(stroke
			(width 2.032)
			(type default)
		)
		(layer "In3.Cu")
	)
	(gr_line
		(start 26.500074 0)
		(end 101.000052 0)
		(stroke
			(width 2.032)
			(type default)
		)
		(layer "In3.Cu")
	)
	(gr_arc
		(start 75.3999 -478.799906)
		(mid 77.999844 -481.39985)
		(end 80.599788 -478.799906)
		(stroke
			(width 2.032)
			(type default)
		)
		(layer "In3.Cu")
	)
	(gr_line
		(start 75.3999 -477.799908)
		(end 75.3999 -478.799906)
		(stroke
			(width 2.032)
			(type default)
		)
		(layer "In3.Cu")
	)
	(gr_line
		(start 77.051154 -479.403918)
		(end 77.051154 -477.167956)
		(stroke
			(width 2.032)
			(type default)
		)
		(layer "In3.Cu")
	)
	(gr_line
		(start 77.051154 -477.167956)
		(end 77.347826 -476.871284)
		(stroke
			(width 2.032)
			(type default)
		)
		(layer "In3.Cu")
	)
	(gr_line
		(start 77.324966 -480.156774)
		(end 77.324966 -479.837496)
		(stroke
			(width 2.032)
			(type default)
		)
		(layer "In3.Cu")
	)
	(gr_line
		(start 77.324966 -479.837496)
		(end 77.89545 -479.267012)
		(stroke
			(width 2.032)
			(type default)
		)
		(layer "In3.Cu")
	)
	(gr_line
		(start 77.347826 -476.871284)
		(end 78.922118 -476.871284)
		(stroke
			(width 2.032)
			(type default)
		)
		(layer "In3.Cu")
	)
	(gr_line
		(start 77.781404 -478.673668)
		(end 77.051154 -479.403918)
		(stroke
			(width 2.032)
			(type default)
		)
		(layer "In3.Cu")
	)
	(gr_line
		(start 77.89545 -479.267012)
		(end 78.123542 -479.267012)
		(stroke
			(width 2.032)
			(type default)
		)
		(layer "In3.Cu")
	)
	(gr_line
		(start 77.979016 -32.460438)
		(end 77.979016 -32.426656)
		(stroke
			(width 2.54)
			(type default)
		)
		(layer "In3.Cu")
	)
	(gr_line
		(start 77.979016 -32.426656)
		(end 78.047342 -32.35833)
		(stroke
			(width 2.54)
			(type default)
		)
		(layer "In3.Cu")
	)
	(gr_line
		(start 77.97927 -519.210544)
		(end 77.97927 -519.176762)
		(stroke
			(width 2.54)
			(type default)
		)
		(layer "In3.Cu")
	)
	(gr_line
		(start 77.97927 -519.176762)
		(end 78.047596 -519.108436)
		(stroke
			(width 2.54)
			(type default)
		)
		(layer "In3.Cu")
	)
	(gr_line
		(start 77.97927 -430.310544)
		(end 77.97927 -430.276762)
		(stroke
			(width 2.54)
			(type default)
		)
		(layer "In3.Cu")
	)
	(gr_line
		(start 77.97927 -430.276762)
		(end 78.047596 -430.208436)
		(stroke
			(width 2.54)
			(type default)
		)
		(layer "In3.Cu")
	)
	(gr_line
		(start 77.97927 -341.410544)
		(end 77.97927 -341.376762)
		(stroke
			(width 2.54)
			(type default)
		)
		(layer "In3.Cu")
	)
	(gr_line
		(start 77.97927 -341.376762)
		(end 78.047596 -341.308436)
		(stroke
			(width 2.54)
			(type default)
		)
		(layer "In3.Cu")
	)
	(gr_line
		(start 77.97927 -210.260438)
		(end 77.97927 -210.226656)
		(stroke
			(width 2.54)
			(type default)
		)
		(layer "In3.Cu")
	)
	(gr_line
		(start 77.97927 -210.226656)
		(end 78.047596 -210.15833)
		(stroke
			(width 2.54)
			(type default)
		)
		(layer "In3.Cu")
	)
	(gr_line
		(start 77.979524 -121.360438)
		(end 77.979524 -121.326656)
		(stroke
			(width 2.54)
			(type default)
		)
		(layer "In3.Cu")
	)
	(gr_line
		(start 77.979524 -121.326656)
		(end 78.04785 -121.25833)
		(stroke
			(width 2.54)
			(type default)
		)
		(layer "In3.Cu")
	)
	(gr_line
		(start 77.98689 -480.156774)
		(end 77.324966 -480.156774)
		(stroke
			(width 2.032)
			(type default)
		)
		(layer "In3.Cu")
	)
	(gr_circle
		(center 77.999844 -32.299656)
		(end 80.73009 -32.299656)
		(stroke
			(width 3.81)
			(type default)
		)
		(fill no)
		(layer "In3.Cu")
	)
	(gr_circle
		(center 77.999844 -32.299656)
		(end 82.880454 -32.299656)
		(stroke
			(width 0.508)
			(type default)
		)
		(fill no)
		(layer "In3.Cu")
	)
	(gr_circle
		(center 78.000098 -519.049762)
		(end 80.730344 -519.049762)
		(stroke
			(width 3.81)
			(type default)
		)
		(fill no)
		(layer "In3.Cu")
	)
	(gr_circle
		(center 78.000098 -519.049762)
		(end 82.880708 -519.049762)
		(stroke
			(width 0.508)
			(type default)
		)
		(fill no)
		(layer "In3.Cu")
	)
	(gr_circle
		(center 78.000098 -430.149762)
		(end 80.730344 -430.149762)
		(stroke
			(width 3.81)
			(type default)
		)
		(fill no)
		(layer "In3.Cu")
	)
	(gr_circle
		(center 78.000098 -430.149762)
		(end 82.880708 -430.149762)
		(stroke
			(width 0.508)
			(type default)
		)
		(fill no)
		(layer "In3.Cu")
	)
	(gr_circle
		(center 78.000098 -341.249762)
		(end 80.730344 -341.249762)
		(stroke
			(width 3.81)
			(type default)
		)
		(fill no)
		(layer "In3.Cu")
	)
	(gr_circle
		(center 78.000098 -341.249762)
		(end 82.880708 -341.249762)
		(stroke
			(width 0.508)
			(type default)
		)
		(fill no)
		(layer "In3.Cu")
	)
	(gr_circle
		(center 78.000098 -210.099656)
		(end 80.730344 -210.099656)
		(stroke
			(width 3.81)
			(type default)
		)
		(fill no)
		(layer "In3.Cu")
	)
	(gr_circle
		(center 78.000098 -210.099656)
		(end 82.880708 -210.099656)
		(stroke
			(width 0.508)
			(type default)
		)
		(fill no)
		(layer "In3.Cu")
	)
	(gr_circle
		(center 78.000352 -121.199656)
		(end 80.730598 -121.199656)
		(stroke
			(width 3.81)
			(type default)
		)
		(fill no)
		(layer "In3.Cu")
	)
	(gr_circle
		(center 78.000352 -121.199656)
		(end 82.880962 -121.199656)
		(stroke
			(width 0.508)
			(type default)
		)
		(fill no)
		(layer "In3.Cu")
	)
	(gr_line
		(start 78.123542 -479.267012)
		(end 78.169262 -479.312732)
		(stroke
			(width 2.032)
			(type default)
		)
		(layer "In3.Cu")
	)
	(gr_line
		(start 78.123542 -478.673668)
		(end 77.781404 -478.673668)
		(stroke
			(width 2.032)
			(type default)
		)
		(layer "In3.Cu")
	)
	(gr_line
		(start 78.123542 -478.673668)
		(end 79.332836 -478.673668)
		(stroke
			(width 2.032)
			(type default)
		)
		(layer "In3.Cu")
	)
	(gr_line
		(start 78.922118 -477.875092)
		(end 78.123542 -478.673668)
		(stroke
			(width 2.032)
			(type default)
		)
		(layer "In3.Cu")
	)
	(gr_line
		(start 78.922118 -476.871284)
		(end 78.922118 -477.875092)
		(stroke
			(width 2.032)
			(type default)
		)
		(layer "In3.Cu")
	)
	(gr_line
		(start 79.332836 -478.673668)
		(end 79.424022 -478.582482)
		(stroke
			(width 2.032)
			(type default)
		)
		(layer "In3.Cu")
	)
	(gr_line
		(start 79.424022 -478.719642)
		(end 77.98689 -480.156774)
		(stroke
			(width 2.032)
			(type default)
		)
		(layer "In3.Cu")
	)
	(gr_line
		(start 79.424022 -478.582482)
		(end 79.424022 -478.719642)
		(stroke
			(width 2.032)
			(type default)
		)
		(layer "In3.Cu")
	)
	(gr_line
		(start 80.599788 -478.799906)
		(end 80.599788 -477.799908)
		(stroke
			(width 2.032)
			(type default)
		)
		(layer "In3.Cu")
	)
	(gr_arc
		(start 80.599788 -477.799908)
		(mid 77.999844 -475.199964)
		(end 75.3999 -477.799908)
		(stroke
			(width 2.032)
			(type default)
		)
		(layer "In3.Cu")
	)
	(gr_line
		(start 101.000052 -529.999956)
		(end 26.500074 -529.999956)
		(stroke
			(width 2.032)
			(type default)
		)
		(layer "In3.Cu")
	)
	(gr_arc
		(start 101.000052 -529.999956)
		(mid 102.41428 -529.414185)
		(end 103.000048 -527.99996)
		(stroke
			(width 2.032)
			(type default)
		)
		(layer "In3.Cu")
	)
	(gr_arc
		(start 103.000048 -1.999996)
		(mid 102.414258 -0.585805)
		(end 101.000052 0)
		(stroke
			(width 2.032)
			(type default)
		)
		(layer "In3.Cu")
	)
	(gr_line
		(start 103.000048 -1.999996)
		(end 103.000048 -527.99996)
		(stroke
			(width 2.032)
			(type default)
		)
		(layer "In3.Cu")
	)
	(gr_line
		(start 0 -524.500094)
		(end 0 -5.500116)
		(stroke
			(width 0.2)
			(type default)
		)
		(layer "In4.Cu")
	)
	(gr_line
		(start 0 -524.500094)
		(end 0 -5.500116)
		(stroke
			(width 2.032)
			(type default)
		)
		(layer "In4.Cu")
	)
	(gr_arc
		(start 0 -524.500094)
		(mid 0.439393 -525.560749)
		(end 1.500124 -525.999964)
		(stroke
			(width 0.2)
			(type default)
		)
		(layer "In4.Cu")
	)
	(gr_arc
		(start 0 -524.500094)
		(mid 0.439393 -525.560749)
		(end 1.500124 -525.999964)
		(stroke
			(width 2.032)
			(type default)
		)
		(layer "In4.Cu")
	)
	(gr_poly
		(pts
			(xy 27.598878 -528.983956) (xy 27.614329 -528.983524) (xy 27.644326 -528.976099) (xy 27.671657 -528.961677)
			(xy 27.68346 -528.951698) (xy 27.704555 -528.933522) (xy 27.751023 -528.902846) (xy 27.801456 -528.87925)
			(xy 27.854784 -528.863235) (xy 27.909874 -528.855141) (xy 27.965554 -528.855141) (xy 28.020644 -528.863235)
			(xy 28.073972 -528.87925) (xy 28.124405 -528.902846) (xy 28.170873 -528.933522) (xy 28.191968 -528.951698)
			(xy 28.203783 -528.961661) (xy 28.231108 -528.976085) (xy 28.261101 -528.983509) (xy 28.27655 -528.983956)
			(xy 40.298878 -528.983956) (xy 40.314329 -528.983524) (xy 40.344326 -528.976099) (xy 40.371657 -528.961677)
			(xy 40.38346 -528.951698) (xy 40.404555 -528.933522) (xy 40.451023 -528.902846) (xy 40.501456 -528.87925)
			(xy 40.554784 -528.863235) (xy 40.609874 -528.855141) (xy 40.665554 -528.855141) (xy 40.720644 -528.863235)
			(xy 40.773972 -528.87925) (xy 40.824405 -528.902846) (xy 40.870873 -528.933522) (xy 40.891968 -528.951698)
			(xy 40.903783 -528.961661) (xy 40.931108 -528.976085) (xy 40.961101 -528.983509) (xy 40.97655 -528.983956)
			(xy 52.998878 -528.983956) (xy 53.014329 -528.983524) (xy 53.044326 -528.976099) (xy 53.071657 -528.961677)
			(xy 53.08346 -528.951698) (xy 53.104555 -528.933522) (xy 53.151023 -528.902846) (xy 53.201456 -528.87925)
			(xy 53.254784 -528.863235) (xy 53.309874 -528.855141) (xy 53.365554 -528.855141) (xy 53.420644 -528.863235)
			(xy 53.473972 -528.87925) (xy 53.524405 -528.902846) (xy 53.570873 -528.933522) (xy 53.591968 -528.951698)
			(xy 53.603783 -528.961661) (xy 53.631108 -528.976085) (xy 53.661101 -528.983509) (xy 53.67655 -528.983956)
			(xy 65.698878 -528.983956) (xy 65.714329 -528.983524) (xy 65.744326 -528.976099) (xy 65.771657 -528.961677)
			(xy 65.78346 -528.951698) (xy 65.804555 -528.933522) (xy 65.851023 -528.902846) (xy 65.901456 -528.87925)
			(xy 65.954784 -528.863235) (xy 66.009874 -528.855141) (xy 66.065554 -528.855141) (xy 66.120644 -528.863235)
			(xy 66.173972 -528.87925) (xy 66.224405 -528.902846) (xy 66.270873 -528.933522) (xy 66.291968 -528.951698)
			(xy 66.303783 -528.961661) (xy 66.331108 -528.976085) (xy 66.361101 -528.983509) (xy 66.37655 -528.983956)
			(xy 78.398878 -528.983956) (xy 78.414329 -528.983524) (xy 78.444326 -528.976099) (xy 78.471657 -528.961677)
			(xy 78.48346 -528.951698) (xy 78.504555 -528.933522) (xy 78.551023 -528.902846) (xy 78.601456 -528.87925)
			(xy 78.654784 -528.863235) (xy 78.709874 -528.855141) (xy 78.765554 -528.855141) (xy 78.820644 -528.863235)
			(xy 78.873972 -528.87925) (xy 78.924405 -528.902846) (xy 78.970873 -528.933522) (xy 78.991968 -528.951698)
			(xy 79.003783 -528.961661) (xy 79.031108 -528.976085) (xy 79.061101 -528.983509) (xy 79.07655 -528.983956)
			(xy 91.098878 -528.983956) (xy 91.114329 -528.983524) (xy 91.144326 -528.976099) (xy 91.171657 -528.961677)
			(xy 91.18346 -528.951698) (xy 91.204555 -528.933522) (xy 91.251023 -528.902846) (xy 91.301456 -528.87925)
			(xy 91.354784 -528.863235) (xy 91.409874 -528.855141) (xy 91.465554 -528.855141) (xy 91.520644 -528.863235)
			(xy 91.573972 -528.87925) (xy 91.624405 -528.902846) (xy 91.670873 -528.933522) (xy 91.691968 -528.951698)
			(xy 91.703783 -528.961661) (xy 91.731108 -528.976085) (xy 91.761101 -528.983509) (xy 91.77655 -528.983956)
			(xy 101.000052 -528.983956) (xy 101.045522 -528.983449) (xy 101.136075 -528.975062) (xy 101.225467 -528.958355)
			(xy 101.312937 -528.933471) (xy 101.397737 -528.900622) (xy 101.479144 -528.860089) (xy 101.556464 -528.812216)
			(xy 101.629036 -528.757413) (xy 101.696242 -528.696148) (xy 101.757508 -528.628942) (xy 101.812312 -528.55637)
			(xy 101.860185 -528.479051) (xy 101.900719 -528.397644) (xy 101.933569 -528.312844) (xy 101.958454 -528.225375)
			(xy 101.975161 -528.135983) (xy 101.983549 -528.04543) (xy 101.984048 -527.99996) (xy 101.984048 -525.382236)
			(xy 101.983586 -525.366909) (xy 101.976272 -525.337141) (xy 101.962081 -525.30997) (xy 101.952298 -525.298162)
			(xy 101.934352 -525.277135) (xy 101.904082 -525.230879) (xy 101.880807 -525.180739) (xy 101.865012 -525.127764)
			(xy 101.85703 -525.073064) (xy 101.857026 -525.017784) (xy 101.865002 -524.963083) (xy 101.88079 -524.910106)
			(xy 101.904059 -524.859963) (xy 101.934322 -524.813703) (xy 101.952298 -524.792702) (xy 101.962138 -524.780931)
			(xy 101.976362 -524.753756) (xy 101.983666 -524.723965) (xy 101.984048 -524.708628) (xy 101.984048 -512.682236)
			(xy 101.983586 -512.666909) (xy 101.976272 -512.637141) (xy 101.962081 -512.60997) (xy 101.952298 -512.598162)
			(xy 101.934352 -512.577135) (xy 101.904082 -512.530879) (xy 101.880807 -512.480739) (xy 101.865012 -512.427764)
			(xy 101.85703 -512.373064) (xy 101.857026 -512.317784) (xy 101.865002 -512.263083) (xy 101.88079 -512.210106)
			(xy 101.904059 -512.159963) (xy 101.934322 -512.113703) (xy 101.952298 -512.092702) (xy 101.962138 -512.080931)
			(xy 101.976362 -512.053756) (xy 101.983666 -512.023965) (xy 101.984048 -512.008628) (xy 101.984048 -499.982236)
			(xy 101.983586 -499.966909) (xy 101.976272 -499.937141) (xy 101.962081 -499.90997) (xy 101.952298 -499.898162)
			(xy 101.934352 -499.877135) (xy 101.904082 -499.830879) (xy 101.880807 -499.780739) (xy 101.865012 -499.727764)
			(xy 101.85703 -499.673064) (xy 101.857026 -499.617784) (xy 101.865002 -499.563083) (xy 101.88079 -499.510106)
			(xy 101.904059 -499.459963) (xy 101.934322 -499.413703) (xy 101.952298 -499.392702) (xy 101.962138 -499.380931)
			(xy 101.976362 -499.353756) (xy 101.983666 -499.323965) (xy 101.984048 -499.308628) (xy 101.984048 -487.282236)
			(xy 101.983586 -487.266909) (xy 101.976272 -487.237141) (xy 101.962081 -487.20997) (xy 101.952298 -487.198162)
			(xy 101.934352 -487.177135) (xy 101.904082 -487.130879) (xy 101.880807 -487.080739) (xy 101.865012 -487.027764)
			(xy 101.85703 -486.973064) (xy 101.857026 -486.917784) (xy 101.865002 -486.863083) (xy 101.88079 -486.810106)
			(xy 101.904059 -486.759963) (xy 101.934322 -486.713703) (xy 101.952298 -486.692702) (xy 101.962138 -486.680931)
			(xy 101.976362 -486.653756) (xy 101.983666 -486.623965) (xy 101.984048 -486.608628) (xy 101.984048 -474.582236)
			(xy 101.983586 -474.566909) (xy 101.976272 -474.537141) (xy 101.962081 -474.50997) (xy 101.952298 -474.498162)
			(xy 101.934352 -474.477135) (xy 101.904082 -474.430879) (xy 101.880807 -474.380739) (xy 101.865012 -474.327764)
			(xy 101.85703 -474.273064) (xy 101.857026 -474.217784) (xy 101.865002 -474.163083) (xy 101.88079 -474.110106)
			(xy 101.904059 -474.059963) (xy 101.934322 -474.013703) (xy 101.952298 -473.992702) (xy 101.962138 -473.980931)
			(xy 101.976362 -473.953756) (xy 101.983666 -473.923965) (xy 101.984048 -473.908628) (xy 101.984048 -461.882236)
			(xy 101.983586 -461.866909) (xy 101.976272 -461.837141) (xy 101.962081 -461.80997) (xy 101.952298 -461.798162)
			(xy 101.934352 -461.777135) (xy 101.904082 -461.730879) (xy 101.880807 -461.680739) (xy 101.865012 -461.627764)
			(xy 101.85703 -461.573064) (xy 101.857026 -461.517784) (xy 101.865002 -461.463083) (xy 101.88079 -461.410106)
			(xy 101.904059 -461.359963) (xy 101.934322 -461.313703) (xy 101.952298 -461.292702) (xy 101.962138 -461.280931)
			(xy 101.976362 -461.253756) (xy 101.983666 -461.223965) (xy 101.984048 -461.208628) (xy 101.984048 -449.182236)
			(xy 101.983586 -449.166909) (xy 101.976272 -449.137141) (xy 101.962081 -449.10997) (xy 101.952298 -449.098162)
			(xy 101.934352 -449.077135) (xy 101.904082 -449.030879) (xy 101.880807 -448.980739) (xy 101.865012 -448.927764)
			(xy 101.85703 -448.873064) (xy 101.857026 -448.817784) (xy 101.865002 -448.763083) (xy 101.88079 -448.710106)
			(xy 101.904059 -448.659963) (xy 101.934322 -448.613703) (xy 101.952298 -448.592702) (xy 101.962138 -448.580931)
			(xy 101.976362 -448.553756) (xy 101.983666 -448.523965) (xy 101.984048 -448.508628) (xy 101.984048 -436.482236)
			(xy 101.983586 -436.466909) (xy 101.976272 -436.437141) (xy 101.962081 -436.40997) (xy 101.952298 -436.398162)
			(xy 101.934352 -436.377135) (xy 101.904082 -436.330879) (xy 101.880807 -436.280739) (xy 101.865012 -436.227764)
			(xy 101.85703 -436.173064) (xy 101.857026 -436.117784) (xy 101.865002 -436.063083) (xy 101.88079 -436.010106)
			(xy 101.904059 -435.959963) (xy 101.934322 -435.913703) (xy 101.952298 -435.892702) (xy 101.962138 -435.880931)
			(xy 101.976362 -435.853756) (xy 101.983666 -435.823965) (xy 101.984048 -435.808628) (xy 101.984048 -423.782236)
			(xy 101.983586 -423.766909) (xy 101.976272 -423.737141) (xy 101.962081 -423.70997) (xy 101.952298 -423.698162)
			(xy 101.934352 -423.677135) (xy 101.904082 -423.630879) (xy 101.880807 -423.580739) (xy 101.865012 -423.527764)
			(xy 101.85703 -423.473064) (xy 101.857026 -423.417784) (xy 101.865002 -423.363083) (xy 101.88079 -423.310106)
			(xy 101.904059 -423.259963) (xy 101.934322 -423.213703) (xy 101.952298 -423.192702) (xy 101.962138 -423.180931)
			(xy 101.976362 -423.153756) (xy 101.983666 -423.123965) (xy 101.984048 -423.108628) (xy 101.984048 -411.082236)
			(xy 101.983586 -411.066909) (xy 101.976272 -411.037141) (xy 101.962081 -411.00997) (xy 101.952298 -410.998162)
			(xy 101.934352 -410.977135) (xy 101.904082 -410.930879) (xy 101.880807 -410.880739) (xy 101.865012 -410.827764)
			(xy 101.85703 -410.773064) (xy 101.857026 -410.717784) (xy 101.865002 -410.663083) (xy 101.88079 -410.610106)
			(xy 101.904059 -410.559963) (xy 101.934322 -410.513703) (xy 101.952298 -410.492702) (xy 101.962138 -410.480931)
			(xy 101.976362 -410.453756) (xy 101.983666 -410.423965) (xy 101.984048 -410.408628) (xy 101.984048 -398.382236)
			(xy 101.983586 -398.366909) (xy 101.976272 -398.337141) (xy 101.962081 -398.30997) (xy 101.952298 -398.298162)
			(xy 101.934352 -398.277135) (xy 101.904082 -398.230879) (xy 101.880807 -398.180739) (xy 101.865012 -398.127764)
			(xy 101.85703 -398.073064) (xy 101.857026 -398.017784) (xy 101.865002 -397.963083) (xy 101.88079 -397.910106)
			(xy 101.904059 -397.859963) (xy 101.934322 -397.813703) (xy 101.952298 -397.792702) (xy 101.962138 -397.780931)
			(xy 101.976362 -397.753756) (xy 101.983666 -397.723965) (xy 101.984048 -397.708628) (xy 101.984048 -385.682236)
			(xy 101.983586 -385.666909) (xy 101.976272 -385.637141) (xy 101.962081 -385.60997) (xy 101.952298 -385.598162)
			(xy 101.934352 -385.577135) (xy 101.904082 -385.530879) (xy 101.880807 -385.480739) (xy 101.865012 -385.427764)
			(xy 101.85703 -385.373064) (xy 101.857026 -385.317784) (xy 101.865002 -385.263083) (xy 101.88079 -385.210106)
			(xy 101.904059 -385.159963) (xy 101.934322 -385.113703) (xy 101.952298 -385.092702) (xy 101.962138 -385.080931)
			(xy 101.976362 -385.053756) (xy 101.983666 -385.023965) (xy 101.984048 -385.008628) (xy 101.984048 -372.982236)
			(xy 101.983586 -372.966909) (xy 101.976272 -372.937141) (xy 101.962081 -372.90997) (xy 101.952298 -372.898162)
			(xy 101.934352 -372.877135) (xy 101.904082 -372.830879) (xy 101.880807 -372.780739) (xy 101.865012 -372.727764)
			(xy 101.85703 -372.673064) (xy 101.857026 -372.617784) (xy 101.865002 -372.563083) (xy 101.88079 -372.510106)
			(xy 101.904059 -372.459963) (xy 101.934322 -372.413703) (xy 101.952298 -372.392702) (xy 101.962138 -372.380931)
			(xy 101.976362 -372.353756) (xy 101.983666 -372.323965) (xy 101.984048 -372.308628) (xy 101.984048 -360.282236)
			(xy 101.983586 -360.266909) (xy 101.976272 -360.237141) (xy 101.962081 -360.20997) (xy 101.952298 -360.198162)
			(xy 101.934352 -360.177135) (xy 101.904082 -360.130879) (xy 101.880807 -360.080739) (xy 101.865012 -360.027764)
			(xy 101.85703 -359.973064) (xy 101.857026 -359.917784) (xy 101.865002 -359.863083) (xy 101.88079 -359.810106)
			(xy 101.904059 -359.759963) (xy 101.934322 -359.713703) (xy 101.952298 -359.692702) (xy 101.962138 -359.680931)
			(xy 101.976362 -359.653756) (xy 101.983666 -359.623965) (xy 101.984048 -359.608628) (xy 101.984048 -347.582236)
			(xy 101.983586 -347.566909) (xy 101.976272 -347.537141) (xy 101.962081 -347.50997) (xy 101.952298 -347.498162)
			(xy 101.934352 -347.477135) (xy 101.904082 -347.430879) (xy 101.880807 -347.380739) (xy 101.865012 -347.327764)
			(xy 101.85703 -347.273064) (xy 101.857026 -347.217784) (xy 101.865002 -347.163083) (xy 101.88079 -347.110106)
			(xy 101.904059 -347.059963) (xy 101.934322 -347.013703) (xy 101.952298 -346.992702) (xy 101.962138 -346.980931)
			(xy 101.976362 -346.953756) (xy 101.983666 -346.923965) (xy 101.984048 -346.908628) (xy 101.984048 -334.882236)
			(xy 101.983586 -334.866909) (xy 101.976272 -334.837141) (xy 101.962081 -334.80997) (xy 101.952298 -334.798162)
			(xy 101.934352 -334.777135) (xy 101.904082 -334.730879) (xy 101.880807 -334.680739) (xy 101.865012 -334.627764)
			(xy 101.85703 -334.573064) (xy 101.857026 -334.517784) (xy 101.865002 -334.463083) (xy 101.88079 -334.410106)
			(xy 101.904059 -334.359963) (xy 101.934322 -334.313703) (xy 101.952298 -334.292702) (xy 101.962138 -334.280931)
			(xy 101.976362 -334.253756) (xy 101.983666 -334.223965) (xy 101.984048 -334.208628) (xy 101.984048 -322.182236)
			(xy 101.983586 -322.166909) (xy 101.976272 -322.137141) (xy 101.962081 -322.10997) (xy 101.952298 -322.098162)
			(xy 101.934352 -322.077135) (xy 101.904082 -322.030879) (xy 101.880807 -321.980739) (xy 101.865012 -321.927764)
			(xy 101.85703 -321.873064) (xy 101.857026 -321.817784) (xy 101.865002 -321.763083) (xy 101.88079 -321.710106)
			(xy 101.904059 -321.659963) (xy 101.934322 -321.613703) (xy 101.952298 -321.592702) (xy 101.962138 -321.580931)
			(xy 101.976362 -321.553756) (xy 101.983666 -321.523965) (xy 101.984048 -321.508628) (xy 101.984048 -309.482236)
			(xy 101.983586 -309.466909) (xy 101.976272 -309.437141) (xy 101.962081 -309.40997) (xy 101.952298 -309.398162)
			(xy 101.934352 -309.377135) (xy 101.904082 -309.330879) (xy 101.880807 -309.280739) (xy 101.865012 -309.227764)
			(xy 101.85703 -309.173064) (xy 101.857026 -309.117784) (xy 101.865002 -309.063083) (xy 101.88079 -309.010106)
			(xy 101.904059 -308.959963) (xy 101.934322 -308.913703) (xy 101.952298 -308.892702) (xy 101.962138 -308.880931)
			(xy 101.976362 -308.853756) (xy 101.983666 -308.823965) (xy 101.984048 -308.808628) (xy 101.984048 -296.782236)
			(xy 101.983586 -296.766909) (xy 101.976272 -296.737141) (xy 101.962081 -296.70997) (xy 101.952298 -296.698162)
			(xy 101.934352 -296.677135) (xy 101.904082 -296.630879) (xy 101.880807 -296.580739) (xy 101.865012 -296.527764)
			(xy 101.85703 -296.473064) (xy 101.857026 -296.417784) (xy 101.865002 -296.363083) (xy 101.88079 -296.310106)
			(xy 101.904059 -296.259963) (xy 101.934322 -296.213703) (xy 101.952298 -296.192702) (xy 101.962138 -296.180931)
			(xy 101.976362 -296.153756) (xy 101.983666 -296.123965) (xy 101.984048 -296.108628) (xy 101.984048 -284.082236)
			(xy 101.983586 -284.066909) (xy 101.976272 -284.037141) (xy 101.962081 -284.00997) (xy 101.952298 -283.998162)
			(xy 101.934352 -283.977135) (xy 101.904082 -283.930879) (xy 101.880807 -283.880739) (xy 101.865012 -283.827764)
			(xy 101.85703 -283.773064) (xy 101.857026 -283.717784) (xy 101.865002 -283.663083) (xy 101.88079 -283.610106)
			(xy 101.904059 -283.559963) (xy 101.934322 -283.513703) (xy 101.952298 -283.492702) (xy 101.962138 -283.480931)
			(xy 101.976362 -283.453756) (xy 101.983666 -283.423965) (xy 101.984048 -283.408628) (xy 101.984048 -271.382236)
			(xy 101.983586 -271.366909) (xy 101.976272 -271.337141) (xy 101.962081 -271.30997) (xy 101.952298 -271.298162)
			(xy 101.934352 -271.277135) (xy 101.904082 -271.230879) (xy 101.880807 -271.180739) (xy 101.865012 -271.127764)
			(xy 101.85703 -271.073064) (xy 101.857026 -271.017784) (xy 101.865002 -270.963083) (xy 101.88079 -270.910106)
			(xy 101.904059 -270.859963) (xy 101.934322 -270.813703) (xy 101.952298 -270.792702) (xy 101.962138 -270.780931)
			(xy 101.976362 -270.753756) (xy 101.983666 -270.723965) (xy 101.984048 -270.708628) (xy 101.984048 -258.682236)
			(xy 101.983586 -258.666909) (xy 101.976272 -258.637141) (xy 101.962081 -258.60997) (xy 101.952298 -258.598162)
			(xy 101.934352 -258.577135) (xy 101.904082 -258.530879) (xy 101.880807 -258.480739) (xy 101.865012 -258.427764)
			(xy 101.85703 -258.373064) (xy 101.857026 -258.317784) (xy 101.865002 -258.263083) (xy 101.88079 -258.210106)
			(xy 101.904059 -258.159963) (xy 101.934322 -258.113703) (xy 101.952298 -258.092702) (xy 101.962138 -258.080931)
			(xy 101.976362 -258.053756) (xy 101.983666 -258.023965) (xy 101.984048 -258.008628) (xy 101.984048 -245.982236)
			(xy 101.983586 -245.966909) (xy 101.976272 -245.937141) (xy 101.962081 -245.90997) (xy 101.952298 -245.898162)
			(xy 101.934352 -245.877135) (xy 101.904082 -245.830879) (xy 101.880807 -245.780739) (xy 101.865012 -245.727764)
			(xy 101.85703 -245.673064) (xy 101.857026 -245.617784) (xy 101.865002 -245.563083) (xy 101.88079 -245.510106)
			(xy 101.904059 -245.459963) (xy 101.934322 -245.413703) (xy 101.952298 -245.392702) (xy 101.962138 -245.380931)
			(xy 101.976362 -245.353756) (xy 101.983666 -245.323965) (xy 101.984048 -245.308628) (xy 101.984048 -233.282236)
			(xy 101.983586 -233.266909) (xy 101.976272 -233.237141) (xy 101.962081 -233.20997) (xy 101.952298 -233.198162)
			(xy 101.934352 -233.177135) (xy 101.904082 -233.130879) (xy 101.880807 -233.080739) (xy 101.865012 -233.027764)
			(xy 101.85703 -232.973064) (xy 101.857026 -232.917784) (xy 101.865002 -232.863083) (xy 101.88079 -232.810106)
			(xy 101.904059 -232.759963) (xy 101.934322 -232.713703) (xy 101.952298 -232.692702) (xy 101.962138 -232.680931)
			(xy 101.976362 -232.653756) (xy 101.983666 -232.623965) (xy 101.984048 -232.608628) (xy 101.984048 -220.582236)
			(xy 101.983586 -220.566909) (xy 101.976272 -220.537141) (xy 101.962081 -220.50997) (xy 101.952298 -220.498162)
			(xy 101.934352 -220.477135) (xy 101.904082 -220.430879) (xy 101.880807 -220.380739) (xy 101.865012 -220.327764)
			(xy 101.85703 -220.273064) (xy 101.857026 -220.217784) (xy 101.865002 -220.163083) (xy 101.88079 -220.110106)
			(xy 101.904059 -220.059963) (xy 101.934322 -220.013703) (xy 101.952298 -219.992702) (xy 101.962138 -219.980931)
			(xy 101.976362 -219.953756) (xy 101.983666 -219.923965) (xy 101.984048 -219.908628) (xy 101.984048 -207.882236)
			(xy 101.983586 -207.866909) (xy 101.976272 -207.837141) (xy 101.962081 -207.80997) (xy 101.952298 -207.798162)
			(xy 101.934352 -207.777135) (xy 101.904082 -207.730879) (xy 101.880807 -207.680739) (xy 101.865012 -207.627764)
			(xy 101.85703 -207.573064) (xy 101.857026 -207.517784) (xy 101.865002 -207.463083) (xy 101.88079 -207.410106)
			(xy 101.904059 -207.359963) (xy 101.934322 -207.313703) (xy 101.952298 -207.292702) (xy 101.962138 -207.280931)
			(xy 101.976362 -207.253756) (xy 101.983666 -207.223965) (xy 101.984048 -207.208628) (xy 101.984048 -195.182236)
			(xy 101.983586 -195.166909) (xy 101.976272 -195.137141) (xy 101.962081 -195.10997) (xy 101.952298 -195.098162)
			(xy 101.934352 -195.077135) (xy 101.904082 -195.030879) (xy 101.880807 -194.980739) (xy 101.865012 -194.927764)
			(xy 101.85703 -194.873064) (xy 101.857026 -194.817784) (xy 101.865002 -194.763083) (xy 101.88079 -194.710106)
			(xy 101.904059 -194.659963) (xy 101.934322 -194.613703) (xy 101.952298 -194.592702) (xy 101.962138 -194.580931)
			(xy 101.976362 -194.553756) (xy 101.983666 -194.523965) (xy 101.984048 -194.508628) (xy 101.984048 -182.482236)
			(xy 101.983586 -182.466909) (xy 101.976272 -182.437141) (xy 101.962081 -182.40997) (xy 101.952298 -182.398162)
			(xy 101.934352 -182.377135) (xy 101.904082 -182.330879) (xy 101.880807 -182.280739) (xy 101.865012 -182.227764)
			(xy 101.85703 -182.173064) (xy 101.857026 -182.117784) (xy 101.865002 -182.063083) (xy 101.88079 -182.010106)
			(xy 101.904059 -181.959963) (xy 101.934322 -181.913703) (xy 101.952298 -181.892702) (xy 101.962138 -181.880931)
			(xy 101.976362 -181.853756) (xy 101.983666 -181.823965) (xy 101.984048 -181.808628) (xy 101.984048 -169.782236)
			(xy 101.983586 -169.766909) (xy 101.976272 -169.737141) (xy 101.962081 -169.70997) (xy 101.952298 -169.698162)
			(xy 101.934352 -169.677135) (xy 101.904082 -169.630879) (xy 101.880807 -169.580739) (xy 101.865012 -169.527764)
			(xy 101.85703 -169.473064) (xy 101.857026 -169.417784) (xy 101.865002 -169.363083) (xy 101.88079 -169.310106)
			(xy 101.904059 -169.259963) (xy 101.934322 -169.213703) (xy 101.952298 -169.192702) (xy 101.962138 -169.180931)
			(xy 101.976362 -169.153756) (xy 101.983666 -169.123965) (xy 101.984048 -169.108628) (xy 101.984048 -157.082236)
			(xy 101.983586 -157.066909) (xy 101.976272 -157.037141) (xy 101.962081 -157.00997) (xy 101.952298 -156.998162)
			(xy 101.934352 -156.977135) (xy 101.904082 -156.930879) (xy 101.880807 -156.880739) (xy 101.865012 -156.827764)
			(xy 101.85703 -156.773064) (xy 101.857026 -156.717784) (xy 101.865002 -156.663083) (xy 101.88079 -156.610106)
			(xy 101.904059 -156.559963) (xy 101.934322 -156.513703) (xy 101.952298 -156.492702) (xy 101.962138 -156.480931)
			(xy 101.976362 -156.453756) (xy 101.983666 -156.423965) (xy 101.984048 -156.408628) (xy 101.984048 -144.382236)
			(xy 101.983586 -144.366909) (xy 101.976272 -144.337141) (xy 101.962081 -144.30997) (xy 101.952298 -144.298162)
			(xy 101.934352 -144.277135) (xy 101.904082 -144.230879) (xy 101.880807 -144.180739) (xy 101.865012 -144.127764)
			(xy 101.85703 -144.073064) (xy 101.857026 -144.017784) (xy 101.865002 -143.963083) (xy 101.88079 -143.910106)
			(xy 101.904059 -143.859963) (xy 101.934322 -143.813703) (xy 101.952298 -143.792702) (xy 101.962138 -143.780931)
			(xy 101.976362 -143.753756) (xy 101.983666 -143.723965) (xy 101.984048 -143.708628) (xy 101.984048 -131.682236)
			(xy 101.983586 -131.666909) (xy 101.976272 -131.637141) (xy 101.962081 -131.60997) (xy 101.952298 -131.598162)
			(xy 101.934352 -131.577135) (xy 101.904082 -131.530879) (xy 101.880807 -131.480739) (xy 101.865012 -131.427764)
			(xy 101.85703 -131.373064) (xy 101.857026 -131.317784) (xy 101.865002 -131.263083) (xy 101.88079 -131.210106)
			(xy 101.904059 -131.159963) (xy 101.934322 -131.113703) (xy 101.952298 -131.092702) (xy 101.962138 -131.080931)
			(xy 101.976362 -131.053756) (xy 101.983666 -131.023965) (xy 101.984048 -131.008628) (xy 101.984048 -118.982236)
			(xy 101.983586 -118.966909) (xy 101.976272 -118.937141) (xy 101.962081 -118.90997) (xy 101.952298 -118.898162)
			(xy 101.934352 -118.877135) (xy 101.904082 -118.830879) (xy 101.880807 -118.780739) (xy 101.865012 -118.727764)
			(xy 101.85703 -118.673064) (xy 101.857026 -118.617784) (xy 101.865002 -118.563083) (xy 101.88079 -118.510106)
			(xy 101.904059 -118.459963) (xy 101.934322 -118.413703) (xy 101.952298 -118.392702) (xy 101.962138 -118.380931)
			(xy 101.976362 -118.353756) (xy 101.983666 -118.323965) (xy 101.984048 -118.308628) (xy 101.984048 -106.282236)
			(xy 101.983586 -106.266909) (xy 101.976272 -106.237141) (xy 101.962081 -106.20997) (xy 101.952298 -106.198162)
			(xy 101.934352 -106.177135) (xy 101.904082 -106.130879) (xy 101.880807 -106.080739) (xy 101.865012 -106.027764)
			(xy 101.85703 -105.973064) (xy 101.857026 -105.917784) (xy 101.865002 -105.863083) (xy 101.88079 -105.810106)
			(xy 101.904059 -105.759963) (xy 101.934322 -105.713703) (xy 101.952298 -105.692702) (xy 101.962138 -105.680931)
			(xy 101.976362 -105.653756) (xy 101.983666 -105.623965) (xy 101.984048 -105.608628) (xy 101.984048 -93.582236)
			(xy 101.983586 -93.566909) (xy 101.976272 -93.537141) (xy 101.962081 -93.50997) (xy 101.952298 -93.498162)
			(xy 101.934352 -93.477135) (xy 101.904082 -93.430879) (xy 101.880807 -93.380739) (xy 101.865012 -93.327764)
			(xy 101.85703 -93.273064) (xy 101.857026 -93.217784) (xy 101.865002 -93.163083) (xy 101.88079 -93.110106)
			(xy 101.904059 -93.059963) (xy 101.934322 -93.013703) (xy 101.952298 -92.992702) (xy 101.962138 -92.980931)
			(xy 101.976362 -92.953756) (xy 101.983666 -92.923965) (xy 101.984048 -92.908628) (xy 101.984048 -80.882236)
			(xy 101.983586 -80.866909) (xy 101.976272 -80.837141) (xy 101.962081 -80.80997) (xy 101.952298 -80.798162)
			(xy 101.934352 -80.777135) (xy 101.904082 -80.730879) (xy 101.880807 -80.680739) (xy 101.865012 -80.627764)
			(xy 101.85703 -80.573064) (xy 101.857026 -80.517784) (xy 101.865002 -80.463083) (xy 101.88079 -80.410106)
			(xy 101.904059 -80.359963) (xy 101.934322 -80.313703) (xy 101.952298 -80.292702) (xy 101.962138 -80.280931)
			(xy 101.976362 -80.253756) (xy 101.983666 -80.223965) (xy 101.984048 -80.208628) (xy 101.984048 -68.182236)
			(xy 101.983586 -68.166909) (xy 101.976272 -68.137141) (xy 101.962081 -68.10997) (xy 101.952298 -68.098162)
			(xy 101.934352 -68.077135) (xy 101.904082 -68.030879) (xy 101.880807 -67.980739) (xy 101.865012 -67.927764)
			(xy 101.85703 -67.873064) (xy 101.857026 -67.817784) (xy 101.865002 -67.763083) (xy 101.88079 -67.710106)
			(xy 101.904059 -67.659963) (xy 101.934322 -67.613703) (xy 101.952298 -67.592702) (xy 101.962138 -67.580931)
			(xy 101.976362 -67.553756) (xy 101.983666 -67.523965) (xy 101.984048 -67.508628) (xy 101.984048 -55.482236)
			(xy 101.983586 -55.466909) (xy 101.976272 -55.437141) (xy 101.962081 -55.40997) (xy 101.952298 -55.398162)
			(xy 101.934352 -55.377135) (xy 101.904082 -55.330879) (xy 101.880807 -55.280739) (xy 101.865012 -55.227764)
			(xy 101.85703 -55.173064) (xy 101.857026 -55.117784) (xy 101.865002 -55.063083) (xy 101.88079 -55.010106)
			(xy 101.904059 -54.959963) (xy 101.934322 -54.913703) (xy 101.952298 -54.892702) (xy 101.962138 -54.880931)
			(xy 101.976362 -54.853756) (xy 101.983666 -54.823965) (xy 101.984048 -54.808628) (xy 101.984048 -42.782236)
			(xy 101.983586 -42.766909) (xy 101.976272 -42.737141) (xy 101.962081 -42.70997) (xy 101.952298 -42.698162)
			(xy 101.934352 -42.677135) (xy 101.904082 -42.630879) (xy 101.880807 -42.580739) (xy 101.865012 -42.527764)
			(xy 101.85703 -42.473064) (xy 101.857026 -42.417784) (xy 101.865002 -42.363083) (xy 101.88079 -42.310106)
			(xy 101.904059 -42.259963) (xy 101.934322 -42.213703) (xy 101.952298 -42.192702) (xy 101.962138 -42.180931)
			(xy 101.976362 -42.153756) (xy 101.983666 -42.123965) (xy 101.984048 -42.108628) (xy 101.984048 -30.082236)
			(xy 101.983586 -30.066909) (xy 101.976272 -30.037141) (xy 101.962081 -30.00997) (xy 101.952298 -29.998162)
			(xy 101.934352 -29.977135) (xy 101.904082 -29.930879) (xy 101.880807 -29.880739) (xy 101.865012 -29.827764)
			(xy 101.85703 -29.773064) (xy 101.857026 -29.717784) (xy 101.865002 -29.663083) (xy 101.88079 -29.610106)
			(xy 101.904059 -29.559963) (xy 101.934322 -29.513703) (xy 101.952298 -29.492702) (xy 101.962138 -29.480931)
			(xy 101.976362 -29.453756) (xy 101.983666 -29.423965) (xy 101.984048 -29.408628) (xy 101.984048 -17.382236)
			(xy 101.983586 -17.366909) (xy 101.976272 -17.337141) (xy 101.962081 -17.30997) (xy 101.952298 -17.298162)
			(xy 101.934352 -17.277135) (xy 101.904082 -17.230879) (xy 101.880807 -17.180739) (xy 101.865012 -17.127764)
			(xy 101.85703 -17.073064) (xy 101.857026 -17.017784) (xy 101.865002 -16.963083) (xy 101.88079 -16.910106)
			(xy 101.904059 -16.859963) (xy 101.934322 -16.813703) (xy 101.952298 -16.792702) (xy 101.962138 -16.780931)
			(xy 101.976362 -16.753756) (xy 101.983666 -16.723965) (xy 101.984048 -16.708628) (xy 101.984048 -4.682236)
			(xy 101.983586 -4.666909) (xy 101.976272 -4.637141) (xy 101.962081 -4.60997) (xy 101.952298 -4.598162)
			(xy 101.934352 -4.577135) (xy 101.904082 -4.530879) (xy 101.880807 -4.480739) (xy 101.865012 -4.427764)
			(xy 101.85703 -4.373064) (xy 101.857026 -4.317784) (xy 101.865002 -4.263083) (xy 101.88079 -4.210106)
			(xy 101.904059 -4.159963) (xy 101.934322 -4.113703) (xy 101.952298 -4.092702) (xy 101.962138 -4.080931)
			(xy 101.976362 -4.053756) (xy 101.983666 -4.023965) (xy 101.984048 -4.008628) (xy 101.984048 -1.999996)
			(xy 101.983539 -1.954528) (xy 101.975148 -1.863979) (xy 101.958437 -1.77459) (xy 101.93355 -1.687125)
			(xy 101.900699 -1.60233) (xy 101.860163 -1.520927) (xy 101.81229 -1.443612) (xy 101.757486 -1.371044)
			(xy 101.696221 -1.303842) (xy 101.629016 -1.242581) (xy 101.556445 -1.187781) (xy 101.479127 -1.139911)
			(xy 101.397723 -1.09938) (xy 101.312925 -1.066533) (xy 101.225459 -1.041651) (xy 101.13607 -1.024945)
			(xy 101.04552 -1.016559) (xy 101.000052 -1.016) (xy 95.642938 -1.016) (xy 95.627553 -1.016471) (xy 95.597681 -1.023847)
			(xy 95.570441 -1.038157) (xy 95.55861 -1.048004) (xy 95.537572 -1.065987) (xy 95.491281 -1.09632)
			(xy 95.441093 -1.119645) (xy 95.388061 -1.135473) (xy 95.333298 -1.14347) (xy 95.277954 -1.14347)
			(xy 95.223191 -1.135473) (xy 95.170159 -1.119645) (xy 95.119971 -1.09632) (xy 95.07368 -1.065987)
			(xy 95.052642 -1.048004) (xy 95.04085 -1.0381) (xy 95.0136 -1.023771) (xy 94.983708 -1.016401) (xy 94.968314 -1.016)
			(xy 82.942938 -1.016) (xy 82.927553 -1.016471) (xy 82.897681 -1.023847) (xy 82.870441 -1.038157)
			(xy 82.85861 -1.048004) (xy 82.837572 -1.065987) (xy 82.791281 -1.09632) (xy 82.741093 -1.119645)
			(xy 82.688061 -1.135473) (xy 82.633298 -1.14347) (xy 82.577954 -1.14347) (xy 82.523191 -1.135473)
			(xy 82.470159 -1.119645) (xy 82.419971 -1.09632) (xy 82.37368 -1.065987) (xy 82.352642 -1.048004)
			(xy 82.34085 -1.0381) (xy 82.3136 -1.023771) (xy 82.283708 -1.016401) (xy 82.268314 -1.016) (xy 70.242938 -1.016)
			(xy 70.227553 -1.016471) (xy 70.197681 -1.023847) (xy 70.170441 -1.038157) (xy 70.15861 -1.048004)
			(xy 70.137572 -1.065987) (xy 70.091281 -1.09632) (xy 70.041093 -1.119645) (xy 69.988061 -1.135473)
			(xy 69.933298 -1.14347) (xy 69.877954 -1.14347) (xy 69.823191 -1.135473) (xy 69.770159 -1.119645)
			(xy 69.719971 -1.09632) (xy 69.67368 -1.065987) (xy 69.652642 -1.048004) (xy 69.64085 -1.0381) (xy 69.6136 -1.023771)
			(xy 69.583708 -1.016401) (xy 69.568314 -1.016) (xy 57.542938 -1.016) (xy 57.527553 -1.016471) (xy 57.497681 -1.023847)
			(xy 57.470441 -1.038157) (xy 57.45861 -1.048004) (xy 57.437572 -1.065987) (xy 57.391281 -1.09632)
			(xy 57.341093 -1.119645) (xy 57.288061 -1.135473) (xy 57.233298 -1.14347) (xy 57.177954 -1.14347)
			(xy 57.123191 -1.135473) (xy 57.070159 -1.119645) (xy 57.019971 -1.09632) (xy 56.97368 -1.065987)
			(xy 56.952642 -1.048004) (xy 56.94085 -1.0381) (xy 56.9136 -1.023771) (xy 56.883708 -1.016401) (xy 56.868314 -1.016)
			(xy 44.842938 -1.016) (xy 44.827553 -1.016471) (xy 44.797681 -1.023847) (xy 44.770441 -1.038157)
			(xy 44.75861 -1.048004) (xy 44.737572 -1.065987) (xy 44.691281 -1.09632) (xy 44.641093 -1.119645)
			(xy 44.588061 -1.135473) (xy 44.533298 -1.14347) (xy 44.477954 -1.14347) (xy 44.423191 -1.135473)
			(xy 44.370159 -1.119645) (xy 44.319971 -1.09632) (xy 44.27368 -1.065987) (xy 44.252642 -1.048004)
			(xy 44.24085 -1.0381) (xy 44.2136 -1.023771) (xy 44.183708 -1.016401) (xy 44.168314 -1.016) (xy 32.142938 -1.016)
			(xy 32.127553 -1.016471) (xy 32.097681 -1.023847) (xy 32.070441 -1.038157) (xy 32.05861 -1.048004)
			(xy 32.037572 -1.065987) (xy 31.991281 -1.09632) (xy 31.941093 -1.119645) (xy 31.888061 -1.135473)
			(xy 31.833298 -1.14347) (xy 31.777954 -1.14347) (xy 31.723191 -1.135473) (xy 31.670159 -1.119645)
			(xy 31.619971 -1.09632) (xy 31.57368 -1.065987) (xy 31.552642 -1.048004) (xy 31.54085 -1.0381) (xy 31.5136 -1.023771)
			(xy 31.483708 -1.016401) (xy 31.468314 -1.016) (xy 26.500074 -1.016) (xy 26.468378 -1.01652) (xy 26.40553 -1.024797)
			(xy 26.3443 -1.041207) (xy 26.285735 -1.065469) (xy 26.230839 -1.097168) (xy 26.180549 -1.13576)
			(xy 26.135727 -1.180587) (xy 26.09714 -1.23088) (xy 26.065447 -1.28578) (xy 26.041191 -1.344347)
			(xy 26.024788 -1.405579) (xy 26.016517 -1.468428) (xy 26.01595 -1.500124) (xy 26.01595 -2.500122)
			(xy 26.015455 -2.570697) (xy 26.007541 -2.711624) (xy 25.991737 -2.851885) (xy 25.968093 -2.99104)
			(xy 25.936685 -3.12865) (xy 25.897609 -3.264283) (xy 25.850991 -3.397511) (xy 25.796975 -3.527916)
			(xy 25.735733 -3.655087) (xy 25.667456 -3.778624) (xy 25.59236 -3.898139) (xy 25.510681 -4.013254)
			(xy 25.422676 -4.123609) (xy 25.328622 -4.228856) (xy 25.228814 -4.328663) (xy 25.123568 -4.422717)
			(xy 25.013213 -4.510723) (xy 24.898097 -4.592401) (xy 24.778582 -4.667497) (xy 24.655045 -4.735774)
			(xy 24.527874 -4.797016) (xy 24.39747 -4.851032) (xy 24.264241 -4.89765) (xy 24.128608 -4.936725)
			(xy 23.990998 -4.968134) (xy 23.851843 -4.991777) (xy 23.711582 -5.007581) (xy 23.570655 -5.015495)
			(xy 23.50008 -5.015992) (xy 19.443446 -5.015992) (xy 19.428061 -5.016462) (xy 19.398187 -5.023837)
			(xy 19.370945 -5.038144) (xy 19.359118 -5.047996) (xy 19.338059 -5.06606) (xy 19.2917 -5.096538)
			(xy 19.241414 -5.119978) (xy 19.188262 -5.135885) (xy 19.133366 -5.143923) (xy 19.077886 -5.143923)
			(xy 19.02299 -5.135885) (xy 18.969838 -5.119978) (xy 18.919552 -5.096538) (xy 18.873193 -5.06606)
			(xy 18.852134 -5.047996) (xy 18.840341 -5.038093) (xy 18.813091 -5.023766) (xy 18.7832 -5.016399)
			(xy 18.767806 -5.015992) (xy 6.743446 -5.015992) (xy 6.728061 -5.016462) (xy 6.698187 -5.023837)
			(xy 6.670945 -5.038144) (xy 6.659118 -5.047996) (xy 6.638059 -5.06606) (xy 6.5917 -5.096538) (xy 6.541414 -5.119978)
			(xy 6.488262 -5.135885) (xy 6.433366 -5.143923) (xy 6.377886 -5.143923) (xy 6.32299 -5.135885) (xy 6.269838 -5.119978)
			(xy 6.219552 -5.096538) (xy 6.173193 -5.06606) (xy 6.152134 -5.047996) (xy 6.140341 -5.038093) (xy 6.113091 -5.023766)
			(xy 6.0832 -5.016399) (xy 6.067806 -5.015992) (xy 1.500124 -5.015992) (xy 1.468427 -5.016511) (xy 1.405575 -5.024786)
			(xy 1.344341 -5.041194) (xy 1.285773 -5.065454) (xy 1.230872 -5.097152) (xy 1.180579 -5.135744) (xy 1.135752 -5.18057)
			(xy 1.09716 -5.230864) (xy 1.065463 -5.285765) (xy 1.041203 -5.344333) (xy 1.024795 -5.405567) (xy 1.01652 -5.468419)
			(xy 1.016 -5.500116) (xy 1.016 -7.747) (xy 5.5306 -7.747) (xy 5.534631 -7.617434) (xy 5.54671 -7.48837)
			(xy 5.566789 -7.360306) (xy 5.594791 -7.233739) (xy 5.630608 -7.109156) (xy 5.6741 -6.987042) (xy 5.7251 -6.867868)
			(xy 5.783411 -6.752095) (xy 5.848806 -6.640171) (xy 5.921033 -6.532529) (xy 5.999813 -6.429586) (xy 6.08484 -6.33174)
			(xy 6.175785 -6.239368) (xy 6.272297 -6.15283) (xy 6.374003 -6.072459) (xy 6.480509 -5.998567) (xy 6.591402 -5.931439)
			(xy 6.706254 -5.871335) (xy 6.824621 -5.818488) (xy 6.946044 -5.773101) (xy 7.070054 -5.735352) (xy 7.196171 -5.705385)
			(xy 7.323907 -5.683316) (xy 7.452768 -5.669232) (xy 7.582255 -5.663186) (xy 7.711868 -5.665202) (xy 7.841104 -5.675272)
			(xy 7.969465 -5.693357) (xy 8.096453 -5.719387) (xy 8.221577 -5.753262) (xy 8.344353 -5.79485) (xy 8.464306 -5.843991)
			(xy 8.580971 -5.900494) (xy 8.693899 -5.964141) (xy 8.802651 -6.034685) (xy 8.906807 -6.111854) (xy 9.005964 -6.195349)
			(xy 9.099738 -6.284847) (xy 9.187767 -6.380002) (xy 9.26971 -6.480445) (xy 9.345249 -6.585788) (xy 9.414094 -6.695624)
			(xy 9.475977 -6.809528) (xy 9.522754 -6.91007) (xy 39.818564 -6.91007) (xy 39.819054 -6.852663) (xy 39.826889 -6.738117)
			(xy 39.842523 -6.624372) (xy 39.865882 -6.51196) (xy 39.896859 -6.401403) (xy 39.935308 -6.293218)
			(xy 39.98105 -6.18791) (xy 40.033872 -6.085968) (xy 40.093527 -5.987869) (xy 40.159738 -5.894069)
			(xy 40.232196 -5.805007) (xy 40.310562 -5.721096) (xy 40.394473 -5.64273) (xy 40.483535 -5.570272)
			(xy 40.577335 -5.504061) (xy 40.675434 -5.444406) (xy 40.777376 -5.391584) (xy 40.882684 -5.345842)
			(xy 40.990869 -5.307393) (xy 41.101426 -5.276416) (xy 41.213838 -5.253057) (xy 41.327583 -5.237423)
			(xy 41.442129 -5.229588) (xy 41.556943 -5.229588) (xy 41.671489 -5.237423) (xy 41.785234 -5.253057)
			(xy 41.897646 -5.276416) (xy 42.008203 -5.307393) (xy 42.116388 -5.345842) (xy 42.221696 -5.391584)
			(xy 42.323638 -5.444406) (xy 42.421737 -5.504061) (xy 42.515537 -5.570272) (xy 42.604599 -5.64273)
			(xy 42.68851 -5.721096) (xy 42.766876 -5.805007) (xy 42.839334 -5.894069) (xy 42.905545 -5.987869)
			(xy 42.9652 -6.085968) (xy 43.018022 -6.18791) (xy 43.063764 -6.293218) (xy 43.102213 -6.401403)
			(xy 43.13319 -6.51196) (xy 43.156549 -6.624372) (xy 43.172183 -6.738117) (xy 43.180018 -6.852663)
			(xy 43.180508 -6.91007) (xy 43.180381 -6.943251) (xy 43.177842 -7.009565) (xy 43.175428 -7.042658)
			(xy 43.170272 -7.100942) (xy 43.152948 -7.216671) (xy 43.127616 -7.330914) (xy 43.094401 -7.443119)
			(xy 43.053462 -7.552742) (xy 43.004999 -7.659253) (xy 42.949245 -7.762135) (xy 42.886471 -7.860891)
			(xy 42.816981 -7.955042) (xy 42.741111 -8.044132) (xy 42.659229 -8.127729) (xy 42.571732 -8.20543)
			(xy 42.500813 -8.26008) (xy 93.154506 -8.26008) (xy 93.158522 -8.14381) (xy 93.170549 -8.028095)
			(xy 93.190531 -7.913485) (xy 93.218373 -7.800526) (xy 93.253942 -7.689758) (xy 93.297068 -7.581707)
			(xy 93.347545 -7.476889) (xy 93.405134 -7.375804) (xy 93.46956 -7.278932) (xy 93.540515 -7.186736)
			(xy 93.617662 -7.099655) (xy 93.700633 -7.018104) (xy 93.789033 -6.942472) (xy 93.88244 -6.873118)
			(xy 93.980409 -6.810375) (xy 94.082473 -6.754539) (xy 94.188147 -6.705878) (xy 94.296926 -6.664624)
			(xy 94.408291 -6.630973) (xy 94.521714 -6.605085) (xy 94.636651 -6.587084) (xy 94.752557 -6.577055)
			(xy 94.868879 -6.575047) (xy 94.985062 -6.581069) (xy 95.100553 -6.595092) (xy 95.214801 -6.61705)
			(xy 95.327262 -6.646837) (xy 95.4374 -6.684312) (xy 95.54469 -6.729297) (xy 95.648621 -6.781576)
			(xy 95.748697 -6.840901) (xy 95.844443 -6.906989) (xy 95.9354 -6.979525) (xy 96.021136 -7.058164)
			(xy 96.101243 -7.14253) (xy 96.175339 -7.232222) (xy 96.243069 -7.326812) (xy 96.304113 -7.42585)
			(xy 96.358178 -7.528863) (xy 96.405008 -7.63536) (xy 96.444379 -7.744835) (xy 96.476103 -7.856765)
			(xy 96.500029 -7.970617) (xy 96.516043 -8.085849) (xy 96.52407 -8.201911) (xy 96.524572 -8.26008)
			(xy 96.52407 -8.318249) (xy 96.516043 -8.434311) (xy 96.500029 -8.549543) (xy 96.476103 -8.663395)
			(xy 96.444379 -8.775325) (xy 96.405008 -8.8848) (xy 96.358178 -8.991297) (xy 96.304113 -9.09431)
			(xy 96.243069 -9.193348) (xy 96.175339 -9.287938) (xy 96.101243 -9.37763) (xy 96.021136 -9.461996)
			(xy 95.9354 -9.540635) (xy 95.844443 -9.613171) (xy 95.748697 -9.679259) (xy 95.648621 -9.738584)
			(xy 95.54469 -9.790863) (xy 95.4374 -9.835848) (xy 95.327262 -9.873323) (xy 95.214801 -9.90311) (xy 95.100553 -9.925068)
			(xy 94.985062 -9.939091) (xy 94.868879 -9.945113) (xy 94.752557 -9.943105) (xy 94.636651 -9.933076)
			(xy 94.521714 -9.915075) (xy 94.408291 -9.889187) (xy 94.296926 -9.855536) (xy 94.188147 -9.814282)
			(xy 94.082473 -9.765621) (xy 93.980409 -9.709785) (xy 93.88244 -9.647042) (xy 93.789033 -9.577688)
			(xy 93.700633 -9.502056) (xy 93.617662 -9.420505) (xy 93.540515 -9.333424) (xy 93.46956 -9.241228)
			(xy 93.405134 -9.144356) (xy 93.347545 -9.043271) (xy 93.297068 -8.938453) (xy 93.253942 -8.830402)
			(xy 93.218373 -8.719634) (xy 93.190531 -8.606675) (xy 93.170549 -8.492065) (xy 93.158522 -8.37635)
			(xy 93.154506 -8.26008) (xy 42.500813 -8.26008) (xy 42.479042 -8.276857) (xy 42.381609 -8.341665)
			(xy 42.279905 -8.39954) (xy 42.174422 -8.450202) (xy 42.065671 -8.493404) (xy 41.954179 -8.528939)
			(xy 41.840485 -8.556634) (xy 41.725141 -8.576354) (xy 41.608704 -8.588005) (xy 41.491739 -8.59153)
			(xy 41.374812 -8.586912) (xy 41.258489 -8.574173) (xy 41.143334 -8.553375) (xy 41.029905 -8.524618)
			(xy 40.91875 -8.488042) (xy 40.810407 -8.443825) (xy 40.705403 -8.392179) (xy 40.604244 -8.333356)
			(xy 40.507421 -8.26764) (xy 40.415403 -8.195349) (xy 40.328636 -8.116834) (xy 40.247539 -8.032474)
			(xy 40.172506 -7.942679) (xy 40.103899 -7.847883) (xy 40.042051 -7.748544) (xy 39.987262 -7.645145)
			(xy 39.939796 -7.538186) (xy 39.899884 -7.428185) (xy 39.86772 -7.315674) (xy 39.843457 -7.201199)
			(xy 39.827215 -7.085313) (xy 39.819072 -6.968579) (xy 39.818564 -6.91007) (xy 9.522754 -6.91007)
			(xy 9.530658 -6.927058) (xy 9.577928 -7.047761) (xy 9.617601 -7.171169) (xy 9.649526 -7.296805) (xy 9.673578 -7.424182)
			(xy 9.689665 -7.552808) (xy 9.697724 -7.682186) (xy 9.698228 -7.747) (xy 9.697724 -7.811814) (xy 9.689665 -7.941192)
			(xy 9.673578 -8.069818) (xy 9.649526 -8.197195) (xy 9.617601 -8.322831) (xy 9.577928 -8.446239) (xy 9.530658 -8.566942)
			(xy 9.475977 -8.684472) (xy 9.414094 -8.798376) (xy 9.345249 -8.908212) (xy 9.26971 -9.013555) (xy 9.187767 -9.113998)
			(xy 9.099738 -9.209153) (xy 9.005964 -9.298651) (xy 8.906807 -9.382146) (xy 8.802651 -9.459315) (xy 8.693899 -9.529859)
			(xy 8.580971 -9.593506) (xy 8.464306 -9.650009) (xy 8.344353 -9.69915) (xy 8.221577 -9.740738) (xy 8.096453 -9.774613)
			(xy 7.969465 -9.800643) (xy 7.841104 -9.818728) (xy 7.711868 -9.828798) (xy 7.582255 -9.830814) (xy 7.452768 -9.824768)
			(xy 7.323907 -9.810684) (xy 7.196171 -9.788615) (xy 7.070054 -9.758648) (xy 6.946044 -9.720899) (xy 6.824621 -9.675512)
			(xy 6.706254 -9.622665) (xy 6.591402 -9.562561) (xy 6.480509 -9.495433) (xy 6.374003 -9.421541) (xy 6.272297 -9.34117)
			(xy 6.175785 -9.254632) (xy 6.08484 -9.16226) (xy 5.999813 -9.064414) (xy 5.921033 -8.961471) (xy 5.848806 -8.853829)
			(xy 5.783411 -8.741905) (xy 5.7251 -8.626132) (xy 5.6741 -8.506958) (xy 5.630608 -8.384844) (xy 5.594791 -8.260261)
			(xy 5.566789 -8.133694) (xy 5.54671 -8.00563) (xy 5.534631 -7.876566) (xy 5.5306 -7.747) (xy 1.016 -7.747)
			(xy 1.016 -12.879578) (xy 1.016492 -12.894921) (xy 1.023881 -12.924707) (xy 1.038164 -12.95187) (xy 1.048004 -12.963652)
			(xy 1.065976 -12.984695) (xy 1.09629 -13.030991) (xy 1.119599 -13.08118) (xy 1.135415 -13.13421)
			(xy 1.143407 -13.188967) (xy 1.143407 -13.244305) (xy 1.135415 -13.299062) (xy 1.119599 -13.352092)
			(xy 1.09629 -13.402281) (xy 1.065976 -13.448577) (xy 1.048004 -13.46962) (xy 1.03813 -13.481379)
			(xy 1.023835 -13.508546) (xy 1.01646 -13.538345) (xy 1.016 -13.553694) (xy 1.016 -19.177) (xy 5.5306 -19.177)
			(xy 5.534631 -19.047434) (xy 5.54671 -18.91837) (xy 5.566789 -18.790306) (xy 5.594791 -18.663739)
			(xy 5.630608 -18.539156) (xy 5.6741 -18.417042) (xy 5.7251 -18.297868) (xy 5.783411 -18.182095) (xy 5.848806 -18.070171)
			(xy 5.921033 -17.962529) (xy 5.999813 -17.859586) (xy 6.08484 -17.76174) (xy 6.175785 -17.669368)
			(xy 6.272297 -17.58283) (xy 6.374003 -17.502459) (xy 6.480509 -17.428567) (xy 6.591402 -17.361439)
			(xy 6.706254 -17.301335) (xy 6.824621 -17.248488) (xy 6.946044 -17.203101) (xy 7.070054 -17.165352)
			(xy 7.196171 -17.135385) (xy 7.323907 -17.113316) (xy 7.452768 -17.099232) (xy 7.582255 -17.093186)
			(xy 7.711868 -17.095202) (xy 7.841104 -17.105272) (xy 7.969465 -17.123357) (xy 8.096453 -17.149387)
			(xy 8.221577 -17.183262) (xy 8.344353 -17.22485) (xy 8.464306 -17.273991) (xy 8.580971 -17.330494)
			(xy 8.693899 -17.394141) (xy 8.802651 -17.464685) (xy 8.906807 -17.541854) (xy 9.005964 -17.625349)
			(xy 9.099738 -17.714847) (xy 9.187767 -17.810002) (xy 9.26971 -17.910445) (xy 9.345249 -18.015788)
			(xy 9.414094 -18.125624) (xy 9.475977 -18.239528) (xy 9.530658 -18.357058) (xy 9.577928 -18.477761)
			(xy 9.617601 -18.601169) (xy 9.649526 -18.726805) (xy 9.673578 -18.854182) (xy 9.689665 -18.982808)
			(xy 9.697724 -19.112186) (xy 9.698228 -19.177) (xy 9.697724 -19.241814) (xy 9.689665 -19.371192)
			(xy 9.673578 -19.499818) (xy 9.649526 -19.627195) (xy 9.617601 -19.752831) (xy 9.577928 -19.876239)
			(xy 9.530658 -19.996942) (xy 9.524527 -20.01012) (xy 86.877404 -20.01012) (xy 86.881424 -19.819469)
			(xy 86.893478 -19.629156) (xy 86.913544 -19.439521) (xy 86.941587 -19.2509) (xy 86.977556 -19.06363)
			(xy 87.021388 -18.878042) (xy 87.073005 -18.694467) (xy 87.132315 -18.513231) (xy 87.199213 -18.334656)
			(xy 87.273579 -18.159061) (xy 87.355281 -17.986756) (xy 87.444175 -17.818049) (xy 87.540101 -17.653239)
			(xy 87.64289 -17.49262) (xy 87.752359 -17.336477) (xy 87.868313 -17.185088) (xy 87.990547 -17.038721)
			(xy 88.118841 -16.897637) (xy 88.252969 -16.762088) (xy 88.392693 -16.632313) (xy 88.537763 -16.508543)
			(xy 88.687921 -16.391) (xy 88.842902 -16.279891) (xy 89.002429 -16.175414) (xy 89.166218 -16.077755)
			(xy 89.333978 -15.987088) (xy 89.505412 -15.903574) (xy 89.680214 -15.827361) (xy 89.858073 -15.758585)
			(xy 90.038674 -15.697367) (xy 90.221694 -15.643818) (xy 90.40681 -15.598032) (xy 90.593691 -15.56009)
			(xy 90.782006 -15.530061) (xy 90.971419 -15.507996) (xy 91.161593 -15.493937) (xy 91.352192 -15.487907)
			(xy 91.542875 -15.489917) (xy 91.733304 -15.499964) (xy 91.92314 -15.51803) (xy 92.112046 -15.544083)
			(xy 92.299685 -15.578076) (xy 92.485725 -15.619949) (xy 92.669834 -15.669628) (xy 92.851685 -15.727024)
			(xy 93.030955 -15.792035) (xy 93.207325 -15.864546) (xy 93.380481 -15.944427) (xy 93.550116 -16.031537)
			(xy 93.715928 -16.125721) (xy 93.877622 -16.226812) (xy 94.03491 -16.334628) (xy 94.187513 -16.44898)
			(xy 94.335161 -16.569663) (xy 94.477589 -16.696464) (xy 94.614545 -16.829155) (xy 94.745786 -16.967503)
			(xy 94.871078 -17.11126) (xy 94.990198 -17.260171) (xy 95.102934 -17.413972) (xy 95.209087 -17.572388)
			(xy 95.308467 -17.735139) (xy 95.400897 -17.901934) (xy 95.486214 -18.072478) (xy 95.564266 -18.246466)
			(xy 95.634913 -18.423591) (xy 95.698031 -18.603536) (xy 95.753507 -18.785982) (xy 95.801242 -18.970605)
			(xy 95.841152 -19.157075) (xy 95.873165 -19.345063) (xy 95.897225 -19.534233) (xy 95.913288 -19.724249)
			(xy 95.921327 -19.914773) (xy 95.92183 -20.01012) (xy 95.921327 -20.105467) (xy 95.913288 -20.295991)
			(xy 95.897225 -20.486007) (xy 95.873165 -20.675177) (xy 95.841152 -20.863165) (xy 95.801242 -21.049635)
			(xy 95.753507 -21.234258) (xy 95.698031 -21.416704) (xy 95.634913 -21.596649) (xy 95.564266 -21.773774)
			(xy 95.486214 -21.947762) (xy 95.400897 -22.118306) (xy 95.308467 -22.285101) (xy 95.209087 -22.447852)
			(xy 95.102934 -22.606268) (xy 94.990198 -22.760069) (xy 94.871078 -22.90898) (xy 94.745786 -23.052737)
			(xy 94.614545 -23.191085) (xy 94.477589 -23.323776) (xy 94.335161 -23.450577) (xy 94.187513 -23.57126)
			(xy 94.03491 -23.685612) (xy 93.877622 -23.793428) (xy 93.715928 -23.894519) (xy 93.550116 -23.988703)
			(xy 93.380481 -24.075813) (xy 93.207325 -24.155694) (xy 93.030955 -24.228205) (xy 92.851685 -24.293216)
			(xy 92.669834 -24.350612) (xy 92.485725 -24.400291) (xy 92.299685 -24.442164) (xy 92.112046 -24.476157)
			(xy 91.92314 -24.50221) (xy 91.733304 -24.520276) (xy 91.542875 -24.530323) (xy 91.352192 -24.532333)
			(xy 91.161593 -24.526303) (xy 90.971419 -24.512244) (xy 90.782006 -24.490179) (xy 90.593691 -24.46015)
			(xy 90.40681 -24.422208) (xy 90.221694 -24.376422) (xy 90.038674 -24.322873) (xy 89.858073 -24.261655)
			(xy 89.680214 -24.192879) (xy 89.505412 -24.116666) (xy 89.333978 -24.033152) (xy 89.166218 -23.942485)
			(xy 89.002429 -23.844826) (xy 88.842902 -23.740349) (xy 88.687921 -23.62924) (xy 88.537763 -23.511697)
			(xy 88.392693 -23.387927) (xy 88.252969 -23.258152) (xy 88.118841 -23.122603) (xy 87.990547 -22.981519)
			(xy 87.868313 -22.835152) (xy 87.752359 -22.683763) (xy 87.64289 -22.52762) (xy 87.540101 -22.367001)
			(xy 87.444175 -22.202191) (xy 87.355281 -22.033484) (xy 87.273579 -21.861179) (xy 87.199213 -21.685584)
			(xy 87.132315 -21.507009) (xy 87.073005 -21.325773) (xy 87.021388 -21.142198) (xy 86.977556 -20.95661)
			(xy 86.941587 -20.76934) (xy 86.913544 -20.580719) (xy 86.893478 -20.391084) (xy 86.881424 -20.200771)
			(xy 86.877404 -20.01012) (xy 9.524527 -20.01012) (xy 9.475977 -20.114472) (xy 9.414094 -20.228376)
			(xy 9.345249 -20.338212) (xy 9.26971 -20.443555) (xy 9.187767 -20.543998) (xy 9.099738 -20.639153)
			(xy 9.005964 -20.728651) (xy 8.906807 -20.812146) (xy 8.802651 -20.889315) (xy 8.693899 -20.959859)
			(xy 8.580971 -21.023506) (xy 8.464306 -21.080009) (xy 8.344353 -21.12915) (xy 8.221577 -21.170738)
			(xy 8.096453 -21.204613) (xy 7.969465 -21.230643) (xy 7.841104 -21.248728) (xy 7.711868 -21.258798)
			(xy 7.582255 -21.260814) (xy 7.452768 -21.254768) (xy 7.323907 -21.240684) (xy 7.196171 -21.218615)
			(xy 7.070054 -21.188648) (xy 6.946044 -21.150899) (xy 6.824621 -21.105512) (xy 6.706254 -21.052665)
			(xy 6.591402 -20.992561) (xy 6.480509 -20.925433) (xy 6.374003 -20.851541) (xy 6.272297 -20.77117)
			(xy 6.175785 -20.684632) (xy 6.08484 -20.59226) (xy 5.999813 -20.494414) (xy 5.921033 -20.391471)
			(xy 5.848806 -20.283829) (xy 5.783411 -20.171905) (xy 5.7251 -20.056132) (xy 5.6741 -19.936958) (xy 5.630608 -19.814844)
			(xy 5.594791 -19.690261) (xy 5.566789 -19.563694) (xy 5.54671 -19.43563) (xy 5.534631 -19.306566)
			(xy 5.5306 -19.177) (xy 1.016 -19.177) (xy 1.016 -25.071578) (xy 1.016492 -25.086921) (xy 1.023881 -25.116707)
			(xy 1.038164 -25.14387) (xy 1.048004 -25.155652) (xy 1.065976 -25.176695) (xy 1.09629 -25.222991)
			(xy 1.119599 -25.27318) (xy 1.135415 -25.32621) (xy 1.143407 -25.380967) (xy 1.143407 -25.436305)
			(xy 1.135415 -25.491062) (xy 1.119599 -25.544092) (xy 1.09629 -25.594281) (xy 1.065976 -25.640577)
			(xy 1.048004 -25.66162) (xy 1.03813 -25.673379) (xy 1.023835 -25.700546) (xy 1.01646 -25.730345)
			(xy 1.016 -25.745694) (xy 1.016 -25.909778) (xy 6.671831 -25.909778) (xy 6.675786 -25.817941) (xy 6.687621 -25.726784)
			(xy 6.707248 -25.636981) (xy 6.734522 -25.549199) (xy 6.769242 -25.464085) (xy 6.81115 -25.382272)
			(xy 6.859936 -25.304364) (xy 6.915239 -25.230939) (xy 6.976649 -25.162539) (xy 7.043711 -25.099672)
			(xy 7.11593 -25.042802) (xy 7.19277 -24.992351) (xy 7.273663 -24.948692) (xy 7.358009 -24.912149)
			(xy 7.445185 -24.882992) (xy 7.534544 -24.861438) (xy 7.625425 -24.847644) (xy 7.717156 -24.841714)
			(xy 7.809057 -24.843692) (xy 7.900448 -24.853563) (xy 7.990652 -24.871253) (xy 8.079001 -24.896633)
			(xy 8.164841 -24.929513) (xy 8.247537 -24.969651) (xy 8.326477 -25.01675) (xy 8.401075 -25.07046)
			(xy 8.470781 -25.130384) (xy 8.535076 -25.196078) (xy 8.593487 -25.267056) (xy 8.645579 -25.342793)
			(xy 8.690968 -25.422728) (xy 8.729318 -25.506268) (xy 8.760343 -25.592796) (xy 8.783816 -25.681671)
			(xy 8.799562 -25.772235) (xy 8.807464 -25.863817) (xy 8.807958 -25.909778) (xy 8.807464 -25.955739)
			(xy 8.799562 -26.047321) (xy 8.783816 -26.137885) (xy 8.760343 -26.22676) (xy 8.729318 -26.313288)
			(xy 8.690968 -26.396828) (xy 8.645579 -26.476763) (xy 8.593487 -26.5525) (xy 8.535076 -26.623478)
			(xy 8.470781 -26.689172) (xy 8.401075 -26.749096) (xy 8.326477 -26.802806) (xy 8.247537 -26.849905)
			(xy 8.164841 -26.890043) (xy 8.079001 -26.922923) (xy 7.990652 -26.948303) (xy 7.900448 -26.965993)
			(xy 7.809057 -26.975864) (xy 7.717156 -26.977842) (xy 7.625425 -26.971912) (xy 7.534544 -26.958118)
			(xy 7.445185 -26.936564) (xy 7.358009 -26.907407) (xy 7.273663 -26.870864) (xy 7.19277 -26.827205)
			(xy 7.11593 -26.776754) (xy 7.043711 -26.719884) (xy 6.976649 -26.657017) (xy 6.915239 -26.588617)
			(xy 6.859936 -26.515192) (xy 6.81115 -26.437284) (xy 6.769242 -26.355471) (xy 6.734522 -26.270357)
			(xy 6.707248 -26.182575) (xy 6.687621 -26.092772) (xy 6.675786 -26.001615) (xy 6.671831 -25.909778)
			(xy 1.016 -25.909778) (xy 1.016 -29.19984) (xy 11.343394 -29.19984) (xy 11.347396 -28.994751) (xy 11.359397 -28.789974)
			(xy 11.379379 -28.585822) (xy 11.40731 -28.382604) (xy 11.443149 -28.180632) (xy 11.486841 -27.980211)
			(xy 11.53832 -27.781647) (xy 11.597506 -27.585243) (xy 11.66431 -27.391298) (xy 11.73863 -27.200107)
			(xy 11.820354 -27.011962) (xy 11.909355 -26.827148) (xy 12.0055 -26.645947) (xy 12.108641 -26.468635)
			(xy 12.218622 -26.295483) (xy 12.335274 -26.126753) (xy 12.458421 -25.962704) (xy 12.587875 -25.803583)
			(xy 12.723439 -25.649635) (xy 12.864906 -25.501094) (xy 13.01206 -25.358184) (xy 13.164678 -25.221125)
			(xy 13.322528 -25.090125) (xy 13.485368 -24.965384) (xy 13.652952 -24.84709) (xy 13.825023 -24.735426)
			(xy 14.00132 -24.630559) (xy 14.181574 -24.532651) (xy 14.365511 -24.441851) (xy 14.55285 -24.358296)
			(xy 14.743307 -24.282114) (xy 14.936591 -24.213421) (xy 15.132408 -24.152321) (xy 15.33046 -24.098908)
			(xy 15.530445 -24.053262) (xy 15.732059 -24.015455) (xy 15.934994 -23.985542) (xy 16.138942 -23.963569)
			(xy 16.343591 -23.949571) (xy 16.548632 -23.943568) (xy 16.75375 -23.945569) (xy 16.958634 -23.955572)
			(xy 17.162971 -23.973561) (xy 17.366452 -23.999508) (xy 17.568765 -24.033375) (xy 17.769602 -24.075109)
			(xy 17.968659 -24.124648) (xy 18.165631 -24.181915) (xy 18.360218 -24.246824) (xy 18.552125 -24.319276)
			(xy 18.741059 -24.399159) (xy 18.926733 -24.486354) (xy 19.108863 -24.580726) (xy 19.287172 -24.682132)
			(xy 19.461389 -24.790418) (xy 19.631249 -24.905419) (xy 19.796492 -25.02696) (xy 19.956868 -25.154855)
			(xy 20.112131 -25.28891) (xy 20.262046 -25.428921) (xy 20.406384 -25.574674) (xy 20.544926 -25.725948)
			(xy 20.67746 -25.882512) (xy 20.803784 -26.044128) (xy 20.923707 -26.210549) (xy 21.037045 -26.381523)
			(xy 21.143626 -26.556788) (xy 21.243288 -26.736078) (xy 21.335879 -26.91912) (xy 21.421258 -27.105636)
			(xy 21.499294 -27.29534) (xy 21.56987 -27.487945) (xy 21.632877 -27.683157) (xy 21.68822 -27.880678)
			(xy 21.735814 -28.080208) (xy 21.775588 -28.281443) (xy 21.807479 -28.484077) (xy 21.83144 -28.687801)
			(xy 21.847435 -28.892304) (xy 21.855438 -29.097276) (xy 21.855938 -29.19984) (xy 21.855438 -29.302404)
			(xy 21.847435 -29.507376) (xy 21.83144 -29.711879) (xy 21.807479 -29.915603) (xy 21.775588 -30.118237)
			(xy 21.735814 -30.319472) (xy 21.68822 -30.519002) (xy 21.632877 -30.716523) (xy 21.56987 -30.911735)
			(xy 21.499294 -31.10434) (xy 21.421258 -31.294044) (xy 21.335879 -31.48056) (xy 21.243288 -31.663602)
			(xy 21.143626 -31.842892) (xy 21.037045 -32.018157) (xy 20.923707 -32.189131) (xy 20.844063 -32.299656)
			(xy 72.856858 -32.299656) (xy 72.860873 -32.096474) (xy 72.872912 -31.893609) (xy 72.892956 -31.691379)
			(xy 72.920974 -31.490098) (xy 72.956922 -31.290081) (xy 73.000744 -31.09164) (xy 73.052371 -30.895086)
			(xy 73.111723 -30.700725) (xy 73.178708 -30.50886) (xy 73.25322 -30.319791) (xy 73.335143 -30.133814)
			(xy 73.42435 -29.951218) (xy 73.520701 -29.772289) (xy 73.624045 -29.597307) (xy 73.734222 -29.426544)
			(xy 73.851059 -29.260266) (xy 73.974374 -29.098735) (xy 74.103974 -28.942201) (xy 74.239657 -28.79091)
			(xy 74.381212 -28.645097) (xy 74.528416 -28.50499) (xy 74.68104 -28.370808) (xy 74.838847 -28.24276)
			(xy 75.001589 -28.121047) (xy 75.169012 -28.005859) (xy 75.340855 -27.897374) (xy 75.51685 -27.795763)
			(xy 75.696722 -27.701185) (xy 75.88019 -27.613786) (xy 76.066968 -27.533704) (xy 76.256764 -27.461064)
			(xy 76.449281 -27.395978) (xy 76.644219 -27.338549) (xy 76.841274 -27.288866) (xy 77.040138 -27.247006)
			(xy 77.2405 -27.213036) (xy 77.442048 -27.187008) (xy 77.644467 -27.168963) (xy 77.84744 -27.158929)
			(xy 78.050652 -27.156921) (xy 78.253784 -27.162943) (xy 78.45652 -27.176986) (xy 78.658543 -27.199027)
			(xy 78.859537 -27.229032) (xy 79.059189 -27.266954) (xy 79.257187 -27.312734) (xy 79.453222 -27.3663)
			(xy 79.646987 -27.42757) (xy 79.838181 -27.496446) (xy 80.026504 -27.572823) (xy 80.211663 -27.656579)
			(xy 80.393369 -27.747586) (xy 80.571337 -27.845699) (xy 80.74529 -27.950768) (xy 80.914957 -28.062626)
			(xy 81.080071 -28.1811) (xy 81.240377 -28.306005) (xy 81.395623 -28.437145) (xy 81.545566 -28.574316)
			(xy 81.689974 -28.717304) (xy 81.828619 -28.865885) (xy 81.961287 -29.019828) (xy 82.087769 -29.178891)
			(xy 82.207869 -29.342828) (xy 82.321398 -29.511381) (xy 82.428179 -29.684288) (xy 82.528046 -29.861278)
			(xy 82.620843 -30.042075) (xy 82.706425 -30.226398) (xy 82.784658 -30.413957) (xy 82.85542 -30.604461)
			(xy 82.918601 -30.797612) (xy 82.974101 -30.993108) (xy 83.021835 -31.190644) (xy 83.061728 -31.389912)
			(xy 83.093717 -31.5906) (xy 83.117753 -31.792395) (xy 83.133798 -31.994982) (xy 83.141826 -32.198045)
			(xy 83.142328 -32.299656) (xy 83.141826 -32.401267) (xy 83.133798 -32.60433) (xy 83.117753 -32.806917)
			(xy 83.093717 -33.008712) (xy 83.061728 -33.2094) (xy 83.021835 -33.408668) (xy 82.974101 -33.606204)
			(xy 82.918601 -33.8017) (xy 82.85542 -33.994851) (xy 82.784658 -34.185355) (xy 82.706425 -34.372914)
			(xy 82.620843 -34.557237) (xy 82.528046 -34.738034) (xy 82.428179 -34.915024) (xy 82.321398 -35.087931)
			(xy 82.207869 -35.256484) (xy 82.087769 -35.420421) (xy 81.961287 -35.579484) (xy 81.828619 -35.733427)
			(xy 81.689974 -35.882008) (xy 81.545566 -36.024996) (xy 81.395623 -36.162167) (xy 81.240377 -36.293307)
			(xy 81.080071 -36.418212) (xy 80.914957 -36.536686) (xy 80.74529 -36.648544) (xy 80.571337 -36.753613)
			(xy 80.393369 -36.851726) (xy 80.211663 -36.942733) (xy 80.026504 -37.026489) (xy 79.838181 -37.102866)
			(xy 79.646987 -37.171742) (xy 79.453222 -37.233012) (xy 79.257187 -37.286578) (xy 79.059189 -37.332358)
			(xy 78.859537 -37.37028) (xy 78.658543 -37.400285) (xy 78.45652 -37.422326) (xy 78.253784 -37.436369)
			(xy 78.050652 -37.442391) (xy 77.84744 -37.440383) (xy 77.644467 -37.430349) (xy 77.442048 -37.412304)
			(xy 77.2405 -37.386276) (xy 77.040138 -37.352306) (xy 76.841274 -37.310446) (xy 76.644219 -37.260763)
			(xy 76.449281 -37.203334) (xy 76.256764 -37.138248) (xy 76.066968 -37.065608) (xy 75.88019 -36.985526)
			(xy 75.696722 -36.898127) (xy 75.51685 -36.803549) (xy 75.340855 -36.701938) (xy 75.169012 -36.593453)
			(xy 75.001589 -36.478265) (xy 74.838847 -36.356552) (xy 74.68104 -36.228504) (xy 74.528416 -36.094322)
			(xy 74.381212 -35.954215) (xy 74.239657 -35.808402) (xy 74.103974 -35.657111) (xy 73.974374 -35.500577)
			(xy 73.851059 -35.339046) (xy 73.734222 -35.172768) (xy 73.624045 -35.002005) (xy 73.520701 -34.827023)
			(xy 73.42435 -34.648094) (xy 73.335143 -34.465498) (xy 73.25322 -34.279521) (xy 73.178708 -34.090452)
			(xy 73.111723 -33.898587) (xy 73.052371 -33.704226) (xy 73.000744 -33.507672) (xy 72.956922 -33.309231)
			(xy 72.920974 -33.109214) (xy 72.892956 -32.907933) (xy 72.872912 -32.705703) (xy 72.860873 -32.502838)
			(xy 72.856858 -32.299656) (xy 20.844063 -32.299656) (xy 20.803784 -32.355552) (xy 20.67746 -32.517168)
			(xy 20.544926 -32.673732) (xy 20.406384 -32.825006) (xy 20.262046 -32.970759) (xy 20.112131 -33.11077)
			(xy 19.956868 -33.244825) (xy 19.796492 -33.37272) (xy 19.631249 -33.494261) (xy 19.461389 -33.609262)
			(xy 19.287172 -33.717548) (xy 19.108863 -33.818954) (xy 18.926733 -33.913326) (xy 18.741059 -34.000521)
			(xy 18.552125 -34.080404) (xy 18.360218 -34.152856) (xy 18.165631 -34.217765) (xy 17.968659 -34.275032)
			(xy 17.769602 -34.324571) (xy 17.568765 -34.366305) (xy 17.366452 -34.400172) (xy 17.162971 -34.426119)
			(xy 16.958634 -34.444108) (xy 16.75375 -34.454111) (xy 16.548632 -34.456112) (xy 16.343591 -34.450109)
			(xy 16.138942 -34.436111) (xy 15.934994 -34.414138) (xy 15.732059 -34.384225) (xy 15.530445 -34.346418)
			(xy 15.33046 -34.300772) (xy 15.132408 -34.247359) (xy 14.936591 -34.186259) (xy 14.743307 -34.117566)
			(xy 14.55285 -34.041384) (xy 14.365511 -33.957829) (xy 14.181574 -33.867029) (xy 14.00132 -33.769121)
			(xy 13.825023 -33.664254) (xy 13.652952 -33.55259) (xy 13.485368 -33.434296) (xy 13.322528 -33.309555)
			(xy 13.164678 -33.178555) (xy 13.01206 -33.041496) (xy 12.864906 -32.898586) (xy 12.723439 -32.750045)
			(xy 12.587875 -32.596097) (xy 12.458421 -32.436976) (xy 12.335274 -32.272927) (xy 12.218622 -32.104197)
			(xy 12.108641 -31.931045) (xy 12.0055 -31.753733) (xy 11.909355 -31.572532) (xy 11.820354 -31.387718)
			(xy 11.73863 -31.199573) (xy 11.66431 -31.008382) (xy 11.597506 -30.814437) (xy 11.53832 -30.618033)
			(xy 11.486841 -30.419469) (xy 11.443149 -30.219048) (xy 11.40731 -30.017076) (xy 11.379379 -29.813858)
			(xy 11.359397 -29.609706) (xy 11.347396 -29.404929) (xy 11.343394 -29.19984) (xy 1.016 -29.19984)
			(xy 1.016 -34.90976) (xy 6.671831 -34.90976) (xy 6.675786 -34.817923) (xy 6.687621 -34.726766) (xy 6.707248 -34.636963)
			(xy 6.734522 -34.549181) (xy 6.769242 -34.464067) (xy 6.81115 -34.382254) (xy 6.859936 -34.304346)
			(xy 6.915239 -34.230921) (xy 6.976649 -34.162521) (xy 7.043711 -34.099654) (xy 7.11593 -34.042784)
			(xy 7.19277 -33.992333) (xy 7.273663 -33.948674) (xy 7.358009 -33.912131) (xy 7.445185 -33.882974)
			(xy 7.534544 -33.86142) (xy 7.625425 -33.847626) (xy 7.717156 -33.841696) (xy 7.809057 -33.843674)
			(xy 7.900448 -33.853545) (xy 7.990652 -33.871235) (xy 8.079001 -33.896615) (xy 8.164841 -33.929495)
			(xy 8.247537 -33.969633) (xy 8.326477 -34.016732) (xy 8.401075 -34.070442) (xy 8.470781 -34.130366)
			(xy 8.535076 -34.19606) (xy 8.593487 -34.267038) (xy 8.645579 -34.342775) (xy 8.690968 -34.42271)
			(xy 8.729318 -34.50625) (xy 8.760343 -34.592778) (xy 8.783816 -34.681653) (xy 8.799562 -34.772217)
			(xy 8.807464 -34.863799) (xy 8.807958 -34.90976) (xy 8.807464 -34.955721) (xy 8.799562 -35.047303)
			(xy 8.783816 -35.137867) (xy 8.760343 -35.226742) (xy 8.729318 -35.31327) (xy 8.690968 -35.39681)
			(xy 8.645579 -35.476745) (xy 8.593487 -35.552482) (xy 8.535076 -35.62346) (xy 8.470781 -35.689154)
			(xy 8.401075 -35.749078) (xy 8.326477 -35.802788) (xy 8.247537 -35.849887) (xy 8.164841 -35.890025)
			(xy 8.079001 -35.922905) (xy 7.990652 -35.948285) (xy 7.900448 -35.965975) (xy 7.809057 -35.975846)
			(xy 7.717156 -35.977824) (xy 7.625425 -35.971894) (xy 7.534544 -35.9581) (xy 7.445185 -35.936546)
			(xy 7.358009 -35.907389) (xy 7.273663 -35.870846) (xy 7.19277 -35.827187) (xy 7.11593 -35.776736)
			(xy 7.043711 -35.719866) (xy 6.976649 -35.656999) (xy 6.915239 -35.588599) (xy 6.859936 -35.515174)
			(xy 6.81115 -35.437266) (xy 6.769242 -35.355453) (xy 6.734522 -35.270339) (xy 6.707248 -35.182557)
			(xy 6.687621 -35.092754) (xy 6.675786 -35.001597) (xy 6.671831 -34.90976) (xy 1.016 -34.90976) (xy 1.016 -37.771578)
			(xy 1.016492 -37.786921) (xy 1.023881 -37.816707) (xy 1.038164 -37.84387) (xy 1.048004 -37.855652)
			(xy 1.065976 -37.876695) (xy 1.09629 -37.922991) (xy 1.119599 -37.97318) (xy 1.135415 -38.02621)
			(xy 1.143407 -38.080967) (xy 1.143407 -38.136305) (xy 1.135415 -38.191062) (xy 1.119599 -38.244092)
			(xy 1.09629 -38.294281) (xy 1.065976 -38.340577) (xy 1.048004 -38.36162) (xy 1.03813 -38.373379)
			(xy 1.023835 -38.400546) (xy 1.01646 -38.430345) (xy 1.016 -38.445694) (xy 1.016 -42.291) (xy 5.5306 -42.291)
			(xy 5.534631 -42.161434) (xy 5.54671 -42.03237) (xy 5.566789 -41.904306) (xy 5.594791 -41.777739)
			(xy 5.630608 -41.653156) (xy 5.6741 -41.531042) (xy 5.7251 -41.411868) (xy 5.783411 -41.296095) (xy 5.848806 -41.184171)
			(xy 5.921033 -41.076529) (xy 5.999813 -40.973586) (xy 6.08484 -40.87574) (xy 6.175785 -40.783368)
			(xy 6.272297 -40.69683) (xy 6.374003 -40.616459) (xy 6.480509 -40.542567) (xy 6.591402 -40.475439)
			(xy 6.706254 -40.415335) (xy 6.824621 -40.362488) (xy 6.946044 -40.317101) (xy 7.070054 -40.279352)
			(xy 7.196171 -40.249385) (xy 7.323907 -40.227316) (xy 7.452768 -40.213232) (xy 7.582255 -40.207186)
			(xy 7.711868 -40.209202) (xy 7.841104 -40.219272) (xy 7.969465 -40.237357) (xy 8.096453 -40.263387)
			(xy 8.221577 -40.297262) (xy 8.344353 -40.33885) (xy 8.464306 -40.387991) (xy 8.580971 -40.444494)
			(xy 8.693899 -40.508141) (xy 8.802651 -40.578685) (xy 8.906807 -40.655854) (xy 9.005964 -40.739349)
			(xy 9.099738 -40.828847) (xy 9.187767 -40.924002) (xy 9.26971 -41.024445) (xy 9.345249 -41.129788)
			(xy 9.414094 -41.239624) (xy 9.475977 -41.353528) (xy 9.530658 -41.471058) (xy 9.577928 -41.591761)
			(xy 9.617601 -41.715169) (xy 9.649526 -41.840805) (xy 9.673578 -41.968182) (xy 9.689665 -42.096808)
			(xy 9.697724 -42.226186) (xy 9.698228 -42.291) (xy 9.697724 -42.355814) (xy 9.689665 -42.485192)
			(xy 9.673578 -42.613818) (xy 9.649526 -42.741195) (xy 9.617601 -42.866831) (xy 9.577928 -42.990239)
			(xy 9.530658 -43.110942) (xy 9.475977 -43.228472) (xy 9.414094 -43.342376) (xy 9.345249 -43.452212)
			(xy 9.26971 -43.557555) (xy 9.187767 -43.657998) (xy 9.099738 -43.753153) (xy 9.005964 -43.842651)
			(xy 8.906807 -43.926146) (xy 8.802651 -44.003315) (xy 8.693899 -44.073859) (xy 8.580971 -44.137506)
			(xy 8.464306 -44.194009) (xy 8.344353 -44.24315) (xy 8.221577 -44.284738) (xy 8.096453 -44.318613)
			(xy 7.969465 -44.344643) (xy 7.841104 -44.362728) (xy 7.711868 -44.372798) (xy 7.582255 -44.374814)
			(xy 7.452768 -44.368768) (xy 7.323907 -44.354684) (xy 7.196171 -44.332615) (xy 7.070054 -44.302648)
			(xy 6.946044 -44.264899) (xy 6.824621 -44.219512) (xy 6.706254 -44.166665) (xy 6.591402 -44.106561)
			(xy 6.480509 -44.039433) (xy 6.374003 -43.965541) (xy 6.272297 -43.88517) (xy 6.175785 -43.798632)
			(xy 6.08484 -43.70626) (xy 5.999813 -43.608414) (xy 5.921033 -43.505471) (xy 5.848806 -43.397829)
			(xy 5.783411 -43.285905) (xy 5.7251 -43.170132) (xy 5.6741 -43.050958) (xy 5.630608 -42.928844) (xy 5.594791 -42.804261)
			(xy 5.566789 -42.677694) (xy 5.54671 -42.54963) (xy 5.534631 -42.420566) (xy 5.5306 -42.291) (xy 1.016 -42.291)
			(xy 1.016 -50.471578) (xy 1.016492 -50.486921) (xy 1.023881 -50.516707) (xy 1.038164 -50.54387) (xy 1.048004 -50.555652)
			(xy 1.065976 -50.576695) (xy 1.09629 -50.622991) (xy 1.119599 -50.67318) (xy 1.135415 -50.72621)
			(xy 1.143407 -50.780967) (xy 1.143407 -50.836305) (xy 1.135415 -50.891062) (xy 1.119599 -50.944092)
			(xy 1.09629 -50.994281) (xy 1.065976 -51.040577) (xy 1.048004 -51.06162) (xy 1.03813 -51.073379)
			(xy 1.023835 -51.100546) (xy 1.01646 -51.130345) (xy 1.016 -51.145694) (xy 1.016 -51.36007) (xy 39.818564 -51.36007)
			(xy 39.819054 -51.302663) (xy 39.826889 -51.188117) (xy 39.842523 -51.074372) (xy 39.865882 -50.96196)
			(xy 39.896859 -50.851403) (xy 39.935308 -50.743218) (xy 39.98105 -50.63791) (xy 40.033872 -50.535968)
			(xy 40.093527 -50.437869) (xy 40.159738 -50.344069) (xy 40.232196 -50.255007) (xy 40.310562 -50.171096)
			(xy 40.394473 -50.09273) (xy 40.483535 -50.020272) (xy 40.577335 -49.954061) (xy 40.675434 -49.894406)
			(xy 40.777376 -49.841584) (xy 40.882684 -49.795842) (xy 40.990869 -49.757393) (xy 41.101426 -49.726416)
			(xy 41.213838 -49.703057) (xy 41.327583 -49.687423) (xy 41.442129 -49.679588) (xy 41.556943 -49.679588)
			(xy 41.671489 -49.687423) (xy 41.785234 -49.703057) (xy 41.897646 -49.726416) (xy 42.008203 -49.757393)
			(xy 42.116388 -49.795842) (xy 42.221696 -49.841584) (xy 42.323638 -49.894406) (xy 42.421737 -49.954061)
			(xy 42.515537 -50.020272) (xy 42.604599 -50.09273) (xy 42.68851 -50.171096) (xy 42.766876 -50.255007)
			(xy 42.839334 -50.344069) (xy 42.905545 -50.437869) (xy 42.9652 -50.535968) (xy 43.018022 -50.63791)
			(xy 43.063764 -50.743218) (xy 43.102213 -50.851403) (xy 43.13319 -50.96196) (xy 43.156549 -51.074372)
			(xy 43.172183 -51.188117) (xy 43.180018 -51.302663) (xy 43.180508 -51.36007) (xy 43.180381 -51.393251)
			(xy 43.177842 -51.459565) (xy 43.175428 -51.492658) (xy 43.170272 -51.550942) (xy 43.152948 -51.666671)
			(xy 43.127616 -51.780914) (xy 43.094401 -51.893119) (xy 43.053462 -52.002742) (xy 43.004999 -52.109253)
			(xy 42.949245 -52.212135) (xy 42.886471 -52.310891) (xy 42.816981 -52.405042) (xy 42.741111 -52.494132)
			(xy 42.659229 -52.577729) (xy 42.571732 -52.65543) (xy 42.500813 -52.71008) (xy 93.154506 -52.71008)
			(xy 93.158522 -52.59381) (xy 93.170549 -52.478095) (xy 93.190531 -52.363485) (xy 93.218373 -52.250526)
			(xy 93.253942 -52.139758) (xy 93.297068 -52.031707) (xy 93.347545 -51.926889) (xy 93.405134 -51.825804)
			(xy 93.46956 -51.728932) (xy 93.540515 -51.636736) (xy 93.617662 -51.549655) (xy 93.700633 -51.468104)
			(xy 93.789033 -51.392472) (xy 93.88244 -51.323118) (xy 93.980409 -51.260375) (xy 94.082473 -51.204539)
			(xy 94.188147 -51.155878) (xy 94.296926 -51.114624) (xy 94.408291 -51.080973) (xy 94.521714 -51.055085)
			(xy 94.636651 -51.037084) (xy 94.752557 -51.027055) (xy 94.868879 -51.025047) (xy 94.985062 -51.031069)
			(xy 95.100553 -51.045092) (xy 95.214801 -51.06705) (xy 95.327262 -51.096837) (xy 95.4374 -51.134312)
			(xy 95.54469 -51.179297) (xy 95.648621 -51.231576) (xy 95.748697 -51.290901) (xy 95.844443 -51.356989)
			(xy 95.9354 -51.429525) (xy 96.021136 -51.508164) (xy 96.101243 -51.59253) (xy 96.175339 -51.682222)
			(xy 96.243069 -51.776812) (xy 96.304113 -51.87585) (xy 96.358178 -51.978863) (xy 96.405008 -52.08536)
			(xy 96.444379 -52.194835) (xy 96.476103 -52.306765) (xy 96.500029 -52.420617) (xy 96.516043 -52.535849)
			(xy 96.52407 -52.651911) (xy 96.524572 -52.71008) (xy 96.52407 -52.768249) (xy 96.516043 -52.884311)
			(xy 96.500029 -52.999543) (xy 96.476103 -53.113395) (xy 96.444379 -53.225325) (xy 96.405008 -53.3348)
			(xy 96.358178 -53.441297) (xy 96.304113 -53.54431) (xy 96.243069 -53.643348) (xy 96.175339 -53.737938)
			(xy 96.101243 -53.82763) (xy 96.021136 -53.911996) (xy 95.9354 -53.990635) (xy 95.844443 -54.063171)
			(xy 95.748697 -54.129259) (xy 95.648621 -54.188584) (xy 95.54469 -54.240863) (xy 95.4374 -54.285848)
			(xy 95.327262 -54.323323) (xy 95.214801 -54.35311) (xy 95.100553 -54.375068) (xy 94.985062 -54.389091)
			(xy 94.868879 -54.395113) (xy 94.752557 -54.393105) (xy 94.636651 -54.383076) (xy 94.521714 -54.365075)
			(xy 94.408291 -54.339187) (xy 94.296926 -54.305536) (xy 94.188147 -54.264282) (xy 94.082473 -54.215621)
			(xy 93.980409 -54.159785) (xy 93.88244 -54.097042) (xy 93.789033 -54.027688) (xy 93.700633 -53.952056)
			(xy 93.617662 -53.870505) (xy 93.540515 -53.783424) (xy 93.46956 -53.691228) (xy 93.405134 -53.594356)
			(xy 93.347545 -53.493271) (xy 93.297068 -53.388453) (xy 93.253942 -53.280402) (xy 93.218373 -53.169634)
			(xy 93.190531 -53.056675) (xy 93.170549 -52.942065) (xy 93.158522 -52.82635) (xy 93.154506 -52.71008)
			(xy 42.500813 -52.71008) (xy 42.479042 -52.726857) (xy 42.381609 -52.791665) (xy 42.279905 -52.84954)
			(xy 42.174422 -52.900202) (xy 42.065671 -52.943404) (xy 41.954179 -52.978939) (xy 41.840485 -53.006634)
			(xy 41.725141 -53.026354) (xy 41.608704 -53.038005) (xy 41.491739 -53.04153) (xy 41.374812 -53.036912)
			(xy 41.258489 -53.024173) (xy 41.143334 -53.003375) (xy 41.029905 -52.974618) (xy 40.91875 -52.938042)
			(xy 40.810407 -52.893825) (xy 40.705403 -52.842179) (xy 40.604244 -52.783356) (xy 40.507421 -52.71764)
			(xy 40.415403 -52.645349) (xy 40.328636 -52.566834) (xy 40.247539 -52.482474) (xy 40.172506 -52.392679)
			(xy 40.103899 -52.297883) (xy 40.042051 -52.198544) (xy 39.987262 -52.095145) (xy 39.939796 -51.988186)
			(xy 39.899884 -51.878185) (xy 39.86772 -51.765674) (xy 39.843457 -51.651199) (xy 39.827215 -51.535313)
			(xy 39.819072 -51.418579) (xy 39.818564 -51.36007) (xy 1.016 -51.36007) (xy 1.016 -53.721) (xy 5.5306 -53.721)
			(xy 5.534631 -53.591434) (xy 5.54671 -53.46237) (xy 5.566789 -53.334306) (xy 5.594791 -53.207739)
			(xy 5.630608 -53.083156) (xy 5.6741 -52.961042) (xy 5.7251 -52.841868) (xy 5.783411 -52.726095) (xy 5.848806 -52.614171)
			(xy 5.921033 -52.506529) (xy 5.999813 -52.403586) (xy 6.08484 -52.30574) (xy 6.175785 -52.213368)
			(xy 6.272297 -52.12683) (xy 6.374003 -52.046459) (xy 6.480509 -51.972567) (xy 6.591402 -51.905439)
			(xy 6.706254 -51.845335) (xy 6.824621 -51.792488) (xy 6.946044 -51.747101) (xy 7.070054 -51.709352)
			(xy 7.196171 -51.679385) (xy 7.323907 -51.657316) (xy 7.452768 -51.643232) (xy 7.582255 -51.637186)
			(xy 7.711868 -51.639202) (xy 7.841104 -51.649272) (xy 7.969465 -51.667357) (xy 8.096453 -51.693387)
			(xy 8.221577 -51.727262) (xy 8.344353 -51.76885) (xy 8.464306 -51.817991) (xy 8.580971 -51.874494)
			(xy 8.693899 -51.938141) (xy 8.802651 -52.008685) (xy 8.906807 -52.085854) (xy 9.005964 -52.169349)
			(xy 9.099738 -52.258847) (xy 9.187767 -52.354002) (xy 9.26971 -52.454445) (xy 9.345249 -52.559788)
			(xy 9.414094 -52.669624) (xy 9.475977 -52.783528) (xy 9.530658 -52.901058) (xy 9.577928 -53.021761)
			(xy 9.617601 -53.145169) (xy 9.649526 -53.270805) (xy 9.673578 -53.398182) (xy 9.689665 -53.526808)
			(xy 9.697724 -53.656186) (xy 9.698228 -53.721) (xy 9.697724 -53.785814) (xy 9.689665 -53.915192)
			(xy 9.673578 -54.043818) (xy 9.649526 -54.171195) (xy 9.617601 -54.296831) (xy 9.577928 -54.420239)
			(xy 9.530658 -54.540942) (xy 9.475977 -54.658472) (xy 9.414094 -54.772376) (xy 9.345249 -54.882212)
			(xy 9.26971 -54.987555) (xy 9.187767 -55.087998) (xy 9.099738 -55.183153) (xy 9.005964 -55.272651)
			(xy 8.906807 -55.356146) (xy 8.802651 -55.433315) (xy 8.693899 -55.503859) (xy 8.580971 -55.567506)
			(xy 8.464306 -55.624009) (xy 8.344353 -55.67315) (xy 8.221577 -55.714738) (xy 8.096453 -55.748613)
			(xy 7.969465 -55.774643) (xy 7.841104 -55.792728) (xy 7.711868 -55.802798) (xy 7.582255 -55.804814)
			(xy 7.452768 -55.798768) (xy 7.323907 -55.784684) (xy 7.196171 -55.762615) (xy 7.070054 -55.732648)
			(xy 6.946044 -55.694899) (xy 6.824621 -55.649512) (xy 6.706254 -55.596665) (xy 6.591402 -55.536561)
			(xy 6.480509 -55.469433) (xy 6.374003 -55.395541) (xy 6.272297 -55.31517) (xy 6.175785 -55.228632)
			(xy 6.08484 -55.13626) (xy 5.999813 -55.038414) (xy 5.921033 -54.935471) (xy 5.848806 -54.827829)
			(xy 5.783411 -54.715905) (xy 5.7251 -54.600132) (xy 5.6741 -54.480958) (xy 5.630608 -54.358844) (xy 5.594791 -54.234261)
			(xy 5.566789 -54.107694) (xy 5.54671 -53.97963) (xy 5.534631 -53.850566) (xy 5.5306 -53.721) (xy 1.016 -53.721)
			(xy 1.016 -60.833) (xy 5.5306 -60.833) (xy 5.534631 -60.703434) (xy 5.54671 -60.57437) (xy 5.566789 -60.446306)
			(xy 5.594791 -60.319739) (xy 5.630608 -60.195156) (xy 5.6741 -60.073042) (xy 5.7251 -59.953868) (xy 5.783411 -59.838095)
			(xy 5.848806 -59.726171) (xy 5.921033 -59.618529) (xy 5.999813 -59.515586) (xy 6.08484 -59.41774)
			(xy 6.175785 -59.325368) (xy 6.272297 -59.23883) (xy 6.374003 -59.158459) (xy 6.480509 -59.084567)
			(xy 6.591402 -59.017439) (xy 6.706254 -58.957335) (xy 6.824621 -58.904488) (xy 6.946044 -58.859101)
			(xy 7.070054 -58.821352) (xy 7.196171 -58.791385) (xy 7.323907 -58.769316) (xy 7.452768 -58.755232)
			(xy 7.582255 -58.749186) (xy 7.711868 -58.751202) (xy 7.841104 -58.761272) (xy 7.969465 -58.779357)
			(xy 8.096453 -58.805387) (xy 8.221577 -58.839262) (xy 8.344353 -58.88085) (xy 8.464306 -58.929991)
			(xy 8.580971 -58.986494) (xy 8.693899 -59.050141) (xy 8.802651 -59.120685) (xy 8.906807 -59.197854)
			(xy 9.005964 -59.281349) (xy 9.099738 -59.370847) (xy 9.187767 -59.466002) (xy 9.26971 -59.566445)
			(xy 9.345249 -59.671788) (xy 9.414094 -59.781624) (xy 9.475977 -59.895528) (xy 9.530658 -60.013058)
			(xy 9.577928 -60.133761) (xy 9.617601 -60.257169) (xy 9.649526 -60.382805) (xy 9.673578 -60.510182)
			(xy 9.689665 -60.638808) (xy 9.697724 -60.768186) (xy 9.698228 -60.833) (xy 9.697724 -60.897814)
			(xy 9.689665 -61.027192) (xy 9.673578 -61.155818) (xy 9.649526 -61.283195) (xy 9.617601 -61.408831)
			(xy 9.577928 -61.532239) (xy 9.530658 -61.652942) (xy 9.475977 -61.770472) (xy 9.414094 -61.884376)
			(xy 9.345249 -61.994212) (xy 9.26971 -62.099555) (xy 9.187767 -62.199998) (xy 9.099738 -62.295153)
			(xy 9.005964 -62.384651) (xy 8.906807 -62.468146) (xy 8.802651 -62.545315) (xy 8.693899 -62.615859)
			(xy 8.580971 -62.679506) (xy 8.464306 -62.736009) (xy 8.344353 -62.78515) (xy 8.221577 -62.826738)
			(xy 8.096453 -62.860613) (xy 7.969465 -62.886643) (xy 7.841104 -62.904728) (xy 7.711868 -62.914798)
			(xy 7.582255 -62.916814) (xy 7.452768 -62.910768) (xy 7.323907 -62.896684) (xy 7.196171 -62.874615)
			(xy 7.070054 -62.844648) (xy 6.946044 -62.806899) (xy 6.824621 -62.761512) (xy 6.706254 -62.708665)
			(xy 6.591402 -62.648561) (xy 6.480509 -62.581433) (xy 6.374003 -62.507541) (xy 6.272297 -62.42717)
			(xy 6.175785 -62.340632) (xy 6.08484 -62.24826) (xy 5.999813 -62.150414) (xy 5.921033 -62.047471)
			(xy 5.848806 -61.939829) (xy 5.783411 -61.827905) (xy 5.7251 -61.712132) (xy 5.6741 -61.592958) (xy 5.630608 -61.470844)
			(xy 5.594791 -61.346261) (xy 5.566789 -61.219694) (xy 5.54671 -61.09163) (xy 5.534631 -60.962566)
			(xy 5.5306 -60.833) (xy 1.016 -60.833) (xy 1.016 -63.171578) (xy 1.016492 -63.186921) (xy 1.023881 -63.216707)
			(xy 1.038164 -63.24387) (xy 1.048004 -63.255652) (xy 1.065976 -63.276695) (xy 1.09629 -63.322991)
			(xy 1.119599 -63.37318) (xy 1.135415 -63.42621) (xy 1.143407 -63.480967) (xy 1.143407 -63.536305)
			(xy 1.135415 -63.591062) (xy 1.119599 -63.644092) (xy 1.09629 -63.694281) (xy 1.065976 -63.740577)
			(xy 1.048004 -63.76162) (xy 1.03813 -63.773379) (xy 1.023835 -63.800546) (xy 1.01646 -63.830345)
			(xy 1.016 -63.845694) (xy 1.016 -64.46012) (xy 86.877404 -64.46012) (xy 86.881424 -64.269469) (xy 86.893478 -64.079156)
			(xy 86.913544 -63.889521) (xy 86.941587 -63.7009) (xy 86.977556 -63.51363) (xy 87.021388 -63.328042)
			(xy 87.073005 -63.144467) (xy 87.132315 -62.963231) (xy 87.199213 -62.784656) (xy 87.273579 -62.609061)
			(xy 87.355281 -62.436756) (xy 87.444175 -62.268049) (xy 87.540101 -62.103239) (xy 87.64289 -61.94262)
			(xy 87.752359 -61.786477) (xy 87.868313 -61.635088) (xy 87.990547 -61.488721) (xy 88.118841 -61.347637)
			(xy 88.252969 -61.212088) (xy 88.392693 -61.082313) (xy 88.537763 -60.958543) (xy 88.687921 -60.841)
			(xy 88.842902 -60.729891) (xy 89.002429 -60.625414) (xy 89.166218 -60.527755) (xy 89.333978 -60.437088)
			(xy 89.505412 -60.353574) (xy 89.680214 -60.277361) (xy 89.858073 -60.208585) (xy 90.038674 -60.147367)
			(xy 90.221694 -60.093818) (xy 90.40681 -60.048032) (xy 90.593691 -60.01009) (xy 90.782006 -59.980061)
			(xy 90.971419 -59.957996) (xy 91.161593 -59.943937) (xy 91.352192 -59.937907) (xy 91.542875 -59.939917)
			(xy 91.733304 -59.949964) (xy 91.92314 -59.96803) (xy 92.112046 -59.994083) (xy 92.299685 -60.028076)
			(xy 92.485725 -60.069949) (xy 92.669834 -60.119628) (xy 92.851685 -60.177024) (xy 93.030955 -60.242035)
			(xy 93.207325 -60.314546) (xy 93.380481 -60.394427) (xy 93.550116 -60.481537) (xy 93.715928 -60.575721)
			(xy 93.877622 -60.676812) (xy 94.03491 -60.784628) (xy 94.187513 -60.89898) (xy 94.335161 -61.019663)
			(xy 94.477589 -61.146464) (xy 94.614545 -61.279155) (xy 94.745786 -61.417503) (xy 94.871078 -61.56126)
			(xy 94.990198 -61.710171) (xy 95.102934 -61.863972) (xy 95.209087 -62.022388) (xy 95.308467 -62.185139)
			(xy 95.400897 -62.351934) (xy 95.486214 -62.522478) (xy 95.564266 -62.696466) (xy 95.634913 -62.873591)
			(xy 95.698031 -63.053536) (xy 95.753507 -63.235982) (xy 95.801242 -63.420605) (xy 95.841152 -63.607075)
			(xy 95.873165 -63.795063) (xy 95.897225 -63.984233) (xy 95.913288 -64.174249) (xy 95.921327 -64.364773)
			(xy 95.92183 -64.46012) (xy 95.921327 -64.555467) (xy 95.913288 -64.745991) (xy 95.897225 -64.936007)
			(xy 95.873165 -65.125177) (xy 95.841152 -65.313165) (xy 95.801242 -65.499635) (xy 95.753507 -65.684258)
			(xy 95.698031 -65.866704) (xy 95.634913 -66.046649) (xy 95.564266 -66.223774) (xy 95.486214 -66.397762)
			(xy 95.400897 -66.568306) (xy 95.308467 -66.735101) (xy 95.209087 -66.897852) (xy 95.102934 -67.056268)
			(xy 94.990198 -67.210069) (xy 94.871078 -67.35898) (xy 94.745786 -67.502737) (xy 94.614545 -67.641085)
			(xy 94.477589 -67.773776) (xy 94.335161 -67.900577) (xy 94.187513 -68.02126) (xy 94.03491 -68.135612)
			(xy 93.877622 -68.243428) (xy 93.715928 -68.344519) (xy 93.550116 -68.438703) (xy 93.380481 -68.525813)
			(xy 93.207325 -68.605694) (xy 93.030955 -68.678205) (xy 92.851685 -68.743216) (xy 92.669834 -68.800612)
			(xy 92.485725 -68.850291) (xy 92.299685 -68.892164) (xy 92.112046 -68.926157) (xy 91.92314 -68.95221)
			(xy 91.733304 -68.970276) (xy 91.542875 -68.980323) (xy 91.352192 -68.982333) (xy 91.161593 -68.976303)
			(xy 90.971419 -68.962244) (xy 90.782006 -68.940179) (xy 90.593691 -68.91015) (xy 90.40681 -68.872208)
			(xy 90.221694 -68.826422) (xy 90.038674 -68.772873) (xy 89.858073 -68.711655) (xy 89.680214 -68.642879)
			(xy 89.505412 -68.566666) (xy 89.333978 -68.483152) (xy 89.166218 -68.392485) (xy 89.002429 -68.294826)
			(xy 88.842902 -68.190349) (xy 88.687921 -68.07924) (xy 88.537763 -67.961697) (xy 88.392693 -67.837927)
			(xy 88.252969 -67.708152) (xy 88.118841 -67.572603) (xy 87.990547 -67.431519) (xy 87.868313 -67.285152)
			(xy 87.752359 -67.133763) (xy 87.64289 -66.97762) (xy 87.540101 -66.817001) (xy 87.444175 -66.652191)
			(xy 87.355281 -66.483484) (xy 87.273579 -66.311179) (xy 87.199213 -66.135584) (xy 87.132315 -65.957009)
			(xy 87.073005 -65.775773) (xy 87.021388 -65.592198) (xy 86.977556 -65.40661) (xy 86.941587 -65.21934)
			(xy 86.913544 -65.030719) (xy 86.893478 -64.841084) (xy 86.881424 -64.650771) (xy 86.877404 -64.46012)
			(xy 1.016 -64.46012) (xy 1.016 -72.263) (xy 5.5306 -72.263) (xy 5.534631 -72.133434) (xy 5.54671 -72.00437)
			(xy 5.566789 -71.876306) (xy 5.594791 -71.749739) (xy 5.630608 -71.625156) (xy 5.6741 -71.503042)
			(xy 5.7251 -71.383868) (xy 5.783411 -71.268095) (xy 5.848806 -71.156171) (xy 5.921033 -71.048529)
			(xy 5.999813 -70.945586) (xy 6.08484 -70.84774) (xy 6.175785 -70.755368) (xy 6.272297 -70.66883)
			(xy 6.374003 -70.588459) (xy 6.480509 -70.514567) (xy 6.591402 -70.447439) (xy 6.706254 -70.387335)
			(xy 6.824621 -70.334488) (xy 6.946044 -70.289101) (xy 7.070054 -70.251352) (xy 7.196171 -70.221385)
			(xy 7.323907 -70.199316) (xy 7.452768 -70.185232) (xy 7.582255 -70.179186) (xy 7.711868 -70.181202)
			(xy 7.841104 -70.191272) (xy 7.969465 -70.209357) (xy 8.096453 -70.235387) (xy 8.221577 -70.269262)
			(xy 8.344353 -70.31085) (xy 8.464306 -70.359991) (xy 8.580971 -70.416494) (xy 8.693899 -70.480141)
			(xy 8.802651 -70.550685) (xy 8.906807 -70.627854) (xy 9.005964 -70.711349) (xy 9.099738 -70.800847)
			(xy 9.187767 -70.896002) (xy 9.26971 -70.996445) (xy 9.345249 -71.101788) (xy 9.414094 -71.211624)
			(xy 9.475977 -71.325528) (xy 9.530658 -71.443058) (xy 9.577928 -71.563761) (xy 9.617601 -71.687169)
			(xy 9.649526 -71.812805) (xy 9.673578 -71.940182) (xy 9.689665 -72.068808) (xy 9.697724 -72.198186)
			(xy 9.698228 -72.263) (xy 9.697724 -72.327814) (xy 9.689665 -72.457192) (xy 9.673578 -72.585818)
			(xy 9.649526 -72.713195) (xy 9.617601 -72.838831) (xy 9.577928 -72.962239) (xy 9.530658 -73.082942)
			(xy 9.475977 -73.200472) (xy 9.414094 -73.314376) (xy 9.345249 -73.424212) (xy 9.26971 -73.529555)
			(xy 9.187767 -73.629998) (xy 9.099738 -73.725153) (xy 9.005964 -73.814651) (xy 8.906807 -73.898146)
			(xy 8.802651 -73.975315) (xy 8.693899 -74.045859) (xy 8.580971 -74.109506) (xy 8.464306 -74.166009)
			(xy 8.344353 -74.21515) (xy 8.221577 -74.256738) (xy 8.096453 -74.290613) (xy 7.969465 -74.316643)
			(xy 7.841104 -74.334728) (xy 7.711868 -74.344798) (xy 7.582255 -74.346814) (xy 7.452768 -74.340768)
			(xy 7.323907 -74.326684) (xy 7.196171 -74.304615) (xy 7.070054 -74.274648) (xy 6.946044 -74.236899)
			(xy 6.824621 -74.191512) (xy 6.706254 -74.138665) (xy 6.591402 -74.078561) (xy 6.480509 -74.011433)
			(xy 6.374003 -73.937541) (xy 6.272297 -73.85717) (xy 6.175785 -73.770632) (xy 6.08484 -73.67826)
			(xy 5.999813 -73.580414) (xy 5.921033 -73.477471) (xy 5.848806 -73.369829) (xy 5.783411 -73.257905)
			(xy 5.7251 -73.142132) (xy 5.6741 -73.022958) (xy 5.630608 -72.900844) (xy 5.594791 -72.776261) (xy 5.566789 -72.649694)
			(xy 5.54671 -72.52163) (xy 5.534631 -72.392566) (xy 5.5306 -72.263) (xy 1.016 -72.263) (xy 1.016 -75.871578)
			(xy 1.016492 -75.886921) (xy 1.023881 -75.916707) (xy 1.038164 -75.94387) (xy 1.048004 -75.955652)
			(xy 1.065976 -75.976695) (xy 1.09629 -76.022991) (xy 1.119599 -76.07318) (xy 1.135415 -76.12621)
			(xy 1.143407 -76.180967) (xy 1.143407 -76.236305) (xy 1.135415 -76.291062) (xy 1.119599 -76.344092)
			(xy 1.09629 -76.394281) (xy 1.065976 -76.440577) (xy 1.048004 -76.46162) (xy 1.03813 -76.473379)
			(xy 1.023835 -76.500546) (xy 1.01646 -76.530345) (xy 1.016 -76.545694) (xy 1.016 -77.476858) (xy 6.601727 -77.476858)
			(xy 6.605682 -77.385021) (xy 6.617517 -77.293864) (xy 6.637144 -77.204061) (xy 6.664418 -77.116279)
			(xy 6.699138 -77.031165) (xy 6.741046 -76.949352) (xy 6.789832 -76.871444) (xy 6.845135 -76.798019)
			(xy 6.906545 -76.729619) (xy 6.973607 -76.666752) (xy 7.045826 -76.609882) (xy 7.122666 -76.559431)
			(xy 7.203559 -76.515772) (xy 7.287905 -76.479229) (xy 7.375081 -76.450072) (xy 7.46444 -76.428518)
			(xy 7.555321 -76.414724) (xy 7.647052 -76.408794) (xy 7.738953 -76.410772) (xy 7.830344 -76.420643)
			(xy 7.920548 -76.438333) (xy 8.008897 -76.463713) (xy 8.094737 -76.496593) (xy 8.177433 -76.536731)
			(xy 8.256373 -76.58383) (xy 8.330971 -76.63754) (xy 8.400677 -76.697464) (xy 8.464972 -76.763158)
			(xy 8.523383 -76.834136) (xy 8.575475 -76.909873) (xy 8.620864 -76.989808) (xy 8.659214 -77.073348)
			(xy 8.690239 -77.159876) (xy 8.713712 -77.248751) (xy 8.729458 -77.339315) (xy 8.73736 -77.430897)
			(xy 8.737854 -77.476858) (xy 8.73736 -77.522819) (xy 8.729458 -77.614401) (xy 8.713712 -77.704965)
			(xy 8.690239 -77.79384) (xy 8.659214 -77.880368) (xy 8.620864 -77.963908) (xy 8.575475 -78.043843)
			(xy 8.523383 -78.11958) (xy 8.464972 -78.190558) (xy 8.400677 -78.256252) (xy 8.330971 -78.316176)
			(xy 8.256373 -78.369886) (xy 8.241646 -78.378673) (xy 74.888081 -78.378673) (xy 74.888081 -78.220963)
			(xy 74.896069 -78.063456) (xy 74.912025 -77.906556) (xy 74.935906 -77.750665) (xy 74.967653 -77.596184)
			(xy 75.007183 -77.443509) (xy 75.054395 -77.293033) (xy 75.109169 -77.14514) (xy 75.171362 -77.000212)
			(xy 75.240817 -76.85862) (xy 75.317353 -76.720727) (xy 75.400776 -76.586888) (xy 75.49087 -76.457446)
			(xy 75.587405 -76.332733) (xy 75.690133 -76.21307) (xy 75.798789 -76.098763) (xy 75.913096 -75.990107)
			(xy 76.032759 -75.887379) (xy 76.157472 -75.790844) (xy 76.286914 -75.70075) (xy 76.420753 -75.617327)
			(xy 76.558646 -75.540791) (xy 76.700238 -75.471336) (xy 76.845166 -75.409143) (xy 76.993059 -75.354369)
			(xy 77.143535 -75.307157) (xy 77.29621 -75.267627) (xy 77.450691 -75.23588) (xy 77.606582 -75.211999)
			(xy 77.763482 -75.196043) (xy 77.920989 -75.188055) (xy 78.078699 -75.188055) (xy 78.236206 -75.196043)
			(xy 78.393106 -75.211999) (xy 78.548997 -75.23588) (xy 78.703478 -75.267627) (xy 78.856153 -75.307157)
			(xy 79.006629 -75.354369) (xy 79.154522 -75.409143) (xy 79.29945 -75.471336) (xy 79.441042 -75.540791)
			(xy 79.578935 -75.617327) (xy 79.712774 -75.70075) (xy 79.842216 -75.790844) (xy 79.966929 -75.887379)
			(xy 80.086592 -75.990107) (xy 80.200899 -76.098763) (xy 80.309555 -76.21307) (xy 80.412283 -76.332733)
			(xy 80.508818 -76.457446) (xy 80.598912 -76.586888) (xy 80.682335 -76.720727) (xy 80.758871 -76.85862)
			(xy 80.828326 -77.000212) (xy 80.890519 -77.14514) (xy 80.945293 -77.293033) (xy 80.992505 -77.443509)
			(xy 81.032035 -77.596184) (xy 81.063782 -77.750665) (xy 81.087663 -77.906556) (xy 81.103619 -78.063456)
			(xy 81.111607 -78.220963) (xy 81.112106 -78.299818) (xy 81.111607 -78.378673) (xy 81.103619 -78.53618)
			(xy 81.087663 -78.69308) (xy 81.063782 -78.848971) (xy 81.032035 -79.003452) (xy 80.992505 -79.156127)
			(xy 80.945293 -79.306603) (xy 80.890519 -79.454496) (xy 80.828326 -79.599424) (xy 80.758871 -79.741016)
			(xy 80.682335 -79.878909) (xy 80.598912 -80.012748) (xy 80.508818 -80.14219) (xy 80.412283 -80.266903)
			(xy 80.309555 -80.386566) (xy 80.200899 -80.500873) (xy 80.086592 -80.609529) (xy 79.966929 -80.712257)
			(xy 79.842216 -80.808792) (xy 79.712774 -80.898886) (xy 79.578935 -80.982309) (xy 79.441042 -81.058845)
			(xy 79.29945 -81.1283) (xy 79.154522 -81.190493) (xy 79.006629 -81.245267) (xy 78.856153 -81.292479)
			(xy 78.703478 -81.332009) (xy 78.548997 -81.363756) (xy 78.393106 -81.387637) (xy 78.236206 -81.403593)
			(xy 78.078699 -81.411581) (xy 77.920989 -81.411581) (xy 77.763482 -81.403593) (xy 77.606582 -81.387637)
			(xy 77.450691 -81.363756) (xy 77.29621 -81.332009) (xy 77.143535 -81.292479) (xy 76.993059 -81.245267)
			(xy 76.845166 -81.190493) (xy 76.700238 -81.1283) (xy 76.558646 -81.058845) (xy 76.420753 -80.982309)
			(xy 76.286914 -80.898886) (xy 76.157472 -80.808792) (xy 76.032759 -80.712257) (xy 75.913096 -80.609529)
			(xy 75.798789 -80.500873) (xy 75.690133 -80.386566) (xy 75.587405 -80.266903) (xy 75.49087 -80.14219)
			(xy 75.400776 -80.012748) (xy 75.317353 -79.878909) (xy 75.240817 -79.741016) (xy 75.171362 -79.599424)
			(xy 75.109169 -79.454496) (xy 75.054395 -79.306603) (xy 75.007183 -79.156127) (xy 74.967653 -79.003452)
			(xy 74.935906 -78.848971) (xy 74.912025 -78.69308) (xy 74.896069 -78.53618) (xy 74.888081 -78.378673)
			(xy 8.241646 -78.378673) (xy 8.177433 -78.416985) (xy 8.094737 -78.457123) (xy 8.008897 -78.490003)
			(xy 7.920548 -78.515383) (xy 7.830344 -78.533073) (xy 7.738953 -78.542944) (xy 7.647052 -78.544922)
			(xy 7.555321 -78.538992) (xy 7.46444 -78.525198) (xy 7.375081 -78.503644) (xy 7.287905 -78.474487)
			(xy 7.203559 -78.437944) (xy 7.122666 -78.394285) (xy 7.045826 -78.343834) (xy 6.973607 -78.286964)
			(xy 6.906545 -78.224097) (xy 6.845135 -78.155697) (xy 6.789832 -78.082272) (xy 6.741046 -78.004364)
			(xy 6.699138 -77.922551) (xy 6.664418 -77.837437) (xy 6.637144 -77.749655) (xy 6.617517 -77.659852)
			(xy 6.605682 -77.568695) (xy 6.601727 -77.476858) (xy 1.016 -77.476858) (xy 1.016 -88.571578) (xy 1.016492 -88.586921)
			(xy 1.023881 -88.616707) (xy 1.038164 -88.64387) (xy 1.048004 -88.655652) (xy 1.065976 -88.676695)
			(xy 1.09629 -88.722991) (xy 1.119599 -88.77318) (xy 1.135415 -88.82621) (xy 1.143407 -88.880967)
			(xy 1.143407 -88.936305) (xy 1.135415 -88.991062) (xy 1.119599 -89.044092) (xy 1.09629 -89.094281)
			(xy 1.065976 -89.140577) (xy 1.048004 -89.16162) (xy 1.03813 -89.173379) (xy 1.023835 -89.200546)
			(xy 1.01646 -89.230345) (xy 1.016 -89.245694) (xy 1.016 -89.476834) (xy 6.601727 -89.476834) (xy 6.605682 -89.384997)
			(xy 6.617517 -89.29384) (xy 6.637144 -89.204037) (xy 6.664418 -89.116255) (xy 6.699138 -89.031141)
			(xy 6.741046 -88.949328) (xy 6.789832 -88.87142) (xy 6.845135 -88.797995) (xy 6.906545 -88.729595)
			(xy 6.973607 -88.666728) (xy 7.045826 -88.609858) (xy 7.122666 -88.559407) (xy 7.203559 -88.515748)
			(xy 7.287905 -88.479205) (xy 7.375081 -88.450048) (xy 7.46444 -88.428494) (xy 7.555321 -88.4147)
			(xy 7.647052 -88.40877) (xy 7.738953 -88.410748) (xy 7.830344 -88.420619) (xy 7.920548 -88.438309)
			(xy 8.008897 -88.463689) (xy 8.094737 -88.496569) (xy 8.177433 -88.536707) (xy 8.256373 -88.583806)
			(xy 8.330971 -88.637516) (xy 8.400677 -88.69744) (xy 8.464972 -88.763134) (xy 8.523383 -88.834112)
			(xy 8.575475 -88.909849) (xy 8.620864 -88.989784) (xy 8.659214 -89.073324) (xy 8.690239 -89.159852)
			(xy 8.713712 -89.248727) (xy 8.729458 -89.339291) (xy 8.73736 -89.430873) (xy 8.737854 -89.476834)
			(xy 8.73736 -89.522795) (xy 8.729458 -89.614377) (xy 8.713712 -89.704941) (xy 8.690239 -89.793816)
			(xy 8.659214 -89.880344) (xy 8.620864 -89.963884) (xy 8.575475 -90.043819) (xy 8.523383 -90.119556)
			(xy 8.464972 -90.190534) (xy 8.400677 -90.256228) (xy 8.330971 -90.316152) (xy 8.256373 -90.369862)
			(xy 8.177433 -90.416961) (xy 8.094737 -90.457099) (xy 8.008897 -90.489979) (xy 7.920548 -90.515359)
			(xy 7.830344 -90.533049) (xy 7.738953 -90.54292) (xy 7.647052 -90.544898) (xy 7.555321 -90.538968)
			(xy 7.46444 -90.525174) (xy 7.375081 -90.50362) (xy 7.287905 -90.474463) (xy 7.203559 -90.43792)
			(xy 7.122666 -90.394261) (xy 7.045826 -90.34381) (xy 6.973607 -90.28694) (xy 6.906545 -90.224073)
			(xy 6.845135 -90.155673) (xy 6.789832 -90.082248) (xy 6.741046 -90.00434) (xy 6.699138 -89.922527)
			(xy 6.664418 -89.837413) (xy 6.637144 -89.749631) (xy 6.617517 -89.659828) (xy 6.605682 -89.568671)
			(xy 6.601727 -89.476834) (xy 1.016 -89.476834) (xy 1.016 -95.377) (xy 5.5306 -95.377) (xy 5.534631 -95.247434)
			(xy 5.54671 -95.11837) (xy 5.566789 -94.990306) (xy 5.594791 -94.863739) (xy 5.630608 -94.739156)
			(xy 5.6741 -94.617042) (xy 5.7251 -94.497868) (xy 5.783411 -94.382095) (xy 5.848806 -94.270171) (xy 5.921033 -94.162529)
			(xy 5.999813 -94.059586) (xy 6.08484 -93.96174) (xy 6.175785 -93.869368) (xy 6.272297 -93.78283)
			(xy 6.374003 -93.702459) (xy 6.480509 -93.628567) (xy 6.591402 -93.561439) (xy 6.706254 -93.501335)
			(xy 6.824621 -93.448488) (xy 6.946044 -93.403101) (xy 7.070054 -93.365352) (xy 7.196171 -93.335385)
			(xy 7.323907 -93.313316) (xy 7.452768 -93.299232) (xy 7.582255 -93.293186) (xy 7.711868 -93.295202)
			(xy 7.841104 -93.305272) (xy 7.969465 -93.323357) (xy 8.096453 -93.349387) (xy 8.221577 -93.383262)
			(xy 8.344353 -93.42485) (xy 8.464306 -93.473991) (xy 8.580971 -93.530494) (xy 8.693899 -93.594141)
			(xy 8.802651 -93.664685) (xy 8.906807 -93.741854) (xy 9.005964 -93.825349) (xy 9.099738 -93.914847)
			(xy 9.187767 -94.010002) (xy 9.26971 -94.110445) (xy 9.345249 -94.215788) (xy 9.414094 -94.325624)
			(xy 9.475977 -94.439528) (xy 9.530658 -94.557058) (xy 9.577928 -94.677761) (xy 9.617601 -94.801169)
			(xy 9.649526 -94.926805) (xy 9.673578 -95.054182) (xy 9.689665 -95.182808) (xy 9.697724 -95.312186)
			(xy 9.698228 -95.377) (xy 9.697724 -95.441814) (xy 9.689665 -95.571192) (xy 9.673578 -95.699818)
			(xy 9.65276 -95.81007) (xy 39.818564 -95.81007) (xy 39.819054 -95.752663) (xy 39.826889 -95.638117)
			(xy 39.842523 -95.524372) (xy 39.865882 -95.41196) (xy 39.896859 -95.301403) (xy 39.935308 -95.193218)
			(xy 39.98105 -95.08791) (xy 40.033872 -94.985968) (xy 40.093527 -94.887869) (xy 40.159738 -94.794069)
			(xy 40.232196 -94.705007) (xy 40.310562 -94.621096) (xy 40.394473 -94.54273) (xy 40.483535 -94.470272)
			(xy 40.577335 -94.404061) (xy 40.675434 -94.344406) (xy 40.777376 -94.291584) (xy 40.882684 -94.245842)
			(xy 40.990869 -94.207393) (xy 41.101426 -94.176416) (xy 41.213838 -94.153057) (xy 41.327583 -94.137423)
			(xy 41.442129 -94.129588) (xy 41.556943 -94.129588) (xy 41.671489 -94.137423) (xy 41.785234 -94.153057)
			(xy 41.897646 -94.176416) (xy 42.008203 -94.207393) (xy 42.116388 -94.245842) (xy 42.221696 -94.291584)
			(xy 42.323638 -94.344406) (xy 42.421737 -94.404061) (xy 42.515537 -94.470272) (xy 42.604599 -94.54273)
			(xy 42.68851 -94.621096) (xy 42.766876 -94.705007) (xy 42.839334 -94.794069) (xy 42.905545 -94.887869)
			(xy 42.9652 -94.985968) (xy 43.018022 -95.08791) (xy 43.063764 -95.193218) (xy 43.102213 -95.301403)
			(xy 43.13319 -95.41196) (xy 43.156549 -95.524372) (xy 43.172183 -95.638117) (xy 43.180018 -95.752663)
			(xy 43.180508 -95.81007) (xy 43.180381 -95.843251) (xy 43.177842 -95.909565) (xy 43.175428 -95.942658)
			(xy 43.170272 -96.000942) (xy 43.152948 -96.116671) (xy 43.127616 -96.230914) (xy 43.094401 -96.343119)
			(xy 43.053462 -96.452742) (xy 43.004999 -96.559253) (xy 42.949245 -96.662135) (xy 42.886471 -96.760891)
			(xy 42.816981 -96.855042) (xy 42.741111 -96.944132) (xy 42.659229 -97.027729) (xy 42.571732 -97.10543)
			(xy 42.500813 -97.16008) (xy 93.154506 -97.16008) (xy 93.158522 -97.04381) (xy 93.170549 -96.928095)
			(xy 93.190531 -96.813485) (xy 93.218373 -96.700526) (xy 93.253942 -96.589758) (xy 93.297068 -96.481707)
			(xy 93.347545 -96.376889) (xy 93.405134 -96.275804) (xy 93.46956 -96.178932) (xy 93.540515 -96.086736)
			(xy 93.617662 -95.999655) (xy 93.700633 -95.918104) (xy 93.789033 -95.842472) (xy 93.88244 -95.773118)
			(xy 93.980409 -95.710375) (xy 94.082473 -95.654539) (xy 94.188147 -95.605878) (xy 94.296926 -95.564624)
			(xy 94.408291 -95.530973) (xy 94.521714 -95.505085) (xy 94.636651 -95.487084) (xy 94.752557 -95.477055)
			(xy 94.868879 -95.475047) (xy 94.985062 -95.481069) (xy 95.100553 -95.495092) (xy 95.214801 -95.51705)
			(xy 95.327262 -95.546837) (xy 95.4374 -95.584312) (xy 95.54469 -95.629297) (xy 95.648621 -95.681576)
			(xy 95.748697 -95.740901) (xy 95.844443 -95.806989) (xy 95.9354 -95.879525) (xy 96.021136 -95.958164)
			(xy 96.101243 -96.04253) (xy 96.175339 -96.132222) (xy 96.243069 -96.226812) (xy 96.304113 -96.32585)
			(xy 96.358178 -96.428863) (xy 96.405008 -96.53536) (xy 96.444379 -96.644835) (xy 96.476103 -96.756765)
			(xy 96.500029 -96.870617) (xy 96.516043 -96.985849) (xy 96.52407 -97.101911) (xy 96.524572 -97.16008)
			(xy 96.52407 -97.218249) (xy 96.516043 -97.334311) (xy 96.500029 -97.449543) (xy 96.476103 -97.563395)
			(xy 96.444379 -97.675325) (xy 96.405008 -97.7848) (xy 96.358178 -97.891297) (xy 96.304113 -97.99431)
			(xy 96.243069 -98.093348) (xy 96.175339 -98.187938) (xy 96.101243 -98.27763) (xy 96.021136 -98.361996)
			(xy 95.9354 -98.440635) (xy 95.844443 -98.513171) (xy 95.748697 -98.579259) (xy 95.648621 -98.638584)
			(xy 95.54469 -98.690863) (xy 95.4374 -98.735848) (xy 95.327262 -98.773323) (xy 95.214801 -98.80311)
			(xy 95.100553 -98.825068) (xy 94.985062 -98.839091) (xy 94.868879 -98.845113) (xy 94.752557 -98.843105)
			(xy 94.636651 -98.833076) (xy 94.521714 -98.815075) (xy 94.408291 -98.789187) (xy 94.296926 -98.755536)
			(xy 94.188147 -98.714282) (xy 94.082473 -98.665621) (xy 93.980409 -98.609785) (xy 93.88244 -98.547042)
			(xy 93.789033 -98.477688) (xy 93.700633 -98.402056) (xy 93.617662 -98.320505) (xy 93.540515 -98.233424)
			(xy 93.46956 -98.141228) (xy 93.405134 -98.044356) (xy 93.347545 -97.943271) (xy 93.297068 -97.838453)
			(xy 93.253942 -97.730402) (xy 93.218373 -97.619634) (xy 93.190531 -97.506675) (xy 93.170549 -97.392065)
			(xy 93.158522 -97.27635) (xy 93.154506 -97.16008) (xy 42.500813 -97.16008) (xy 42.479042 -97.176857)
			(xy 42.381609 -97.241665) (xy 42.279905 -97.29954) (xy 42.174422 -97.350202) (xy 42.065671 -97.393404)
			(xy 41.954179 -97.428939) (xy 41.840485 -97.456634) (xy 41.725141 -97.476354) (xy 41.608704 -97.488005)
			(xy 41.491739 -97.49153) (xy 41.374812 -97.486912) (xy 41.258489 -97.474173) (xy 41.143334 -97.453375)
			(xy 41.029905 -97.424618) (xy 40.91875 -97.388042) (xy 40.810407 -97.343825) (xy 40.705403 -97.292179)
			(xy 40.604244 -97.233356) (xy 40.507421 -97.16764) (xy 40.415403 -97.095349) (xy 40.328636 -97.016834)
			(xy 40.247539 -96.932474) (xy 40.172506 -96.842679) (xy 40.103899 -96.747883) (xy 40.042051 -96.648544)
			(xy 39.987262 -96.545145) (xy 39.939796 -96.438186) (xy 39.899884 -96.328185) (xy 39.86772 -96.215674)
			(xy 39.843457 -96.101199) (xy 39.827215 -95.985313) (xy 39.819072 -95.868579) (xy 39.818564 -95.81007)
			(xy 9.65276 -95.81007) (xy 9.649526 -95.827195) (xy 9.617601 -95.952831) (xy 9.577928 -96.076239)
			(xy 9.530658 -96.196942) (xy 9.475977 -96.314472) (xy 9.414094 -96.428376) (xy 9.345249 -96.538212)
			(xy 9.26971 -96.643555) (xy 9.187767 -96.743998) (xy 9.099738 -96.839153) (xy 9.005964 -96.928651)
			(xy 8.906807 -97.012146) (xy 8.802651 -97.089315) (xy 8.693899 -97.159859) (xy 8.580971 -97.223506)
			(xy 8.464306 -97.280009) (xy 8.344353 -97.32915) (xy 8.221577 -97.370738) (xy 8.096453 -97.404613)
			(xy 7.969465 -97.430643) (xy 7.841104 -97.448728) (xy 7.711868 -97.458798) (xy 7.582255 -97.460814)
			(xy 7.452768 -97.454768) (xy 7.323907 -97.440684) (xy 7.196171 -97.418615) (xy 7.070054 -97.388648)
			(xy 6.946044 -97.350899) (xy 6.824621 -97.305512) (xy 6.706254 -97.252665) (xy 6.591402 -97.192561)
			(xy 6.480509 -97.125433) (xy 6.374003 -97.051541) (xy 6.272297 -96.97117) (xy 6.175785 -96.884632)
			(xy 6.08484 -96.79226) (xy 5.999813 -96.694414) (xy 5.921033 -96.591471) (xy 5.848806 -96.483829)
			(xy 5.783411 -96.371905) (xy 5.7251 -96.256132) (xy 5.6741 -96.136958) (xy 5.630608 -96.014844) (xy 5.594791 -95.890261)
			(xy 5.566789 -95.763694) (xy 5.54671 -95.63563) (xy 5.534631 -95.506566) (xy 5.5306 -95.377) (xy 1.016 -95.377)
			(xy 1.016 -101.271578) (xy 1.016492 -101.286921) (xy 1.023881 -101.316707) (xy 1.038164 -101.34387)
			(xy 1.048004 -101.355652) (xy 1.065976 -101.376695) (xy 1.09629 -101.422991) (xy 1.119599 -101.47318)
			(xy 1.135415 -101.52621) (xy 1.143407 -101.580967) (xy 1.143407 -101.636305) (xy 1.135415 -101.691062)
			(xy 1.119599 -101.744092) (xy 1.09629 -101.794281) (xy 1.065976 -101.840577) (xy 1.048004 -101.86162)
			(xy 1.03813 -101.873379) (xy 1.023835 -101.900546) (xy 1.01646 -101.930345) (xy 1.016 -101.945694)
			(xy 1.016 -106.807) (xy 5.5306 -106.807) (xy 5.534631 -106.677434) (xy 5.54671 -106.54837) (xy 5.566789 -106.420306)
			(xy 5.594791 -106.293739) (xy 5.630608 -106.169156) (xy 5.6741 -106.047042) (xy 5.7251 -105.927868)
			(xy 5.783411 -105.812095) (xy 5.848806 -105.700171) (xy 5.921033 -105.592529) (xy 5.999813 -105.489586)
			(xy 6.08484 -105.39174) (xy 6.175785 -105.299368) (xy 6.272297 -105.21283) (xy 6.374003 -105.132459)
			(xy 6.480509 -105.058567) (xy 6.591402 -104.991439) (xy 6.706254 -104.931335) (xy 6.824621 -104.878488)
			(xy 6.946044 -104.833101) (xy 7.070054 -104.795352) (xy 7.196171 -104.765385) (xy 7.323907 -104.743316)
			(xy 7.452768 -104.729232) (xy 7.582255 -104.723186) (xy 7.711868 -104.725202) (xy 7.841104 -104.735272)
			(xy 7.969465 -104.753357) (xy 8.096453 -104.779387) (xy 8.221577 -104.813262) (xy 8.344353 -104.85485)
			(xy 8.464306 -104.903991) (xy 8.580971 -104.960494) (xy 8.693899 -105.024141) (xy 8.802651 -105.094685)
			(xy 8.906807 -105.171854) (xy 9.005964 -105.255349) (xy 9.099738 -105.344847) (xy 9.187767 -105.440002)
			(xy 9.26971 -105.540445) (xy 9.345249 -105.645788) (xy 9.414094 -105.755624) (xy 9.475977 -105.869528)
			(xy 9.530658 -105.987058) (xy 9.577928 -106.107761) (xy 9.617601 -106.231169) (xy 9.649526 -106.356805)
			(xy 9.673578 -106.484182) (xy 9.689665 -106.612808) (xy 9.697724 -106.742186) (xy 9.698228 -106.807)
			(xy 9.697724 -106.871814) (xy 9.689665 -107.001192) (xy 9.673578 -107.129818) (xy 9.649526 -107.257195)
			(xy 9.617601 -107.382831) (xy 9.577928 -107.506239) (xy 9.530658 -107.626942) (xy 9.475977 -107.744472)
			(xy 9.414094 -107.858376) (xy 9.345249 -107.968212) (xy 9.26971 -108.073555) (xy 9.187767 -108.173998)
			(xy 9.099738 -108.269153) (xy 9.005964 -108.358651) (xy 8.906807 -108.442146) (xy 8.802651 -108.519315)
			(xy 8.693899 -108.589859) (xy 8.580971 -108.653506) (xy 8.464306 -108.710009) (xy 8.344353 -108.75915)
			(xy 8.221577 -108.800738) (xy 8.096453 -108.834613) (xy 7.969465 -108.860643) (xy 7.841104 -108.878728)
			(xy 7.711868 -108.888798) (xy 7.582255 -108.890814) (xy 7.452768 -108.884768) (xy 7.323907 -108.870684)
			(xy 7.196171 -108.848615) (xy 7.070054 -108.818648) (xy 6.946044 -108.780899) (xy 6.824621 -108.735512)
			(xy 6.706254 -108.682665) (xy 6.591402 -108.622561) (xy 6.480509 -108.555433) (xy 6.374003 -108.481541)
			(xy 6.272297 -108.40117) (xy 6.175785 -108.314632) (xy 6.08484 -108.22226) (xy 5.999813 -108.124414)
			(xy 5.921033 -108.021471) (xy 5.848806 -107.913829) (xy 5.783411 -107.801905) (xy 5.7251 -107.686132)
			(xy 5.6741 -107.566958) (xy 5.630608 -107.444844) (xy 5.594791 -107.320261) (xy 5.566789 -107.193694)
			(xy 5.54671 -107.06563) (xy 5.534631 -106.936566) (xy 5.5306 -106.807) (xy 1.016 -106.807) (xy 1.016 -108.909866)
			(xy 86.877404 -108.909866) (xy 86.881424 -108.719215) (xy 86.893478 -108.528902) (xy 86.913544 -108.339267)
			(xy 86.941587 -108.150646) (xy 86.977556 -107.963376) (xy 87.021388 -107.777788) (xy 87.073005 -107.594213)
			(xy 87.132315 -107.412977) (xy 87.199213 -107.234402) (xy 87.273579 -107.058807) (xy 87.355281 -106.886502)
			(xy 87.444175 -106.717795) (xy 87.540101 -106.552985) (xy 87.64289 -106.392366) (xy 87.752359 -106.236223)
			(xy 87.868313 -106.084834) (xy 87.990547 -105.938467) (xy 88.118841 -105.797383) (xy 88.252969 -105.661834)
			(xy 88.392693 -105.532059) (xy 88.537763 -105.408289) (xy 88.687921 -105.290746) (xy 88.842902 -105.179637)
			(xy 89.002429 -105.07516) (xy 89.166218 -104.977501) (xy 89.333978 -104.886834) (xy 89.505412 -104.80332)
			(xy 89.680214 -104.727107) (xy 89.858073 -104.658331) (xy 90.038674 -104.597113) (xy 90.221694 -104.543564)
			(xy 90.40681 -104.497778) (xy 90.593691 -104.459836) (xy 90.782006 -104.429807) (xy 90.971419 -104.407742)
			(xy 91.161593 -104.393683) (xy 91.352192 -104.387653) (xy 91.542875 -104.389663) (xy 91.733304 -104.39971)
			(xy 91.92314 -104.417776) (xy 92.112046 -104.443829) (xy 92.299685 -104.477822) (xy 92.485725 -104.519695)
			(xy 92.669834 -104.569374) (xy 92.851685 -104.62677) (xy 93.030955 -104.691781) (xy 93.207325 -104.764292)
			(xy 93.380481 -104.844173) (xy 93.550116 -104.931283) (xy 93.715928 -105.025467) (xy 93.877622 -105.126558)
			(xy 94.03491 -105.234374) (xy 94.187513 -105.348726) (xy 94.335161 -105.469409) (xy 94.477589 -105.59621)
			(xy 94.614545 -105.728901) (xy 94.745786 -105.867249) (xy 94.871078 -106.011006) (xy 94.990198 -106.159917)
			(xy 95.102934 -106.313718) (xy 95.209087 -106.472134) (xy 95.308467 -106.634885) (xy 95.400897 -106.80168)
			(xy 95.486214 -106.972224) (xy 95.564266 -107.146212) (xy 95.634913 -107.323337) (xy 95.698031 -107.503282)
			(xy 95.753507 -107.685728) (xy 95.801242 -107.870351) (xy 95.841152 -108.056821) (xy 95.873165 -108.244809)
			(xy 95.897225 -108.433979) (xy 95.913288 -108.623995) (xy 95.921327 -108.814519) (xy 95.92183 -108.909866)
			(xy 95.921327 -109.005213) (xy 95.913288 -109.195737) (xy 95.897225 -109.385753) (xy 95.873165 -109.574923)
			(xy 95.841152 -109.762911) (xy 95.801242 -109.949381) (xy 95.753507 -110.134004) (xy 95.698031 -110.31645)
			(xy 95.634913 -110.496395) (xy 95.564266 -110.67352) (xy 95.486214 -110.847508) (xy 95.400897 -111.018052)
			(xy 95.308467 -111.184847) (xy 95.209087 -111.347598) (xy 95.102934 -111.506014) (xy 94.990198 -111.659815)
			(xy 94.871078 -111.808726) (xy 94.745786 -111.952483) (xy 94.614545 -112.090831) (xy 94.477589 -112.223522)
			(xy 94.335161 -112.350323) (xy 94.187513 -112.471006) (xy 94.03491 -112.585358) (xy 93.877622 -112.693174)
			(xy 93.715928 -112.794265) (xy 93.550116 -112.888449) (xy 93.380481 -112.975559) (xy 93.207325 -113.05544)
			(xy 93.030955 -113.127951) (xy 92.851685 -113.192962) (xy 92.669834 -113.250358) (xy 92.485725 -113.300037)
			(xy 92.299685 -113.34191) (xy 92.112046 -113.375903) (xy 91.92314 -113.401956) (xy 91.733304 -113.420022)
			(xy 91.542875 -113.430069) (xy 91.352192 -113.432079) (xy 91.161593 -113.426049) (xy 90.971419 -113.41199)
			(xy 90.782006 -113.389925) (xy 90.593691 -113.359896) (xy 90.40681 -113.321954) (xy 90.221694 -113.276168)
			(xy 90.038674 -113.222619) (xy 89.858073 -113.161401) (xy 89.680214 -113.092625) (xy 89.505412 -113.016412)
			(xy 89.333978 -112.932898) (xy 89.166218 -112.842231) (xy 89.002429 -112.744572) (xy 88.842902 -112.640095)
			(xy 88.687921 -112.528986) (xy 88.537763 -112.411443) (xy 88.392693 -112.287673) (xy 88.252969 -112.157898)
			(xy 88.118841 -112.022349) (xy 87.990547 -111.881265) (xy 87.868313 -111.734898) (xy 87.752359 -111.583509)
			(xy 87.64289 -111.427366) (xy 87.540101 -111.266747) (xy 87.444175 -111.101937) (xy 87.355281 -110.93323)
			(xy 87.273579 -110.760925) (xy 87.199213 -110.58533) (xy 87.132315 -110.406755) (xy 87.073005 -110.225519)
			(xy 87.021388 -110.041944) (xy 86.977556 -109.856356) (xy 86.941587 -109.669086) (xy 86.913544 -109.480465)
			(xy 86.893478 -109.29083) (xy 86.881424 -109.100517) (xy 86.877404 -108.909866) (xy 1.016 -108.909866)
			(xy 1.016 -113.971578) (xy 1.016492 -113.986921) (xy 1.023881 -114.016707) (xy 1.038164 -114.04387)
			(xy 1.048004 -114.055652) (xy 1.065976 -114.076695) (xy 1.09629 -114.122991) (xy 1.119599 -114.17318)
			(xy 1.135415 -114.22621) (xy 1.143407 -114.280967) (xy 1.143407 -114.336305) (xy 1.135415 -114.391062)
			(xy 1.119599 -114.444092) (xy 1.09629 -114.494281) (xy 1.065976 -114.540577) (xy 1.048004 -114.56162)
			(xy 1.03813 -114.573379) (xy 1.023835 -114.600546) (xy 1.01646 -114.630345) (xy 1.016 -114.645694)
			(xy 1.016 -118.09984) (xy 11.34441 -118.09984) (xy 11.348411 -117.894791) (xy 11.36041 -117.690054)
			(xy 11.380388 -117.485941) (xy 11.408314 -117.282762) (xy 11.444146 -117.080829) (xy 11.48783 -116.880446)
			(xy 11.539298 -116.681921) (xy 11.598473 -116.485555) (xy 11.665264 -116.291648) (xy 11.73957 -116.100494)
			(xy 11.821277 -115.912384) (xy 11.910262 -115.727606) (xy 12.006388 -115.54644) (xy 12.109509 -115.369163)
			(xy 12.219469 -115.196044) (xy 12.336099 -115.027347) (xy 12.459222 -114.863329) (xy 12.588651 -114.70424)
			(xy 12.724188 -114.550322) (xy 12.865627 -114.401808) (xy 13.012754 -114.258927) (xy 13.165342 -114.121894)
			(xy 13.323161 -113.99092) (xy 13.48597 -113.866202) (xy 13.653521 -113.747932) (xy 13.825559 -113.636288)
			(xy 14.001822 -113.531442) (xy 14.182041 -113.433553) (xy 14.365942 -113.34277) (xy 14.553246 -113.259232)
			(xy 14.743666 -113.183064) (xy 14.936912 -113.114384) (xy 15.132692 -113.053296) (xy 15.330705 -112.999894)
			(xy 15.530652 -112.954257) (xy 15.732226 -112.916457) (xy 15.935122 -112.886549) (xy 16.139031 -112.864581)
			(xy 16.343641 -112.850586) (xy 16.548641 -112.844584) (xy 16.75372 -112.846585) (xy 16.958564 -112.856585)
			(xy 17.162863 -112.874571) (xy 17.366304 -112.900513) (xy 17.568577 -112.934374) (xy 17.769376 -112.9761)
			(xy 17.968394 -113.025629) (xy 18.165328 -113.082885) (xy 18.359878 -113.147782) (xy 18.551748 -113.220219)
			(xy 18.740645 -113.300087) (xy 18.926283 -113.387265) (xy 19.108378 -113.481619) (xy 19.286653 -113.583006)
			(xy 19.460836 -113.691271) (xy 19.630663 -113.806249) (xy 19.795875 -113.927767) (xy 19.956219 -114.055637)
			(xy 20.111453 -114.189666) (xy 20.261339 -114.32965) (xy 20.405649 -114.475375) (xy 20.544163 -114.62662)
			(xy 20.676672 -114.783153) (xy 20.802972 -114.944738) (xy 20.922871 -115.111127) (xy 21.036188 -115.282067)
			(xy 21.142748 -115.457299) (xy 21.242391 -115.636554) (xy 21.334964 -115.819561) (xy 21.420326 -116.00604)
			(xy 21.498347 -116.195708) (xy 21.56891 -116.388276) (xy 21.631905 -116.58345) (xy 21.687237 -116.780933)
			(xy 21.734822 -116.980424) (xy 21.774587 -117.181621) (xy 21.806472 -117.384215) (xy 21.830429 -117.5879)
			(xy 21.84642 -117.792364) (xy 21.854422 -117.997296) (xy 21.854922 -118.09984) (xy 21.854422 -118.202384)
			(xy 21.84642 -118.407316) (xy 21.830429 -118.61178) (xy 21.806472 -118.815465) (xy 21.774587 -119.018059)
			(xy 21.734822 -119.219256) (xy 21.687237 -119.418747) (xy 21.631905 -119.61623) (xy 21.56891 -119.811404)
			(xy 21.498347 -120.003972) (xy 21.420326 -120.19364) (xy 21.334964 -120.380119) (xy 21.242391 -120.563126)
			(xy 21.142748 -120.742381) (xy 21.036188 -120.917613) (xy 20.922871 -121.088553) (xy 20.842811 -121.199656)
			(xy 72.857366 -121.199656) (xy 72.861381 -120.996474) (xy 72.87342 -120.793609) (xy 72.893464 -120.591379)
			(xy 72.921482 -120.390098) (xy 72.95743 -120.190081) (xy 73.001252 -119.99164) (xy 73.052879 -119.795086)
			(xy 73.112231 -119.600725) (xy 73.179216 -119.40886) (xy 73.253728 -119.219791) (xy 73.335651 -119.033814)
			(xy 73.424858 -118.851218) (xy 73.521209 -118.672289) (xy 73.624553 -118.497307) (xy 73.73473 -118.326544)
			(xy 73.851567 -118.160266) (xy 73.974882 -117.998735) (xy 74.104482 -117.842201) (xy 74.240165 -117.69091)
			(xy 74.38172 -117.545097) (xy 74.528924 -117.40499) (xy 74.681548 -117.270808) (xy 74.839355 -117.14276)
			(xy 75.002097 -117.021047) (xy 75.16952 -116.905859) (xy 75.341363 -116.797374) (xy 75.517358 -116.695763)
			(xy 75.69723 -116.601185) (xy 75.880698 -116.513786) (xy 76.067476 -116.433704) (xy 76.257272 -116.361064)
			(xy 76.449789 -116.295978) (xy 76.644727 -116.238549) (xy 76.841782 -116.188866) (xy 77.040646 -116.147006)
			(xy 77.241008 -116.113036) (xy 77.442556 -116.087008) (xy 77.644975 -116.068963) (xy 77.847948 -116.058929)
			(xy 78.05116 -116.056921) (xy 78.254292 -116.062943) (xy 78.457028 -116.076986) (xy 78.659051 -116.099027)
			(xy 78.860045 -116.129032) (xy 79.059697 -116.166954) (xy 79.257695 -116.212734) (xy 79.45373 -116.2663)
			(xy 79.647495 -116.32757) (xy 79.838689 -116.396446) (xy 80.027012 -116.472823) (xy 80.212171 -116.556579)
			(xy 80.393877 -116.647586) (xy 80.571845 -116.745699) (xy 80.745798 -116.850768) (xy 80.915465 -116.962626)
			(xy 81.080579 -117.0811) (xy 81.240885 -117.206005) (xy 81.396131 -117.337145) (xy 81.546074 -117.474316)
			(xy 81.690482 -117.617304) (xy 81.829127 -117.765885) (xy 81.961795 -117.919828) (xy 82.088277 -118.078891)
			(xy 82.208377 -118.242828) (xy 82.321906 -118.411381) (xy 82.428687 -118.584288) (xy 82.528554 -118.761278)
			(xy 82.621351 -118.942075) (xy 82.706933 -119.126398) (xy 82.785166 -119.313957) (xy 82.855928 -119.504461)
			(xy 82.919109 -119.697612) (xy 82.974609 -119.893108) (xy 83.022343 -120.090644) (xy 83.062236 -120.289912)
			(xy 83.094225 -120.4906) (xy 83.118261 -120.692395) (xy 83.134306 -120.894982) (xy 83.142334 -121.098045)
			(xy 83.142836 -121.199656) (xy 83.142334 -121.301267) (xy 83.134306 -121.50433) (xy 83.118261 -121.706917)
			(xy 83.094225 -121.908712) (xy 83.062236 -122.1094) (xy 83.022343 -122.308668) (xy 82.974609 -122.506204)
			(xy 82.919109 -122.7017) (xy 82.855928 -122.894851) (xy 82.785166 -123.085355) (xy 82.706933 -123.272914)
			(xy 82.621351 -123.457237) (xy 82.528554 -123.638034) (xy 82.428687 -123.815024) (xy 82.321906 -123.987931)
			(xy 82.208377 -124.156484) (xy 82.088277 -124.320421) (xy 81.961795 -124.479484) (xy 81.829127 -124.633427)
			(xy 81.690482 -124.782008) (xy 81.546074 -124.924996) (xy 81.396131 -125.062167) (xy 81.240885 -125.193307)
			(xy 81.080579 -125.318212) (xy 80.915465 -125.436686) (xy 80.745798 -125.548544) (xy 80.571845 -125.653613)
			(xy 80.393877 -125.751726) (xy 80.212171 -125.842733) (xy 80.027012 -125.926489) (xy 79.838689 -126.002866)
			(xy 79.647495 -126.071742) (xy 79.45373 -126.133012) (xy 79.257695 -126.186578) (xy 79.059697 -126.232358)
			(xy 78.860045 -126.27028) (xy 78.659051 -126.300285) (xy 78.457028 -126.322326) (xy 78.254292 -126.336369)
			(xy 78.05116 -126.342391) (xy 77.847948 -126.340383) (xy 77.644975 -126.330349) (xy 77.442556 -126.312304)
			(xy 77.241008 -126.286276) (xy 77.040646 -126.252306) (xy 76.841782 -126.210446) (xy 76.644727 -126.160763)
			(xy 76.449789 -126.103334) (xy 76.257272 -126.038248) (xy 76.067476 -125.965608) (xy 75.880698 -125.885526)
			(xy 75.69723 -125.798127) (xy 75.517358 -125.703549) (xy 75.341363 -125.601938) (xy 75.16952 -125.493453)
			(xy 75.002097 -125.378265) (xy 74.839355 -125.256552) (xy 74.681548 -125.128504) (xy 74.528924 -124.994322)
			(xy 74.38172 -124.854215) (xy 74.240165 -124.708402) (xy 74.104482 -124.557111) (xy 73.974882 -124.400577)
			(xy 73.851567 -124.239046) (xy 73.73473 -124.072768) (xy 73.624553 -123.902005) (xy 73.521209 -123.727023)
			(xy 73.424858 -123.548094) (xy 73.335651 -123.365498) (xy 73.253728 -123.179521) (xy 73.179216 -122.990452)
			(xy 73.112231 -122.798587) (xy 73.052879 -122.604226) (xy 73.001252 -122.407672) (xy 72.95743 -122.209231)
			(xy 72.921482 -122.009214) (xy 72.893464 -121.807933) (xy 72.87342 -121.605703) (xy 72.861381 -121.402838)
			(xy 72.857366 -121.199656) (xy 20.842811 -121.199656) (xy 20.802972 -121.254942) (xy 20.676672 -121.416527)
			(xy 20.544163 -121.57306) (xy 20.405649 -121.724305) (xy 20.261339 -121.87003) (xy 20.111453 -122.010014)
			(xy 19.956219 -122.144043) (xy 19.795875 -122.271913) (xy 19.630663 -122.393431) (xy 19.460836 -122.508409)
			(xy 19.286653 -122.616674) (xy 19.108378 -122.718061) (xy 18.926283 -122.812415) (xy 18.740645 -122.899593)
			(xy 18.551748 -122.979461) (xy 18.359878 -123.051898) (xy 18.165328 -123.116795) (xy 17.968394 -123.174051)
			(xy 17.769376 -123.22358) (xy 17.568577 -123.265306) (xy 17.366304 -123.299167) (xy 17.162863 -123.325109)
			(xy 16.958564 -123.343095) (xy 16.75372 -123.353095) (xy 16.548641 -123.355096) (xy 16.343641 -123.349094)
			(xy 16.139031 -123.335099) (xy 15.935122 -123.313131) (xy 15.732226 -123.283223) (xy 15.530652 -123.245423)
			(xy 15.330705 -123.199786) (xy 15.132692 -123.146384) (xy 14.936912 -123.085296) (xy 14.743666 -123.016616)
			(xy 14.553246 -122.940448) (xy 14.365942 -122.85691) (xy 14.182041 -122.766127) (xy 14.001822 -122.668238)
			(xy 13.825559 -122.563392) (xy 13.653521 -122.451748) (xy 13.48597 -122.333478) (xy 13.323161 -122.20876)
			(xy 13.165342 -122.077786) (xy 13.012754 -121.940753) (xy 12.865627 -121.797872) (xy 12.724188 -121.649358)
			(xy 12.588651 -121.49544) (xy 12.459222 -121.336351) (xy 12.336099 -121.172333) (xy 12.219469 -121.003636)
			(xy 12.109509 -120.830517) (xy 12.006388 -120.65324) (xy 11.910262 -120.472074) (xy 11.821277 -120.287296)
			(xy 11.73957 -120.099186) (xy 11.665264 -119.908032) (xy 11.598473 -119.714125) (xy 11.539298 -119.517759)
			(xy 11.48783 -119.319234) (xy 11.444146 -119.118851) (xy 11.408314 -118.916918) (xy 11.380388 -118.713739)
			(xy 11.36041 -118.509626) (xy 11.348411 -118.304889) (xy 11.34441 -118.09984) (xy 1.016 -118.09984)
			(xy 1.016 -126.671578) (xy 1.016492 -126.686921) (xy 1.023881 -126.716707) (xy 1.038164 -126.74387)
			(xy 1.048004 -126.755652) (xy 1.065976 -126.776695) (xy 1.09629 -126.822991) (xy 1.119599 -126.87318)
			(xy 1.135415 -126.92621) (xy 1.143407 -126.980967) (xy 1.143407 -127.036305) (xy 1.135415 -127.091062)
			(xy 1.119599 -127.144092) (xy 1.09629 -127.194281) (xy 1.065976 -127.240577) (xy 1.048004 -127.26162)
			(xy 1.03813 -127.273379) (xy 1.023835 -127.300546) (xy 1.01646 -127.330345) (xy 1.016 -127.345694)
			(xy 1.016 -130.746068) (xy 5.677649 -130.746068) (xy 5.677649 -130.619932) (xy 5.685569 -130.494044)
			(xy 5.701379 -130.368902) (xy 5.725014 -130.244999) (xy 5.756383 -130.122826) (xy 5.795361 -130.002863)
			(xy 5.841795 -129.885584) (xy 5.895502 -129.771452) (xy 5.956269 -129.660917) (xy 6.023856 -129.554417)
			(xy 6.097997 -129.45237) (xy 6.1784 -129.35518) (xy 6.264746 -129.26323) (xy 6.356696 -129.176884)
			(xy 6.453886 -129.096481) (xy 6.555933 -129.02234) (xy 6.662433 -128.954753) (xy 6.772968 -128.893986)
			(xy 6.8871 -128.840279) (xy 7.004379 -128.793845) (xy 7.124342 -128.754867) (xy 7.246515 -128.723498)
			(xy 7.370418 -128.699863) (xy 7.49556 -128.684053) (xy 7.621448 -128.676133) (xy 7.747584 -128.676133)
			(xy 7.873472 -128.684053) (xy 7.998614 -128.699863) (xy 8.122517 -128.723498) (xy 8.24469 -128.754867)
			(xy 8.364653 -128.793845) (xy 8.481932 -128.840279) (xy 8.596064 -128.893986) (xy 8.706599 -128.954753)
			(xy 8.813099 -129.02234) (xy 8.915146 -129.096481) (xy 9.012336 -129.176884) (xy 9.104286 -129.26323)
			(xy 9.190632 -129.35518) (xy 9.271035 -129.45237) (xy 9.345176 -129.554417) (xy 9.412763 -129.660917)
			(xy 9.47353 -129.771452) (xy 9.527237 -129.885584) (xy 9.573671 -130.002863) (xy 9.612649 -130.122826)
			(xy 9.644018 -130.244999) (xy 9.667653 -130.368902) (xy 9.683463 -130.494044) (xy 9.691383 -130.619932)
			(xy 9.691878 -130.683) (xy 9.691383 -130.746068) (xy 9.683463 -130.871956) (xy 9.667653 -130.997098)
			(xy 9.644018 -131.121001) (xy 9.612649 -131.243174) (xy 9.573671 -131.363137) (xy 9.527237 -131.480416)
			(xy 9.47353 -131.594548) (xy 9.412763 -131.705083) (xy 9.345176 -131.811583) (xy 9.271035 -131.91363)
			(xy 9.190632 -132.01082) (xy 9.104286 -132.10277) (xy 9.012336 -132.189116) (xy 8.915146 -132.269519)
			(xy 8.813099 -132.34366) (xy 8.706599 -132.411247) (xy 8.596064 -132.472014) (xy 8.481932 -132.525721)
			(xy 8.364653 -132.572155) (xy 8.24469 -132.611133) (xy 8.122517 -132.642502) (xy 7.998614 -132.666137)
			(xy 7.873472 -132.681947) (xy 7.747584 -132.689867) (xy 7.621448 -132.689867) (xy 7.49556 -132.681947)
			(xy 7.370418 -132.666137) (xy 7.246515 -132.642502) (xy 7.124342 -132.611133) (xy 7.004379 -132.572155)
			(xy 6.8871 -132.525721) (xy 6.772968 -132.472014) (xy 6.662433 -132.411247) (xy 6.555933 -132.34366)
			(xy 6.453886 -132.269519) (xy 6.356696 -132.189116) (xy 6.264746 -132.10277) (xy 6.1784 -132.01082)
			(xy 6.097997 -131.91363) (xy 6.023856 -131.811583) (xy 5.956269 -131.705083) (xy 5.895502 -131.594548)
			(xy 5.841795 -131.480416) (xy 5.795361 -131.363137) (xy 5.756383 -131.243174) (xy 5.725014 -131.121001)
			(xy 5.701379 -130.997098) (xy 5.685569 -130.871956) (xy 5.677649 -130.746068) (xy 1.016 -130.746068)
			(xy 1.016 -139.371578) (xy 1.016492 -139.386921) (xy 1.023881 -139.416707) (xy 1.038164 -139.44387)
			(xy 1.048004 -139.455652) (xy 1.065976 -139.476695) (xy 1.09629 -139.522991) (xy 1.119599 -139.57318)
			(xy 1.135415 -139.62621) (xy 1.143407 -139.680967) (xy 1.143407 -139.736305) (xy 1.135415 -139.791062)
			(xy 1.119599 -139.844092) (xy 1.09629 -139.894281) (xy 1.065976 -139.940577) (xy 1.048004 -139.96162)
			(xy 1.03813 -139.973379) (xy 1.023835 -140.000546) (xy 1.01646 -140.030345) (xy 1.016 -140.045694)
			(xy 1.016 -142.176068) (xy 5.677649 -142.176068) (xy 5.677649 -142.049932) (xy 5.685569 -141.924044)
			(xy 5.701379 -141.798902) (xy 5.725014 -141.674999) (xy 5.756383 -141.552826) (xy 5.795361 -141.432863)
			(xy 5.841795 -141.315584) (xy 5.895502 -141.201452) (xy 5.956269 -141.090917) (xy 6.023856 -140.984417)
			(xy 6.097997 -140.88237) (xy 6.1784 -140.78518) (xy 6.264746 -140.69323) (xy 6.356696 -140.606884)
			(xy 6.453886 -140.526481) (xy 6.555933 -140.45234) (xy 6.662433 -140.384753) (xy 6.772968 -140.323986)
			(xy 6.8871 -140.270279) (xy 7.004379 -140.223845) (xy 7.124342 -140.184867) (xy 7.246515 -140.153498)
			(xy 7.370418 -140.129863) (xy 7.49556 -140.114053) (xy 7.621448 -140.106133) (xy 7.747584 -140.106133)
			(xy 7.873472 -140.114053) (xy 7.998614 -140.129863) (xy 8.122517 -140.153498) (xy 8.24469 -140.184867)
			(xy 8.364653 -140.223845) (xy 8.441392 -140.254228) (xy 39.818818 -140.254228) (xy 39.819523 -140.195605)
			(xy 39.828091 -140.078667) (xy 39.844787 -139.962611) (xy 39.86953 -139.848001) (xy 39.902199 -139.735393)
			(xy 39.942635 -139.625335) (xy 39.990642 -139.518363) (xy 40.045986 -139.414996) (xy 40.108399 -139.315737)
			(xy 40.177577 -139.221068) (xy 40.253183 -139.13145) (xy 40.334851 -139.047318) (xy 40.422182 -138.969081)
			(xy 40.514753 -138.89712) (xy 40.612113 -138.831784) (xy 40.713789 -138.773392) (xy 40.819288 -138.722226)
			(xy 40.928095 -138.678537) (xy 41.039682 -138.642535) (xy 41.153506 -138.614397) (xy 41.269014 -138.594259)
			(xy 41.385645 -138.582218) (xy 41.502832 -138.578334) (xy 41.620004 -138.582625) (xy 41.736593 -138.595071)
			(xy 41.85203 -138.615611) (xy 41.965756 -138.644144) (xy 42.077217 -138.680533) (xy 42.185872 -138.724601)
			(xy 42.291192 -138.776133) (xy 42.392665 -138.834878) (xy 42.489797 -138.900552) (xy 42.582117 -138.972834)
			(xy 42.669176 -139.051374) (xy 42.750551 -139.135789) (xy 42.825845 -139.225669) (xy 42.894694 -139.320578)
			(xy 42.956761 -139.420054) (xy 43.011746 -139.523612) (xy 43.059381 -139.630751) (xy 43.099434 -139.740948)
			(xy 43.131712 -139.853669) (xy 43.156056 -139.968365) (xy 43.172348 -140.084478) (xy 43.18051 -140.201445)
			(xy 43.181016 -140.26007) (xy 43.180861 -140.290833) (xy 43.178574 -140.352316) (xy 43.176444 -140.383006)
			(xy 43.175682 -140.392404) (xy 43.170622 -140.450806) (xy 43.153396 -140.566771) (xy 43.12813 -140.681253)
			(xy 43.094949 -140.793697) (xy 43.054014 -140.903555) (xy 43.005523 -141.010294) (xy 42.949712 -141.113395)
			(xy 42.886853 -141.212356) (xy 42.817252 -141.306696) (xy 42.741246 -141.395958) (xy 42.659204 -141.479706)
			(xy 42.571527 -141.557535) (xy 42.503292 -141.61008) (xy 93.15476 -141.61008) (xy 93.158776 -141.49381)
			(xy 93.170803 -141.378095) (xy 93.190785 -141.263485) (xy 93.218627 -141.150526) (xy 93.254196 -141.039758)
			(xy 93.297322 -140.931707) (xy 93.347799 -140.826889) (xy 93.405388 -140.725804) (xy 93.469814 -140.628932)
			(xy 93.540769 -140.536736) (xy 93.617916 -140.449655) (xy 93.700887 -140.368104) (xy 93.789287 -140.292472)
			(xy 93.882694 -140.223118) (xy 93.980663 -140.160375) (xy 94.082727 -140.104539) (xy 94.188401 -140.055878)
			(xy 94.29718 -140.014624) (xy 94.408545 -139.980973) (xy 94.521968 -139.955085) (xy 94.636905 -139.937084)
			(xy 94.752811 -139.927055) (xy 94.869133 -139.925047) (xy 94.985316 -139.931069) (xy 95.100807 -139.945092)
			(xy 95.215055 -139.96705) (xy 95.327516 -139.996837) (xy 95.437654 -140.034312) (xy 95.544944 -140.079297)
			(xy 95.648875 -140.131576) (xy 95.748951 -140.190901) (xy 95.844697 -140.256989) (xy 95.935654 -140.329525)
			(xy 96.02139 -140.408164) (xy 96.101497 -140.49253) (xy 96.175593 -140.582222) (xy 96.243323 -140.676812)
			(xy 96.304367 -140.77585) (xy 96.358432 -140.878863) (xy 96.405262 -140.98536) (xy 96.444633 -141.094835)
			(xy 96.476357 -141.206765) (xy 96.500283 -141.320617) (xy 96.516297 -141.435849) (xy 96.524324 -141.551911)
			(xy 96.524826 -141.61008) (xy 96.524324 -141.668249) (xy 96.516297 -141.784311) (xy 96.500283 -141.899543)
			(xy 96.476357 -142.013395) (xy 96.444633 -142.125325) (xy 96.405262 -142.2348) (xy 96.358432 -142.341297)
			(xy 96.304367 -142.44431) (xy 96.243323 -142.543348) (xy 96.175593 -142.637938) (xy 96.101497 -142.72763)
			(xy 96.02139 -142.811996) (xy 95.935654 -142.890635) (xy 95.844697 -142.963171) (xy 95.748951 -143.029259)
			(xy 95.648875 -143.088584) (xy 95.544944 -143.140863) (xy 95.437654 -143.185848) (xy 95.327516 -143.223323)
			(xy 95.215055 -143.25311) (xy 95.100807 -143.275068) (xy 94.985316 -143.289091) (xy 94.869133 -143.295113)
			(xy 94.752811 -143.293105) (xy 94.636905 -143.283076) (xy 94.521968 -143.265075) (xy 94.408545 -143.239187)
			(xy 94.29718 -143.205536) (xy 94.188401 -143.164282) (xy 94.082727 -143.115621) (xy 93.980663 -143.059785)
			(xy 93.882694 -142.997042) (xy 93.789287 -142.927688) (xy 93.700887 -142.852056) (xy 93.617916 -142.770505)
			(xy 93.540769 -142.683424) (xy 93.469814 -142.591228) (xy 93.405388 -142.494356) (xy 93.347799 -142.393271)
			(xy 93.297322 -142.288453) (xy 93.254196 -142.180402) (xy 93.218627 -142.069634) (xy 93.190785 -141.956675)
			(xy 93.170803 -141.842065) (xy 93.158776 -141.72635) (xy 93.15476 -141.61008) (xy 42.503292 -141.61008)
			(xy 42.47864 -141.629064) (xy 42.380994 -141.693948) (xy 42.279065 -141.75187) (xy 42.173347 -141.802549)
			(xy 42.064355 -141.845738) (xy 41.952619 -141.881228) (xy 41.838681 -141.908845) (xy 41.723096 -141.928457)
			(xy 41.606425 -141.939967) (xy 41.489236 -141.943319) (xy 41.372098 -141.938497) (xy 41.25558 -141.925525)
			(xy 41.14025 -141.904466) (xy 41.026668 -141.875421) (xy 40.915385 -141.838533) (xy 40.806943 -141.79398)
			(xy 40.70187 -141.74198) (xy 40.600675 -141.682784) (xy 40.50385 -141.616681) (xy 40.411868 -141.543992)
			(xy 40.325173 -141.46507) (xy 40.244189 -141.380299) (xy 40.169308 -141.290091) (xy 40.100895 -141.194885)
			(xy 40.039282 -141.095143) (xy 39.984769 -140.991351) (xy 39.937621 -140.884012) (xy 39.898066 -140.773649)
			(xy 39.866298 -140.660798) (xy 39.842471 -140.546008) (xy 39.826699 -140.429836) (xy 39.819061 -140.312848)
			(xy 39.818818 -140.254228) (xy 8.441392 -140.254228) (xy 8.481932 -140.270279) (xy 8.596064 -140.323986)
			(xy 8.706599 -140.384753) (xy 8.813099 -140.45234) (xy 8.915146 -140.526481) (xy 9.012336 -140.606884)
			(xy 9.104286 -140.69323) (xy 9.190632 -140.78518) (xy 9.271035 -140.88237) (xy 9.345176 -140.984417)
			(xy 9.412763 -141.090917) (xy 9.47353 -141.201452) (xy 9.527237 -141.315584) (xy 9.573671 -141.432863)
			(xy 9.612649 -141.552826) (xy 9.644018 -141.674999) (xy 9.667653 -141.798902) (xy 9.683463 -141.924044)
			(xy 9.691383 -142.049932) (xy 9.691878 -142.113) (xy 9.691383 -142.176068) (xy 9.683463 -142.301956)
			(xy 9.667653 -142.427098) (xy 9.644018 -142.551001) (xy 9.612649 -142.673174) (xy 9.573671 -142.793137)
			(xy 9.527237 -142.910416) (xy 9.47353 -143.024548) (xy 9.412763 -143.135083) (xy 9.345176 -143.241583)
			(xy 9.271035 -143.34363) (xy 9.190632 -143.44082) (xy 9.104286 -143.53277) (xy 9.012336 -143.619116)
			(xy 8.915146 -143.699519) (xy 8.813099 -143.77366) (xy 8.706599 -143.841247) (xy 8.596064 -143.902014)
			(xy 8.481932 -143.955721) (xy 8.364653 -144.002155) (xy 8.24469 -144.041133) (xy 8.122517 -144.072502)
			(xy 7.998614 -144.096137) (xy 7.873472 -144.111947) (xy 7.747584 -144.119867) (xy 7.621448 -144.119867)
			(xy 7.49556 -144.111947) (xy 7.370418 -144.096137) (xy 7.246515 -144.072502) (xy 7.124342 -144.041133)
			(xy 7.004379 -144.002155) (xy 6.8871 -143.955721) (xy 6.772968 -143.902014) (xy 6.662433 -143.841247)
			(xy 6.555933 -143.77366) (xy 6.453886 -143.699519) (xy 6.356696 -143.619116) (xy 6.264746 -143.53277)
			(xy 6.1784 -143.44082) (xy 6.097997 -143.34363) (xy 6.023856 -143.241583) (xy 5.956269 -143.135083)
			(xy 5.895502 -143.024548) (xy 5.841795 -142.910416) (xy 5.795361 -142.793137) (xy 5.756383 -142.673174)
			(xy 5.725014 -142.551001) (xy 5.701379 -142.427098) (xy 5.685569 -142.301956) (xy 5.677649 -142.176068)
			(xy 1.016 -142.176068) (xy 1.016 -152.071578) (xy 1.016492 -152.086921) (xy 1.023881 -152.116707)
			(xy 1.038164 -152.14387) (xy 1.048004 -152.155652) (xy 1.065976 -152.176695) (xy 1.09629 -152.222991)
			(xy 1.119599 -152.27318) (xy 1.135415 -152.32621) (xy 1.143407 -152.380967) (xy 1.143407 -152.436305)
			(xy 1.135415 -152.491062) (xy 1.119599 -152.544092) (xy 1.09629 -152.594281) (xy 1.065976 -152.640577)
			(xy 1.048004 -152.66162) (xy 1.03813 -152.673379) (xy 1.023835 -152.700546) (xy 1.01646 -152.730345)
			(xy 1.016 -152.745694) (xy 1.016 -153.359866) (xy 86.877404 -153.359866) (xy 86.881424 -153.169215)
			(xy 86.893478 -152.978902) (xy 86.913544 -152.789267) (xy 86.941587 -152.600646) (xy 86.977556 -152.413376)
			(xy 87.021388 -152.227788) (xy 87.073005 -152.044213) (xy 87.132315 -151.862977) (xy 87.199213 -151.684402)
			(xy 87.273579 -151.508807) (xy 87.355281 -151.336502) (xy 87.444175 -151.167795) (xy 87.540101 -151.002985)
			(xy 87.64289 -150.842366) (xy 87.752359 -150.686223) (xy 87.868313 -150.534834) (xy 87.990547 -150.388467)
			(xy 88.118841 -150.247383) (xy 88.252969 -150.111834) (xy 88.392693 -149.982059) (xy 88.537763 -149.858289)
			(xy 88.687921 -149.740746) (xy 88.842902 -149.629637) (xy 89.002429 -149.52516) (xy 89.166218 -149.427501)
			(xy 89.333978 -149.336834) (xy 89.505412 -149.25332) (xy 89.680214 -149.177107) (xy 89.858073 -149.108331)
			(xy 90.038674 -149.047113) (xy 90.221694 -148.993564) (xy 90.40681 -148.947778) (xy 90.593691 -148.909836)
			(xy 90.782006 -148.879807) (xy 90.971419 -148.857742) (xy 91.161593 -148.843683) (xy 91.352192 -148.837653)
			(xy 91.542875 -148.839663) (xy 91.733304 -148.84971) (xy 91.92314 -148.867776) (xy 92.112046 -148.893829)
			(xy 92.299685 -148.927822) (xy 92.485725 -148.969695) (xy 92.669834 -149.019374) (xy 92.851685 -149.07677)
			(xy 93.030955 -149.141781) (xy 93.207325 -149.214292) (xy 93.380481 -149.294173) (xy 93.550116 -149.381283)
			(xy 93.715928 -149.475467) (xy 93.877622 -149.576558) (xy 94.03491 -149.684374) (xy 94.187513 -149.798726)
			(xy 94.335161 -149.919409) (xy 94.477589 -150.04621) (xy 94.614545 -150.178901) (xy 94.745786 -150.317249)
			(xy 94.871078 -150.461006) (xy 94.990198 -150.609917) (xy 95.102934 -150.763718) (xy 95.209087 -150.922134)
			(xy 95.308467 -151.084885) (xy 95.400897 -151.25168) (xy 95.486214 -151.422224) (xy 95.564266 -151.596212)
			(xy 95.634913 -151.773337) (xy 95.698031 -151.953282) (xy 95.753507 -152.135728) (xy 95.801242 -152.320351)
			(xy 95.841152 -152.506821) (xy 95.873165 -152.694809) (xy 95.897225 -152.883979) (xy 95.913288 -153.073995)
			(xy 95.921327 -153.264519) (xy 95.92183 -153.359866) (xy 95.921327 -153.455213) (xy 95.913288 -153.645737)
			(xy 95.897225 -153.835753) (xy 95.873165 -154.024923) (xy 95.841152 -154.212911) (xy 95.801242 -154.399381)
			(xy 95.753507 -154.584004) (xy 95.698031 -154.76645) (xy 95.634913 -154.946395) (xy 95.564266 -155.12352)
			(xy 95.486214 -155.297508) (xy 95.400897 -155.468052) (xy 95.308467 -155.634847) (xy 95.209087 -155.797598)
			(xy 95.102934 -155.956014) (xy 94.990198 -156.109815) (xy 94.871078 -156.258726) (xy 94.745786 -156.402483)
			(xy 94.614545 -156.540831) (xy 94.477589 -156.673522) (xy 94.335161 -156.800323) (xy 94.187513 -156.921006)
			(xy 94.03491 -157.035358) (xy 93.877622 -157.143174) (xy 93.715928 -157.244265) (xy 93.550116 -157.338449)
			(xy 93.380481 -157.425559) (xy 93.207325 -157.50544) (xy 93.030955 -157.577951) (xy 92.851685 -157.642962)
			(xy 92.669834 -157.700358) (xy 92.485725 -157.750037) (xy 92.299685 -157.79191) (xy 92.112046 -157.825903)
			(xy 91.92314 -157.851956) (xy 91.733304 -157.870022) (xy 91.542875 -157.880069) (xy 91.352192 -157.882079)
			(xy 91.161593 -157.876049) (xy 90.971419 -157.86199) (xy 90.782006 -157.839925) (xy 90.593691 -157.809896)
			(xy 90.40681 -157.771954) (xy 90.221694 -157.726168) (xy 90.038674 -157.672619) (xy 89.858073 -157.611401)
			(xy 89.680214 -157.542625) (xy 89.505412 -157.466412) (xy 89.333978 -157.382898) (xy 89.166218 -157.292231)
			(xy 89.002429 -157.194572) (xy 88.842902 -157.090095) (xy 88.687921 -156.978986) (xy 88.537763 -156.861443)
			(xy 88.392693 -156.737673) (xy 88.252969 -156.607898) (xy 88.118841 -156.472349) (xy 87.990547 -156.331265)
			(xy 87.868313 -156.184898) (xy 87.752359 -156.033509) (xy 87.64289 -155.877366) (xy 87.540101 -155.716747)
			(xy 87.444175 -155.551937) (xy 87.355281 -155.38323) (xy 87.273579 -155.210925) (xy 87.199213 -155.03533)
			(xy 87.132315 -154.856755) (xy 87.073005 -154.675519) (xy 87.021388 -154.491944) (xy 86.977556 -154.306356)
			(xy 86.941587 -154.119086) (xy 86.913544 -153.930465) (xy 86.893478 -153.74083) (xy 86.881424 -153.550517)
			(xy 86.877404 -153.359866) (xy 1.016 -153.359866) (xy 1.016 -164.771578) (xy 1.016492 -164.786921)
			(xy 1.023881 -164.816707) (xy 1.038164 -164.84387) (xy 1.048004 -164.855652) (xy 1.065976 -164.876695)
			(xy 1.09629 -164.922991) (xy 1.119599 -164.97318) (xy 1.135415 -165.02621) (xy 1.143407 -165.080967)
			(xy 1.143407 -165.136305) (xy 1.135415 -165.191062) (xy 1.119599 -165.244092) (xy 1.09629 -165.294281)
			(xy 1.065976 -165.340577) (xy 1.048004 -165.36162) (xy 1.03813 -165.373379) (xy 1.023835 -165.400546)
			(xy 1.01646 -165.430345) (xy 1.016 -165.445694) (xy 1.016 -177.471578) (xy 1.016492 -177.486921)
			(xy 1.023881 -177.516707) (xy 1.038164 -177.54387) (xy 1.048004 -177.555652) (xy 1.065976 -177.576695)
			(xy 1.09629 -177.622991) (xy 1.119599 -177.67318) (xy 1.135415 -177.72621) (xy 1.143407 -177.780967)
			(xy 1.143407 -177.836305) (xy 1.135415 -177.891062) (xy 1.119599 -177.944092) (xy 1.09629 -177.994281)
			(xy 1.065976 -178.040577) (xy 1.048004 -178.06162) (xy 1.03813 -178.073379) (xy 1.023835 -178.100546)
			(xy 1.01646 -178.130345) (xy 1.016 -178.145694) (xy 1.016 -184.704228) (xy 39.818818 -184.704228)
			(xy 39.819523 -184.645605) (xy 39.828091 -184.528667) (xy 39.844787 -184.412611) (xy 39.86953 -184.298001)
			(xy 39.902199 -184.185393) (xy 39.942635 -184.075335) (xy 39.990642 -183.968363) (xy 40.045986 -183.864996)
			(xy 40.108399 -183.765737) (xy 40.177577 -183.671068) (xy 40.253183 -183.58145) (xy 40.334851 -183.497318)
			(xy 40.422182 -183.419081) (xy 40.514753 -183.34712) (xy 40.612113 -183.281784) (xy 40.713789 -183.223392)
			(xy 40.819288 -183.172226) (xy 40.928095 -183.128537) (xy 41.039682 -183.092535) (xy 41.153506 -183.064397)
			(xy 41.269014 -183.044259) (xy 41.385645 -183.032218) (xy 41.502832 -183.028334) (xy 41.620004 -183.032625)
			(xy 41.736593 -183.045071) (xy 41.85203 -183.065611) (xy 41.965756 -183.094144) (xy 42.077217 -183.130533)
			(xy 42.185872 -183.174601) (xy 42.291192 -183.226133) (xy 42.392665 -183.284878) (xy 42.489797 -183.350552)
			(xy 42.582117 -183.422834) (xy 42.669176 -183.501374) (xy 42.750551 -183.585789) (xy 42.825845 -183.675669)
			(xy 42.894694 -183.770578) (xy 42.956761 -183.870054) (xy 43.011746 -183.973612) (xy 43.059381 -184.080751)
			(xy 43.099434 -184.190948) (xy 43.131712 -184.303669) (xy 43.156056 -184.418365) (xy 43.172348 -184.534478)
			(xy 43.18051 -184.651445) (xy 43.181016 -184.71007) (xy 43.180861 -184.740833) (xy 43.178574 -184.802316)
			(xy 43.176444 -184.833006) (xy 43.175682 -184.842404) (xy 43.170622 -184.900806) (xy 43.153396 -185.016771)
			(xy 43.12813 -185.131253) (xy 43.094949 -185.243697) (xy 43.054014 -185.353555) (xy 43.005523 -185.460294)
			(xy 42.949712 -185.563395) (xy 42.886853 -185.662356) (xy 42.817252 -185.756696) (xy 42.741246 -185.845958)
			(xy 42.659204 -185.929706) (xy 42.571527 -186.007535) (xy 42.503292 -186.06008) (xy 93.15476 -186.06008)
			(xy 93.158776 -185.94381) (xy 93.170803 -185.828095) (xy 93.190785 -185.713485) (xy 93.218627 -185.600526)
			(xy 93.254196 -185.489758) (xy 93.297322 -185.381707) (xy 93.347799 -185.276889) (xy 93.405388 -185.175804)
			(xy 93.469814 -185.078932) (xy 93.540769 -184.986736) (xy 93.617916 -184.899655) (xy 93.700887 -184.818104)
			(xy 93.789287 -184.742472) (xy 93.882694 -184.673118) (xy 93.980663 -184.610375) (xy 94.082727 -184.554539)
			(xy 94.188401 -184.505878) (xy 94.29718 -184.464624) (xy 94.408545 -184.430973) (xy 94.521968 -184.405085)
			(xy 94.636905 -184.387084) (xy 94.752811 -184.377055) (xy 94.869133 -184.375047) (xy 94.985316 -184.381069)
			(xy 95.100807 -184.395092) (xy 95.215055 -184.41705) (xy 95.327516 -184.446837) (xy 95.437654 -184.484312)
			(xy 95.544944 -184.529297) (xy 95.648875 -184.581576) (xy 95.748951 -184.640901) (xy 95.844697 -184.706989)
			(xy 95.935654 -184.779525) (xy 96.02139 -184.858164) (xy 96.101497 -184.94253) (xy 96.175593 -185.032222)
			(xy 96.243323 -185.126812) (xy 96.304367 -185.22585) (xy 96.358432 -185.328863) (xy 96.405262 -185.43536)
			(xy 96.444633 -185.544835) (xy 96.476357 -185.656765) (xy 96.500283 -185.770617) (xy 96.516297 -185.885849)
			(xy 96.524324 -186.001911) (xy 96.524826 -186.06008) (xy 96.524324 -186.118249) (xy 96.516297 -186.234311)
			(xy 96.500283 -186.349543) (xy 96.476357 -186.463395) (xy 96.444633 -186.575325) (xy 96.405262 -186.6848)
			(xy 96.358432 -186.791297) (xy 96.304367 -186.89431) (xy 96.243323 -186.993348) (xy 96.175593 -187.087938)
			(xy 96.101497 -187.17763) (xy 96.02139 -187.261996) (xy 95.935654 -187.340635) (xy 95.844697 -187.413171)
			(xy 95.748951 -187.479259) (xy 95.648875 -187.538584) (xy 95.544944 -187.590863) (xy 95.437654 -187.635848)
			(xy 95.327516 -187.673323) (xy 95.215055 -187.70311) (xy 95.100807 -187.725068) (xy 94.985316 -187.739091)
			(xy 94.869133 -187.745113) (xy 94.752811 -187.743105) (xy 94.636905 -187.733076) (xy 94.521968 -187.715075)
			(xy 94.408545 -187.689187) (xy 94.29718 -187.655536) (xy 94.188401 -187.614282) (xy 94.082727 -187.565621)
			(xy 93.980663 -187.509785) (xy 93.882694 -187.447042) (xy 93.789287 -187.377688) (xy 93.700887 -187.302056)
			(xy 93.617916 -187.220505) (xy 93.540769 -187.133424) (xy 93.469814 -187.041228) (xy 93.405388 -186.944356)
			(xy 93.347799 -186.843271) (xy 93.297322 -186.738453) (xy 93.254196 -186.630402) (xy 93.218627 -186.519634)
			(xy 93.190785 -186.406675) (xy 93.170803 -186.292065) (xy 93.158776 -186.17635) (xy 93.15476 -186.06008)
			(xy 42.503292 -186.06008) (xy 42.47864 -186.079064) (xy 42.380994 -186.143948) (xy 42.279065 -186.20187)
			(xy 42.173347 -186.252549) (xy 42.064355 -186.295738) (xy 41.952619 -186.331228) (xy 41.838681 -186.358845)
			(xy 41.723096 -186.378457) (xy 41.606425 -186.389967) (xy 41.489236 -186.393319) (xy 41.372098 -186.388497)
			(xy 41.25558 -186.375525) (xy 41.14025 -186.354466) (xy 41.026668 -186.325421) (xy 40.915385 -186.288533)
			(xy 40.806943 -186.24398) (xy 40.70187 -186.19198) (xy 40.600675 -186.132784) (xy 40.50385 -186.066681)
			(xy 40.411868 -185.993992) (xy 40.325173 -185.91507) (xy 40.244189 -185.830299) (xy 40.169308 -185.740091)
			(xy 40.100895 -185.644885) (xy 40.039282 -185.545143) (xy 39.984769 -185.441351) (xy 39.937621 -185.334012)
			(xy 39.898066 -185.223649) (xy 39.866298 -185.110798) (xy 39.842471 -184.996008) (xy 39.826699 -184.879836)
			(xy 39.819061 -184.762848) (xy 39.818818 -184.704228) (xy 1.016 -184.704228) (xy 1.016 -190.171578)
			(xy 1.016492 -190.186921) (xy 1.023881 -190.216707) (xy 1.038164 -190.24387) (xy 1.048004 -190.255652)
			(xy 1.065976 -190.276695) (xy 1.09629 -190.322991) (xy 1.119599 -190.37318) (xy 1.135415 -190.42621)
			(xy 1.143407 -190.480967) (xy 1.143407 -190.536305) (xy 1.135415 -190.591062) (xy 1.119599 -190.644092)
			(xy 1.09629 -190.694281) (xy 1.065976 -190.740577) (xy 1.048004 -190.76162) (xy 1.03813 -190.773379)
			(xy 1.023835 -190.800546) (xy 1.01646 -190.830345) (xy 1.016 -190.845694) (xy 1.016 -197.81012) (xy 86.877404 -197.81012)
			(xy 86.881424 -197.619469) (xy 86.893478 -197.429156) (xy 86.913544 -197.239521) (xy 86.941587 -197.0509)
			(xy 86.977556 -196.86363) (xy 87.021388 -196.678042) (xy 87.073005 -196.494467) (xy 87.132315 -196.313231)
			(xy 87.199213 -196.134656) (xy 87.273579 -195.959061) (xy 87.355281 -195.786756) (xy 87.444175 -195.618049)
			(xy 87.540101 -195.453239) (xy 87.64289 -195.29262) (xy 87.752359 -195.136477) (xy 87.868313 -194.985088)
			(xy 87.990547 -194.838721) (xy 88.118841 -194.697637) (xy 88.252969 -194.562088) (xy 88.392693 -194.432313)
			(xy 88.537763 -194.308543) (xy 88.687921 -194.191) (xy 88.842902 -194.079891) (xy 89.002429 -193.975414)
			(xy 89.166218 -193.877755) (xy 89.333978 -193.787088) (xy 89.505412 -193.703574) (xy 89.680214 -193.627361)
			(xy 89.858073 -193.558585) (xy 90.038674 -193.497367) (xy 90.221694 -193.443818) (xy 90.40681 -193.398032)
			(xy 90.593691 -193.36009) (xy 90.782006 -193.330061) (xy 90.971419 -193.307996) (xy 91.161593 -193.293937)
			(xy 91.352192 -193.287907) (xy 91.542875 -193.289917) (xy 91.733304 -193.299964) (xy 91.92314 -193.31803)
			(xy 92.112046 -193.344083) (xy 92.299685 -193.378076) (xy 92.485725 -193.419949) (xy 92.669834 -193.469628)
			(xy 92.851685 -193.527024) (xy 93.030955 -193.592035) (xy 93.207325 -193.664546) (xy 93.380481 -193.744427)
			(xy 93.550116 -193.831537) (xy 93.715928 -193.925721) (xy 93.877622 -194.026812) (xy 94.03491 -194.134628)
			(xy 94.187513 -194.24898) (xy 94.335161 -194.369663) (xy 94.477589 -194.496464) (xy 94.614545 -194.629155)
			(xy 94.745786 -194.767503) (xy 94.871078 -194.91126) (xy 94.990198 -195.060171) (xy 95.102934 -195.213972)
			(xy 95.209087 -195.372388) (xy 95.308467 -195.535139) (xy 95.400897 -195.701934) (xy 95.486214 -195.872478)
			(xy 95.564266 -196.046466) (xy 95.634913 -196.223591) (xy 95.698031 -196.403536) (xy 95.753507 -196.585982)
			(xy 95.801242 -196.770605) (xy 95.841152 -196.957075) (xy 95.873165 -197.145063) (xy 95.897225 -197.334233)
			(xy 95.913288 -197.524249) (xy 95.921327 -197.714773) (xy 95.92183 -197.81012) (xy 95.921327 -197.905467)
			(xy 95.913288 -198.095991) (xy 95.897225 -198.286007) (xy 95.873165 -198.475177) (xy 95.841152 -198.663165)
			(xy 95.801242 -198.849635) (xy 95.753507 -199.034258) (xy 95.698031 -199.216704) (xy 95.634913 -199.396649)
			(xy 95.564266 -199.573774) (xy 95.486214 -199.747762) (xy 95.400897 -199.918306) (xy 95.308467 -200.085101)
			(xy 95.209087 -200.247852) (xy 95.102934 -200.406268) (xy 94.990198 -200.560069) (xy 94.871078 -200.70898)
			(xy 94.745786 -200.852737) (xy 94.614545 -200.991085) (xy 94.477589 -201.123776) (xy 94.335161 -201.250577)
			(xy 94.187513 -201.37126) (xy 94.03491 -201.485612) (xy 93.877622 -201.593428) (xy 93.715928 -201.694519)
			(xy 93.550116 -201.788703) (xy 93.380481 -201.875813) (xy 93.207325 -201.955694) (xy 93.030955 -202.028205)
			(xy 92.851685 -202.093216) (xy 92.669834 -202.150612) (xy 92.485725 -202.200291) (xy 92.299685 -202.242164)
			(xy 92.112046 -202.276157) (xy 91.92314 -202.30221) (xy 91.733304 -202.320276) (xy 91.542875 -202.330323)
			(xy 91.352192 -202.332333) (xy 91.161593 -202.326303) (xy 90.971419 -202.312244) (xy 90.782006 -202.290179)
			(xy 90.593691 -202.26015) (xy 90.40681 -202.222208) (xy 90.221694 -202.176422) (xy 90.038674 -202.122873)
			(xy 89.858073 -202.061655) (xy 89.680214 -201.992879) (xy 89.505412 -201.916666) (xy 89.333978 -201.833152)
			(xy 89.166218 -201.742485) (xy 89.002429 -201.644826) (xy 88.842902 -201.540349) (xy 88.687921 -201.42924)
			(xy 88.537763 -201.311697) (xy 88.392693 -201.187927) (xy 88.252969 -201.058152) (xy 88.118841 -200.922603)
			(xy 87.990547 -200.781519) (xy 87.868313 -200.635152) (xy 87.752359 -200.483763) (xy 87.64289 -200.32762)
			(xy 87.540101 -200.167001) (xy 87.444175 -200.002191) (xy 87.355281 -199.833484) (xy 87.273579 -199.661179)
			(xy 87.199213 -199.485584) (xy 87.132315 -199.307009) (xy 87.073005 -199.125773) (xy 87.021388 -198.942198)
			(xy 86.977556 -198.75661) (xy 86.941587 -198.56934) (xy 86.913544 -198.380719) (xy 86.893478 -198.191084)
			(xy 86.881424 -198.000771) (xy 86.877404 -197.81012) (xy 1.016 -197.81012) (xy 1.016 -202.871578)
			(xy 1.016492 -202.886921) (xy 1.023881 -202.916707) (xy 1.038164 -202.94387) (xy 1.048004 -202.955652)
			(xy 1.065976 -202.976695) (xy 1.09629 -203.022991) (xy 1.119599 -203.07318) (xy 1.135415 -203.12621)
			(xy 1.143407 -203.180967) (xy 1.143407 -203.236305) (xy 1.135415 -203.291062) (xy 1.119599 -203.344092)
			(xy 1.09629 -203.394281) (xy 1.065976 -203.440577) (xy 1.048004 -203.46162) (xy 1.03813 -203.473379)
			(xy 1.023835 -203.500546) (xy 1.01646 -203.530345) (xy 1.016 -203.545694) (xy 1.016 -206.99984) (xy 11.344156 -206.99984)
			(xy 11.348157 -206.794781) (xy 11.360157 -206.590034) (xy 11.380135 -206.385911) (xy 11.408063 -206.182723)
			(xy 11.443897 -205.980779) (xy 11.487582 -205.780388) (xy 11.539053 -205.581853) (xy 11.598231 -205.385477)
			(xy 11.665026 -205.19156) (xy 11.739335 -205.000397) (xy 11.821046 -204.812279) (xy 11.910035 -204.627492)
			(xy 12.006166 -204.446317) (xy 12.109292 -204.269031) (xy 12.219257 -204.095904) (xy 12.335893 -203.927199)
			(xy 12.459022 -203.763173) (xy 12.588457 -203.604076) (xy 12.724001 -203.45015) (xy 12.865447 -203.30163)
			(xy 13.01258 -203.158741) (xy 13.165176 -203.021702) (xy 13.323003 -202.890721) (xy 13.48582 -202.765997)
			(xy 13.653379 -202.647721) (xy 13.825425 -202.536073) (xy 14.001696 -202.431222) (xy 14.181924 -202.333328)
			(xy 14.365835 -202.242541) (xy 14.553147 -202.158998) (xy 14.743576 -202.082827) (xy 14.936832 -202.014143)
			(xy 15.132621 -201.953053) (xy 15.330644 -201.899647) (xy 15.5306 -201.854009) (xy 15.732184 -201.816206)
			(xy 15.93509 -201.786298) (xy 16.139008 -201.764328) (xy 16.343629 -201.750332) (xy 16.548639 -201.74433)
			(xy 16.753728 -201.746331) (xy 16.958582 -201.756332) (xy 17.16289 -201.774318) (xy 17.366341 -201.800262)
			(xy 17.568624 -201.834124) (xy 17.769433 -201.875852) (xy 17.96846 -201.925384) (xy 18.165404 -201.982643)
			(xy 18.359963 -202.047542) (xy 18.551842 -202.119983) (xy 18.740749 -202.199855) (xy 18.926395 -202.287037)
			(xy 19.108499 -202.381396) (xy 19.286783 -202.482787) (xy 19.460975 -202.591058) (xy 19.63081 -202.706042)
			(xy 19.796029 -202.827565) (xy 19.956381 -202.955442) (xy 20.111622 -203.089477) (xy 20.261516 -203.229468)
			(xy 20.405833 -203.3752) (xy 20.544354 -203.526452) (xy 20.676869 -203.682993) (xy 20.803175 -203.844585)
			(xy 20.92308 -204.010982) (xy 21.036402 -204.181931) (xy 21.142968 -204.357171) (xy 21.242615 -204.536435)
			(xy 21.335193 -204.719451) (xy 21.420559 -204.905939) (xy 21.498584 -205.095616) (xy 21.56915 -205.288193)
			(xy 21.632148 -205.483376) (xy 21.687483 -205.680869) (xy 21.73507 -205.88037) (xy 21.774837 -206.081576)
			(xy 21.806724 -206.284181) (xy 21.830682 -206.487875) (xy 21.846674 -206.692349) (xy 21.854676 -206.897291)
			(xy 21.855176 -206.99984) (xy 21.854676 -207.102389) (xy 21.846674 -207.307331) (xy 21.830682 -207.511805)
			(xy 21.806724 -207.715499) (xy 21.774837 -207.918104) (xy 21.73507 -208.11931) (xy 21.687483 -208.318811)
			(xy 21.632148 -208.516304) (xy 21.56915 -208.711487) (xy 21.498584 -208.904064) (xy 21.420559 -209.093741)
			(xy 21.335193 -209.280229) (xy 21.242615 -209.463245) (xy 21.142968 -209.642509) (xy 21.036402 -209.817749)
			(xy 20.92308 -209.988698) (xy 20.843124 -210.099656) (xy 72.857112 -210.099656) (xy 72.861127 -209.896474)
			(xy 72.873166 -209.693609) (xy 72.89321 -209.491379) (xy 72.921228 -209.290098) (xy 72.957176 -209.090081)
			(xy 73.000998 -208.89164) (xy 73.052625 -208.695086) (xy 73.111977 -208.500725) (xy 73.178962 -208.30886)
			(xy 73.253474 -208.119791) (xy 73.335397 -207.933814) (xy 73.424604 -207.751218) (xy 73.520955 -207.572289)
			(xy 73.624299 -207.397307) (xy 73.734476 -207.226544) (xy 73.851313 -207.060266) (xy 73.974628 -206.898735)
			(xy 74.104228 -206.742201) (xy 74.239911 -206.59091) (xy 74.381466 -206.445097) (xy 74.52867 -206.30499)
			(xy 74.681294 -206.170808) (xy 74.839101 -206.04276) (xy 75.001843 -205.921047) (xy 75.169266 -205.805859)
			(xy 75.341109 -205.697374) (xy 75.517104 -205.595763) (xy 75.696976 -205.501185) (xy 75.880444 -205.413786)
			(xy 76.067222 -205.333704) (xy 76.257018 -205.261064) (xy 76.449535 -205.195978) (xy 76.644473 -205.138549)
			(xy 76.841528 -205.088866) (xy 77.040392 -205.047006) (xy 77.240754 -205.013036) (xy 77.442302 -204.987008)
			(xy 77.644721 -204.968963) (xy 77.847694 -204.958929) (xy 78.050906 -204.956921) (xy 78.254038 -204.962943)
			(xy 78.456774 -204.976986) (xy 78.658797 -204.999027) (xy 78.859791 -205.029032) (xy 79.059443 -205.066954)
			(xy 79.257441 -205.112734) (xy 79.453476 -205.1663) (xy 79.647241 -205.22757) (xy 79.838435 -205.296446)
			(xy 80.026758 -205.372823) (xy 80.211917 -205.456579) (xy 80.393623 -205.547586) (xy 80.571591 -205.645699)
			(xy 80.745544 -205.750768) (xy 80.915211 -205.862626) (xy 81.080325 -205.9811) (xy 81.240631 -206.106005)
			(xy 81.395877 -206.237145) (xy 81.54582 -206.374316) (xy 81.690228 -206.517304) (xy 81.828873 -206.665885)
			(xy 81.961541 -206.819828) (xy 82.088023 -206.978891) (xy 82.208123 -207.142828) (xy 82.321652 -207.311381)
			(xy 82.428433 -207.484288) (xy 82.5283 -207.661278) (xy 82.621097 -207.842075) (xy 82.706679 -208.026398)
			(xy 82.784912 -208.213957) (xy 82.855674 -208.404461) (xy 82.918855 -208.597612) (xy 82.974355 -208.793108)
			(xy 83.022089 -208.990644) (xy 83.061982 -209.189912) (xy 83.093971 -209.3906) (xy 83.118007 -209.592395)
			(xy 83.134052 -209.794982) (xy 83.14208 -209.998045) (xy 83.142582 -210.099656) (xy 83.14208 -210.201267)
			(xy 83.134052 -210.40433) (xy 83.118007 -210.606917) (xy 83.093971 -210.808712) (xy 83.061982 -211.0094)
			(xy 83.022089 -211.208668) (xy 82.974355 -211.406204) (xy 82.918855 -211.6017) (xy 82.855674 -211.794851)
			(xy 82.784912 -211.985355) (xy 82.706679 -212.172914) (xy 82.621097 -212.357237) (xy 82.5283 -212.538034)
			(xy 82.428433 -212.715024) (xy 82.321652 -212.887931) (xy 82.208123 -213.056484) (xy 82.088023 -213.220421)
			(xy 81.961541 -213.379484) (xy 81.828873 -213.533427) (xy 81.690228 -213.682008) (xy 81.54582 -213.824996)
			(xy 81.395877 -213.962167) (xy 81.240631 -214.093307) (xy 81.080325 -214.218212) (xy 80.915211 -214.336686)
			(xy 80.745544 -214.448544) (xy 80.571591 -214.553613) (xy 80.393623 -214.651726) (xy 80.211917 -214.742733)
			(xy 80.026758 -214.826489) (xy 79.838435 -214.902866) (xy 79.647241 -214.971742) (xy 79.453476 -215.033012)
			(xy 79.257441 -215.086578) (xy 79.059443 -215.132358) (xy 78.859791 -215.17028) (xy 78.658797 -215.200285)
			(xy 78.456774 -215.222326) (xy 78.254038 -215.236369) (xy 78.050906 -215.242391) (xy 77.847694 -215.240383)
			(xy 77.644721 -215.230349) (xy 77.442302 -215.212304) (xy 77.240754 -215.186276) (xy 77.040392 -215.152306)
			(xy 76.841528 -215.110446) (xy 76.644473 -215.060763) (xy 76.449535 -215.003334) (xy 76.257018 -214.938248)
			(xy 76.067222 -214.865608) (xy 75.880444 -214.785526) (xy 75.696976 -214.698127) (xy 75.517104 -214.603549)
			(xy 75.341109 -214.501938) (xy 75.169266 -214.393453) (xy 75.001843 -214.278265) (xy 74.839101 -214.156552)
			(xy 74.681294 -214.028504) (xy 74.52867 -213.894322) (xy 74.381466 -213.754215) (xy 74.239911 -213.608402)
			(xy 74.104228 -213.457111) (xy 73.974628 -213.300577) (xy 73.851313 -213.139046) (xy 73.734476 -212.972768)
			(xy 73.624299 -212.802005) (xy 73.520955 -212.627023) (xy 73.424604 -212.448094) (xy 73.335397 -212.265498)
			(xy 73.253474 -212.079521) (xy 73.178962 -211.890452) (xy 73.111977 -211.698587) (xy 73.052625 -211.504226)
			(xy 73.000998 -211.307672) (xy 72.957176 -211.109231) (xy 72.921228 -210.909214) (xy 72.89321 -210.707933)
			(xy 72.873166 -210.505703) (xy 72.861127 -210.302838) (xy 72.857112 -210.099656) (xy 20.843124 -210.099656)
			(xy 20.803175 -210.155095) (xy 20.676869 -210.316687) (xy 20.544354 -210.473228) (xy 20.405833 -210.62448)
			(xy 20.261516 -210.770212) (xy 20.111622 -210.910203) (xy 19.956381 -211.044238) (xy 19.796029 -211.172115)
			(xy 19.63081 -211.293638) (xy 19.460975 -211.408622) (xy 19.286783 -211.516893) (xy 19.108499 -211.618284)
			(xy 18.926395 -211.712643) (xy 18.740749 -211.799825) (xy 18.551842 -211.879697) (xy 18.359963 -211.952138)
			(xy 18.165404 -212.017037) (xy 17.96846 -212.074296) (xy 17.769433 -212.123828) (xy 17.568624 -212.165556)
			(xy 17.366341 -212.199418) (xy 17.16289 -212.225362) (xy 16.958582 -212.243348) (xy 16.753728 -212.253349)
			(xy 16.548639 -212.25535) (xy 16.343629 -212.249348) (xy 16.139008 -212.235352) (xy 15.93509 -212.213382)
			(xy 15.732184 -212.183474) (xy 15.5306 -212.145671) (xy 15.330644 -212.100033) (xy 15.132621 -212.046627)
			(xy 14.936832 -211.985537) (xy 14.743576 -211.916853) (xy 14.553147 -211.840682) (xy 14.365835 -211.757139)
			(xy 14.181924 -211.666352) (xy 14.001696 -211.568458) (xy 13.825425 -211.463607) (xy 13.653379 -211.351959)
			(xy 13.48582 -211.233683) (xy 13.323003 -211.108959) (xy 13.165176 -210.977978) (xy 13.01258 -210.840939)
			(xy 12.865447 -210.69805) (xy 12.724001 -210.54953) (xy 12.588457 -210.395604) (xy 12.459022 -210.236507)
			(xy 12.335893 -210.072481) (xy 12.219257 -209.903776) (xy 12.109292 -209.730649) (xy 12.006166 -209.553363)
			(xy 11.910035 -209.372188) (xy 11.821046 -209.187401) (xy 11.739335 -208.999283) (xy 11.665026 -208.80812)
			(xy 11.598231 -208.614203) (xy 11.539053 -208.417827) (xy 11.487582 -208.219292) (xy 11.443897 -208.018901)
			(xy 11.408063 -207.816957) (xy 11.380135 -207.613769) (xy 11.360157 -207.409646) (xy 11.348157 -207.204899)
			(xy 11.344156 -206.99984) (xy 1.016 -206.99984) (xy 1.016 -215.571578) (xy 1.016492 -215.586921)
			(xy 1.023881 -215.616707) (xy 1.038164 -215.64387) (xy 1.048004 -215.655652) (xy 1.065976 -215.676695)
			(xy 1.09629 -215.722991) (xy 1.119599 -215.77318) (xy 1.135415 -215.82621) (xy 1.143407 -215.880967)
			(xy 1.143407 -215.936305) (xy 1.135415 -215.991062) (xy 1.119599 -216.044092) (xy 1.09629 -216.094281)
			(xy 1.065976 -216.140577) (xy 1.048004 -216.16162) (xy 1.03813 -216.173379) (xy 1.023835 -216.200546)
			(xy 1.01646 -216.230345) (xy 1.016 -216.245694) (xy 1.016 -228.271578) (xy 1.016492 -228.286921)
			(xy 1.023881 -228.316707) (xy 1.038164 -228.34387) (xy 1.048004 -228.355652) (xy 1.065976 -228.376695)
			(xy 1.09629 -228.422991) (xy 1.119599 -228.47318) (xy 1.135415 -228.52621) (xy 1.143407 -228.580967)
			(xy 1.143407 -228.636305) (xy 1.135415 -228.691062) (xy 1.119599 -228.744092) (xy 1.09629 -228.794281)
			(xy 1.065976 -228.840577) (xy 1.048004 -228.86162) (xy 1.03813 -228.873379) (xy 1.023835 -228.900546)
			(xy 1.01646 -228.930345) (xy 1.016 -228.945694) (xy 1.016 -229.16007) (xy 39.818564 -229.16007) (xy 39.819058 -229.102661)
			(xy 39.826902 -228.988113) (xy 39.842544 -228.874366) (xy 39.865911 -228.761952) (xy 39.896896 -228.651394)
			(xy 39.935352 -228.543209) (xy 39.981101 -228.4379) (xy 40.03393 -228.335958) (xy 40.093592 -228.237859)
			(xy 40.159809 -228.14406) (xy 40.232272 -228.054998) (xy 40.310645 -227.971089) (xy 40.39456 -227.892723)
			(xy 40.483627 -227.820266) (xy 40.577431 -227.754056) (xy 40.675535 -227.694402) (xy 40.777481 -227.641581)
			(xy 40.882793 -227.595839) (xy 40.990981 -227.557391) (xy 41.101541 -227.526415) (xy 41.213957 -227.503056)
			(xy 41.327705 -227.487423) (xy 41.442254 -227.479588) (xy 41.557072 -227.479588) (xy 41.671621 -227.487423)
			(xy 41.785369 -227.503056) (xy 41.897785 -227.526415) (xy 42.008345 -227.557391) (xy 42.116533 -227.595839)
			(xy 42.221845 -227.641581) (xy 42.323791 -227.694402) (xy 42.421895 -227.754056) (xy 42.515699 -227.820266)
			(xy 42.604766 -227.892723) (xy 42.688681 -227.971089) (xy 42.767054 -228.054998) (xy 42.839517 -228.14406)
			(xy 42.905734 -228.237859) (xy 42.965396 -228.335958) (xy 43.018225 -228.4379) (xy 43.063974 -228.543209)
			(xy 43.10243 -228.651394) (xy 43.133415 -228.761952) (xy 43.156782 -228.874366) (xy 43.172424 -228.988113)
			(xy 43.180268 -229.102661) (xy 43.180762 -229.16007) (xy 43.180576 -229.193253) (xy 43.177909 -229.259567)
			(xy 43.175428 -229.292658) (xy 43.170272 -229.350942) (xy 43.152948 -229.466671) (xy 43.127616 -229.580914)
			(xy 43.094401 -229.693119) (xy 43.053462 -229.802742) (xy 43.004999 -229.909253) (xy 42.949245 -230.012135)
			(xy 42.886471 -230.110891) (xy 42.816981 -230.205042) (xy 42.741111 -230.294132) (xy 42.659229 -230.377729)
			(xy 42.571732 -230.45543) (xy 42.500813 -230.51008) (xy 93.154506 -230.51008) (xy 93.158522 -230.39381)
			(xy 93.170549 -230.278095) (xy 93.190531 -230.163485) (xy 93.218373 -230.050526) (xy 93.253942 -229.939758)
			(xy 93.297068 -229.831707) (xy 93.347545 -229.726889) (xy 93.405134 -229.625804) (xy 93.46956 -229.528932)
			(xy 93.540515 -229.436736) (xy 93.617662 -229.349655) (xy 93.700633 -229.268104) (xy 93.789033 -229.192472)
			(xy 93.88244 -229.123118) (xy 93.980409 -229.060375) (xy 94.082473 -229.004539) (xy 94.188147 -228.955878)
			(xy 94.296926 -228.914624) (xy 94.408291 -228.880973) (xy 94.521714 -228.855085) (xy 94.636651 -228.837084)
			(xy 94.752557 -228.827055) (xy 94.868879 -228.825047) (xy 94.985062 -228.831069) (xy 95.100553 -228.845092)
			(xy 95.214801 -228.86705) (xy 95.327262 -228.896837) (xy 95.4374 -228.934312) (xy 95.54469 -228.979297)
			(xy 95.648621 -229.031576) (xy 95.748697 -229.090901) (xy 95.844443 -229.156989) (xy 95.9354 -229.229525)
			(xy 96.021136 -229.308164) (xy 96.101243 -229.39253) (xy 96.175339 -229.482222) (xy 96.243069 -229.576812)
			(xy 96.304113 -229.67585) (xy 96.358178 -229.778863) (xy 96.405008 -229.88536) (xy 96.444379 -229.994835)
			(xy 96.476103 -230.106765) (xy 96.500029 -230.220617) (xy 96.516043 -230.335849) (xy 96.52407 -230.451911)
			(xy 96.524572 -230.51008) (xy 96.52407 -230.568249) (xy 96.516043 -230.684311) (xy 96.500029 -230.799543)
			(xy 96.476103 -230.913395) (xy 96.444379 -231.025325) (xy 96.405008 -231.1348) (xy 96.358178 -231.241297)
			(xy 96.304113 -231.34431) (xy 96.243069 -231.443348) (xy 96.175339 -231.537938) (xy 96.101243 -231.62763)
			(xy 96.021136 -231.711996) (xy 95.9354 -231.790635) (xy 95.844443 -231.863171) (xy 95.748697 -231.929259)
			(xy 95.648621 -231.988584) (xy 95.54469 -232.040863) (xy 95.4374 -232.085848) (xy 95.327262 -232.123323)
			(xy 95.214801 -232.15311) (xy 95.100553 -232.175068) (xy 94.985062 -232.189091) (xy 94.868879 -232.195113)
			(xy 94.752557 -232.193105) (xy 94.636651 -232.183076) (xy 94.521714 -232.165075) (xy 94.408291 -232.139187)
			(xy 94.296926 -232.105536) (xy 94.188147 -232.064282) (xy 94.082473 -232.015621) (xy 93.980409 -231.959785)
			(xy 93.88244 -231.897042) (xy 93.789033 -231.827688) (xy 93.700633 -231.752056) (xy 93.617662 -231.670505)
			(xy 93.540515 -231.583424) (xy 93.46956 -231.491228) (xy 93.405134 -231.394356) (xy 93.347545 -231.293271)
			(xy 93.297068 -231.188453) (xy 93.253942 -231.080402) (xy 93.218373 -230.969634) (xy 93.190531 -230.856675)
			(xy 93.170549 -230.742065) (xy 93.158522 -230.62635) (xy 93.154506 -230.51008) (xy 42.500813 -230.51008)
			(xy 42.479042 -230.526857) (xy 42.381609 -230.591665) (xy 42.279905 -230.64954) (xy 42.174422 -230.700202)
			(xy 42.065671 -230.743404) (xy 41.954179 -230.778939) (xy 41.840485 -230.806634) (xy 41.725141 -230.826354)
			(xy 41.608704 -230.838005) (xy 41.491739 -230.84153) (xy 41.374812 -230.836912) (xy 41.258489 -230.824173)
			(xy 41.143334 -230.803375) (xy 41.029905 -230.774618) (xy 40.91875 -230.738042) (xy 40.810407 -230.693825)
			(xy 40.705403 -230.642179) (xy 40.604244 -230.583356) (xy 40.507421 -230.51764) (xy 40.415403 -230.445349)
			(xy 40.328636 -230.366834) (xy 40.247539 -230.282474) (xy 40.172506 -230.192679) (xy 40.103899 -230.097883)
			(xy 40.042051 -229.998544) (xy 39.987262 -229.895145) (xy 39.939796 -229.788186) (xy 39.899884 -229.678185)
			(xy 39.86772 -229.565674) (xy 39.843457 -229.451199) (xy 39.827215 -229.335313) (xy 39.819072 -229.218579)
			(xy 39.818564 -229.16007) (xy 1.016 -229.16007) (xy 1.016 -240.971578) (xy 1.016492 -240.986921)
			(xy 1.023881 -241.016707) (xy 1.038164 -241.04387) (xy 1.048004 -241.055652) (xy 1.065976 -241.076695)
			(xy 1.09629 -241.122991) (xy 1.119599 -241.17318) (xy 1.135415 -241.22621) (xy 1.143407 -241.280967)
			(xy 1.143407 -241.336305) (xy 1.135415 -241.391062) (xy 1.119599 -241.444092) (xy 1.09629 -241.494281)
			(xy 1.065976 -241.540577) (xy 1.048004 -241.56162) (xy 1.03813 -241.573379) (xy 1.023835 -241.600546)
			(xy 1.01646 -241.630345) (xy 1.016 -241.645694) (xy 1.016 -242.26012) (xy 86.877404 -242.26012) (xy 86.881424 -242.069469)
			(xy 86.893478 -241.879156) (xy 86.913544 -241.689521) (xy 86.941587 -241.5009) (xy 86.977556 -241.31363)
			(xy 87.021388 -241.128042) (xy 87.073005 -240.944467) (xy 87.132315 -240.763231) (xy 87.199213 -240.584656)
			(xy 87.273579 -240.409061) (xy 87.355281 -240.236756) (xy 87.444175 -240.068049) (xy 87.540101 -239.903239)
			(xy 87.64289 -239.74262) (xy 87.752359 -239.586477) (xy 87.868313 -239.435088) (xy 87.990547 -239.288721)
			(xy 88.118841 -239.147637) (xy 88.252969 -239.012088) (xy 88.392693 -238.882313) (xy 88.537763 -238.758543)
			(xy 88.687921 -238.641) (xy 88.842902 -238.529891) (xy 89.002429 -238.425414) (xy 89.166218 -238.327755)
			(xy 89.333978 -238.237088) (xy 89.505412 -238.153574) (xy 89.680214 -238.077361) (xy 89.858073 -238.008585)
			(xy 90.038674 -237.947367) (xy 90.221694 -237.893818) (xy 90.40681 -237.848032) (xy 90.593691 -237.81009)
			(xy 90.782006 -237.780061) (xy 90.971419 -237.757996) (xy 91.161593 -237.743937) (xy 91.352192 -237.737907)
			(xy 91.542875 -237.739917) (xy 91.733304 -237.749964) (xy 91.92314 -237.76803) (xy 92.112046 -237.794083)
			(xy 92.299685 -237.828076) (xy 92.485725 -237.869949) (xy 92.669834 -237.919628) (xy 92.851685 -237.977024)
			(xy 93.030955 -238.042035) (xy 93.207325 -238.114546) (xy 93.380481 -238.194427) (xy 93.550116 -238.281537)
			(xy 93.715928 -238.375721) (xy 93.877622 -238.476812) (xy 94.03491 -238.584628) (xy 94.187513 -238.69898)
			(xy 94.335161 -238.819663) (xy 94.477589 -238.946464) (xy 94.614545 -239.079155) (xy 94.745786 -239.217503)
			(xy 94.871078 -239.36126) (xy 94.990198 -239.510171) (xy 95.102934 -239.663972) (xy 95.209087 -239.822388)
			(xy 95.308467 -239.985139) (xy 95.400897 -240.151934) (xy 95.486214 -240.322478) (xy 95.564266 -240.496466)
			(xy 95.634913 -240.673591) (xy 95.698031 -240.853536) (xy 95.753507 -241.035982) (xy 95.801242 -241.220605)
			(xy 95.841152 -241.407075) (xy 95.873165 -241.595063) (xy 95.897225 -241.784233) (xy 95.913288 -241.974249)
			(xy 95.921327 -242.164773) (xy 95.92183 -242.26012) (xy 95.921327 -242.355467) (xy 95.913288 -242.545991)
			(xy 95.897225 -242.736007) (xy 95.873165 -242.925177) (xy 95.841152 -243.113165) (xy 95.801242 -243.299635)
			(xy 95.753507 -243.484258) (xy 95.698031 -243.666704) (xy 95.634913 -243.846649) (xy 95.564266 -244.023774)
			(xy 95.486214 -244.197762) (xy 95.400897 -244.368306) (xy 95.308467 -244.535101) (xy 95.209087 -244.697852)
			(xy 95.102934 -244.856268) (xy 94.990198 -245.010069) (xy 94.871078 -245.15898) (xy 94.745786 -245.302737)
			(xy 94.614545 -245.441085) (xy 94.477589 -245.573776) (xy 94.335161 -245.700577) (xy 94.187513 -245.82126)
			(xy 94.03491 -245.935612) (xy 93.877622 -246.043428) (xy 93.715928 -246.144519) (xy 93.550116 -246.238703)
			(xy 93.380481 -246.325813) (xy 93.207325 -246.405694) (xy 93.030955 -246.478205) (xy 92.851685 -246.543216)
			(xy 92.669834 -246.600612) (xy 92.485725 -246.650291) (xy 92.299685 -246.692164) (xy 92.112046 -246.726157)
			(xy 91.92314 -246.75221) (xy 91.733304 -246.770276) (xy 91.542875 -246.780323) (xy 91.352192 -246.782333)
			(xy 91.161593 -246.776303) (xy 90.971419 -246.762244) (xy 90.782006 -246.740179) (xy 90.593691 -246.71015)
			(xy 90.40681 -246.672208) (xy 90.221694 -246.626422) (xy 90.038674 -246.572873) (xy 89.858073 -246.511655)
			(xy 89.680214 -246.442879) (xy 89.505412 -246.366666) (xy 89.333978 -246.283152) (xy 89.166218 -246.192485)
			(xy 89.002429 -246.094826) (xy 88.842902 -245.990349) (xy 88.687921 -245.87924) (xy 88.537763 -245.761697)
			(xy 88.392693 -245.637927) (xy 88.252969 -245.508152) (xy 88.118841 -245.372603) (xy 87.990547 -245.231519)
			(xy 87.868313 -245.085152) (xy 87.752359 -244.933763) (xy 87.64289 -244.77762) (xy 87.540101 -244.617001)
			(xy 87.444175 -244.452191) (xy 87.355281 -244.283484) (xy 87.273579 -244.111179) (xy 87.199213 -243.935584)
			(xy 87.132315 -243.757009) (xy 87.073005 -243.575773) (xy 87.021388 -243.392198) (xy 86.977556 -243.20661)
			(xy 86.941587 -243.01934) (xy 86.913544 -242.830719) (xy 86.893478 -242.641084) (xy 86.881424 -242.450771)
			(xy 86.877404 -242.26012) (xy 1.016 -242.26012) (xy 1.016 -250.020582) (xy 3.582162 -250.020582)
			(xy 3.582653 -249.963338) (xy 3.590754 -249.849137) (xy 3.606915 -249.735795) (xy 3.631055 -249.623881)
			(xy 3.663052 -249.513955) (xy 3.702747 -249.406568) (xy 3.74994 -249.302259) (xy 3.804394 -249.20155)
			(xy 3.865837 -249.104947) (xy 3.933962 -249.012932) (xy 4.008425 -248.925969) (xy 4.088855 -248.844491)
			(xy 4.174848 -248.768908) (xy 4.265973 -248.699599) (xy 4.361773 -248.636911) (xy 4.461769 -248.581157)
			(xy 4.565458 -248.532619) (xy 4.672322 -248.491538) (xy 4.781825 -248.458121) (xy 4.893417 -248.432535)
			(xy 5.006541 -248.414908) (xy 5.120627 -248.405329) (xy 5.235106 -248.403846) (xy 5.349402 -248.410467)
			(xy 5.462944 -248.425157) (xy 5.575162 -248.447844) (xy 5.685494 -248.478413) (xy 5.793386 -248.516712)
			(xy 5.898298 -248.562549) (xy 5.999704 -248.615693) (xy 6.097096 -248.675879) (xy 6.189986 -248.742805)
			(xy 6.277908 -248.816135) (xy 6.360421 -248.895501) (xy 6.437112 -248.980507) (xy 6.507597 -249.070726)
			(xy 6.571522 -249.165706) (xy 6.628567 -249.26497) (xy 6.678446 -249.368022) (xy 6.720909 -249.474344)
			(xy 6.755743 -249.583404) (xy 6.782773 -249.694656) (xy 6.801865 -249.807541) (xy 6.812922 -249.921494)
			(xy 6.815888 -250.035944) (xy 6.81075 -250.150316) (xy 6.797533 -250.264039) (xy 6.776303 -250.376542)
			(xy 6.747166 -250.48726) (xy 6.710269 -250.59564) (xy 6.665797 -250.701137) (xy 6.613971 -250.803224)
			(xy 6.555053 -250.901388) (xy 6.489337 -250.995137) (xy 6.453632 -251.039884) (xy 6.059424 -251.039884)
			(xy 6.020367 -251.072253) (xy 5.938107 -251.131626) (xy 5.895086 -251.158502) (xy 5.881509 -251.167452)
			(xy 5.858992 -251.190897) (xy 5.843109 -251.219259) (xy 5.834884 -251.250707) (xy 5.83438 -251.26696)
			(xy 5.83438 -251.50699) (xy 5.834126 -251.50699) (xy 5.779452 -251.529781) (xy 5.667407 -251.568246)
			(xy 5.552848 -251.598407) (xy 5.436387 -251.620101) (xy 5.318652 -251.633212) (xy 5.200272 -251.637669)
			(xy 5.081884 -251.633449) (xy 4.964122 -251.620575) (xy 4.847619 -251.599114) (xy 4.732999 -251.569183)
			(xy 4.620877 -251.530943) (xy 4.566158 -251.50826) (xy 4.565904 -251.50826) (xy 4.565904 -251.26823)
			(xy 4.56544 -251.25195) (xy 4.557181 -251.220454) (xy 4.541219 -251.192074) (xy 4.518594 -251.168658)
			(xy 4.504944 -251.159772) (xy 4.45885 -251.131059) (xy 4.370982 -251.067228) (xy 4.32943 -251.032264)
			(xy 3.937762 -251.032264) (xy 3.903919 -250.989342) (xy 3.841441 -250.89964) (xy 3.785164 -250.805923)
			(xy 3.735346 -250.708619) (xy 3.692214 -250.608172) (xy 3.655964 -250.505042) (xy 3.626762 -250.399698)
			(xy 3.604742 -250.292623) (xy 3.590005 -250.184306) (xy 3.582617 -250.07524) (xy 3.582162 -250.020582)
			(xy 1.016 -250.020582) (xy 1.016 -253.671578) (xy 1.016492 -253.686921) (xy 1.023881 -253.716707)
			(xy 1.038164 -253.74387) (xy 1.048004 -253.755652) (xy 1.065976 -253.776695) (xy 1.09629 -253.822991)
			(xy 1.119599 -253.87318) (xy 1.135415 -253.92621) (xy 1.143407 -253.980967) (xy 1.143407 -254.036305)
			(xy 1.135415 -254.091062) (xy 1.119599 -254.144092) (xy 1.09629 -254.194281) (xy 1.065976 -254.240577)
			(xy 1.048004 -254.26162) (xy 1.03813 -254.273379) (xy 1.023835 -254.300546) (xy 1.01646 -254.330345)
			(xy 1.016 -254.345694) (xy 1.016 -266.371578) (xy 1.016492 -266.386921) (xy 1.023881 -266.416707)
			(xy 1.038164 -266.44387) (xy 1.048004 -266.455652) (xy 1.065976 -266.476695) (xy 1.09629 -266.522991)
			(xy 1.119599 -266.57318) (xy 1.135415 -266.62621) (xy 1.143407 -266.680967) (xy 1.143407 -266.736305)
			(xy 1.135415 -266.791062) (xy 1.119599 -266.844092) (xy 1.09629 -266.894281) (xy 1.065976 -266.940577)
			(xy 1.048004 -266.96162) (xy 1.03813 -266.973379) (xy 1.023835 -267.000546) (xy 1.01646 -267.030345)
			(xy 1.016 -267.045694) (xy 1.016 -267.850739) (xy 3.584556 -267.850739) (xy 3.589879 -267.737285)
			(xy 3.603163 -267.624485) (xy 3.624341 -267.512897) (xy 3.653308 -267.403074) (xy 3.689922 -267.295558)
			(xy 3.734001 -267.190881) (xy 3.785327 -267.08956) (xy 3.843647 -266.992097) (xy 3.908672 -266.898974)
			(xy 3.980081 -266.81065) (xy 4.05752 -266.727563) (xy 4.140607 -266.650124) (xy 4.228931 -266.578715)
			(xy 4.322054 -266.51369) (xy 4.419517 -266.455369) (xy 4.520837 -266.404043) (xy 4.625514 -266.359963)
			(xy 4.73303 -266.323349) (xy 4.842854 -266.294382) (xy 4.954441 -266.273204) (xy 5.067241 -266.25992)
			(xy 5.180695 -266.254596) (xy 5.294243 -266.257258) (xy 5.407324 -266.267894) (xy 5.519377 -266.28645)
			(xy 5.629849 -266.312835) (xy 5.738194 -266.346919) (xy 5.843876 -266.388532) (xy 5.946371 -266.437469)
			(xy 6.045175 -266.493488) (xy 6.139797 -266.556312) (xy 6.229771 -266.625631) (xy 6.31465 -266.701101)
			(xy 6.394016 -266.78235) (xy 6.467475 -266.868975) (xy 6.534666 -266.960549) (xy 6.595255 -267.056618)
			(xy 6.648942 -267.156707) (xy 6.695463 -267.260322) (xy 6.734588 -267.36695) (xy 6.766122 -267.476064)
			(xy 6.78991 -267.587124) (xy 6.805834 -267.699582) (xy 6.813816 -267.81288) (xy 6.814312 -267.86967)
			(xy 6.813806 -267.92732) (xy 6.805599 -268.042327) (xy 6.789208 -268.156456) (xy 6.764716 -268.269125)
			(xy 6.73225 -268.37976) (xy 6.691973 -268.487796) (xy 6.644093 -268.592684) (xy 6.588851 -268.693889)
			(xy 6.52653 -268.790895) (xy 6.457448 -268.883208) (xy 6.381956 -268.970358) (xy 6.30044 -269.0519)
			(xy 6.213314 -269.127419) (xy 6.121023 -269.196531) (xy 6.024036 -269.258882) (xy 5.922848 -269.314155)
			(xy 5.817976 -269.362069) (xy 5.709952 -269.402379) (xy 5.599327 -269.434881) (xy 5.486666 -269.459407)
			(xy 5.372543 -269.475834) (xy 5.257538 -269.484078) (xy 5.199888 -269.484602) (xy 5.199634 -269.484602)
			(xy 5.199634 -269.484348) (xy 5.142844 -269.483856) (xy 5.029546 -269.475875) (xy 4.917088 -269.459951)
			(xy 4.806028 -269.436163) (xy 4.696914 -269.404629) (xy 4.590286 -269.365505) (xy 4.486671 -269.318984)
			(xy 4.386581 -269.265297) (xy 4.290512 -269.204708) (xy 4.198938 -269.137518) (xy 4.112313 -269.064058)
			(xy 4.031064 -268.984693) (xy 3.955594 -268.899814) (xy 3.886275 -268.80984) (xy 3.82345 -268.715218)
			(xy 3.767431 -268.616415) (xy 3.718493 -268.513919) (xy 3.67688 -268.408238) (xy 3.642796 -268.299893)
			(xy 3.616411 -268.189421) (xy 3.597855 -268.077368) (xy 3.587219 -267.964287) (xy 3.584556 -267.850739)
			(xy 1.016 -267.850739) (xy 1.016 -273.61007) (xy 39.818564 -273.61007) (xy 39.819058 -273.552661)
			(xy 39.826902 -273.438113) (xy 39.842544 -273.324366) (xy 39.865911 -273.211952) (xy 39.896896 -273.101394)
			(xy 39.935352 -272.993209) (xy 39.981101 -272.8879) (xy 40.03393 -272.785958) (xy 40.093592 -272.687859)
			(xy 40.159809 -272.59406) (xy 40.232272 -272.504998) (xy 40.310645 -272.421089) (xy 40.39456 -272.342723)
			(xy 40.483627 -272.270266) (xy 40.577431 -272.204056) (xy 40.675535 -272.144402) (xy 40.777481 -272.091581)
			(xy 40.882793 -272.045839) (xy 40.990981 -272.007391) (xy 41.101541 -271.976415) (xy 41.213957 -271.953056)
			(xy 41.327705 -271.937423) (xy 41.442254 -271.929588) (xy 41.557072 -271.929588) (xy 41.671621 -271.937423)
			(xy 41.785369 -271.953056) (xy 41.897785 -271.976415) (xy 42.008345 -272.007391) (xy 42.116533 -272.045839)
			(xy 42.221845 -272.091581) (xy 42.323791 -272.144402) (xy 42.421895 -272.204056) (xy 42.515699 -272.270266)
			(xy 42.604766 -272.342723) (xy 42.688681 -272.421089) (xy 42.767054 -272.504998) (xy 42.839517 -272.59406)
			(xy 42.905734 -272.687859) (xy 42.965396 -272.785958) (xy 43.018225 -272.8879) (xy 43.063974 -272.993209)
			(xy 43.10243 -273.101394) (xy 43.133415 -273.211952) (xy 43.156782 -273.324366) (xy 43.172424 -273.438113)
			(xy 43.180268 -273.552661) (xy 43.180762 -273.61007) (xy 43.180576 -273.643253) (xy 43.177909 -273.709567)
			(xy 43.175428 -273.742658) (xy 43.170272 -273.800942) (xy 43.152948 -273.916671) (xy 43.127616 -274.030914)
			(xy 43.094401 -274.143119) (xy 43.053462 -274.252742) (xy 43.004999 -274.359253) (xy 42.949245 -274.462135)
			(xy 42.886471 -274.560891) (xy 42.816981 -274.655042) (xy 42.741111 -274.744132) (xy 42.659229 -274.827729)
			(xy 42.571732 -274.90543) (xy 42.500813 -274.96008) (xy 93.154506 -274.96008) (xy 93.158522 -274.84381)
			(xy 93.170549 -274.728095) (xy 93.190531 -274.613485) (xy 93.218373 -274.500526) (xy 93.253942 -274.389758)
			(xy 93.297068 -274.281707) (xy 93.347545 -274.176889) (xy 93.405134 -274.075804) (xy 93.46956 -273.978932)
			(xy 93.540515 -273.886736) (xy 93.617662 -273.799655) (xy 93.700633 -273.718104) (xy 93.789033 -273.642472)
			(xy 93.88244 -273.573118) (xy 93.980409 -273.510375) (xy 94.082473 -273.454539) (xy 94.188147 -273.405878)
			(xy 94.296926 -273.364624) (xy 94.408291 -273.330973) (xy 94.521714 -273.305085) (xy 94.636651 -273.287084)
			(xy 94.752557 -273.277055) (xy 94.868879 -273.275047) (xy 94.985062 -273.281069) (xy 95.100553 -273.295092)
			(xy 95.214801 -273.31705) (xy 95.327262 -273.346837) (xy 95.4374 -273.384312) (xy 95.54469 -273.429297)
			(xy 95.648621 -273.481576) (xy 95.748697 -273.540901) (xy 95.844443 -273.606989) (xy 95.9354 -273.679525)
			(xy 96.021136 -273.758164) (xy 96.101243 -273.84253) (xy 96.175339 -273.932222) (xy 96.243069 -274.026812)
			(xy 96.304113 -274.12585) (xy 96.358178 -274.228863) (xy 96.405008 -274.33536) (xy 96.444379 -274.444835)
			(xy 96.476103 -274.556765) (xy 96.500029 -274.670617) (xy 96.516043 -274.785849) (xy 96.52407 -274.901911)
			(xy 96.524572 -274.96008) (xy 96.52407 -275.018249) (xy 96.516043 -275.134311) (xy 96.500029 -275.249543)
			(xy 96.476103 -275.363395) (xy 96.444379 -275.475325) (xy 96.405008 -275.5848) (xy 96.358178 -275.691297)
			(xy 96.304113 -275.79431) (xy 96.243069 -275.893348) (xy 96.175339 -275.987938) (xy 96.101243 -276.07763)
			(xy 96.021136 -276.161996) (xy 95.9354 -276.240635) (xy 95.844443 -276.313171) (xy 95.748697 -276.379259)
			(xy 95.648621 -276.438584) (xy 95.54469 -276.490863) (xy 95.4374 -276.535848) (xy 95.327262 -276.573323)
			(xy 95.214801 -276.60311) (xy 95.100553 -276.625068) (xy 94.985062 -276.639091) (xy 94.868879 -276.645113)
			(xy 94.752557 -276.643105) (xy 94.636651 -276.633076) (xy 94.521714 -276.615075) (xy 94.408291 -276.589187)
			(xy 94.296926 -276.555536) (xy 94.188147 -276.514282) (xy 94.082473 -276.465621) (xy 93.980409 -276.409785)
			(xy 93.88244 -276.347042) (xy 93.789033 -276.277688) (xy 93.700633 -276.202056) (xy 93.617662 -276.120505)
			(xy 93.540515 -276.033424) (xy 93.46956 -275.941228) (xy 93.405134 -275.844356) (xy 93.347545 -275.743271)
			(xy 93.297068 -275.638453) (xy 93.253942 -275.530402) (xy 93.218373 -275.419634) (xy 93.190531 -275.306675)
			(xy 93.170549 -275.192065) (xy 93.158522 -275.07635) (xy 93.154506 -274.96008) (xy 42.500813 -274.96008)
			(xy 42.479042 -274.976857) (xy 42.381609 -275.041665) (xy 42.279905 -275.09954) (xy 42.174422 -275.150202)
			(xy 42.065671 -275.193404) (xy 41.954179 -275.228939) (xy 41.840485 -275.256634) (xy 41.725141 -275.276354)
			(xy 41.608704 -275.288005) (xy 41.491739 -275.29153) (xy 41.374812 -275.286912) (xy 41.258489 -275.274173)
			(xy 41.143334 -275.253375) (xy 41.029905 -275.224618) (xy 40.91875 -275.188042) (xy 40.810407 -275.143825)
			(xy 40.705403 -275.092179) (xy 40.604244 -275.033356) (xy 40.507421 -274.96764) (xy 40.415403 -274.895349)
			(xy 40.328636 -274.816834) (xy 40.247539 -274.732474) (xy 40.172506 -274.642679) (xy 40.103899 -274.547883)
			(xy 40.042051 -274.448544) (xy 39.987262 -274.345145) (xy 39.939796 -274.238186) (xy 39.899884 -274.128185)
			(xy 39.86772 -274.015674) (xy 39.843457 -273.901199) (xy 39.827215 -273.785313) (xy 39.819072 -273.668579)
			(xy 39.818564 -273.61007) (xy 1.016 -273.61007) (xy 1.016 -279.071578) (xy 1.016492 -279.086921)
			(xy 1.023881 -279.116707) (xy 1.038164 -279.14387) (xy 1.048004 -279.155652) (xy 1.065976 -279.176695)
			(xy 1.09629 -279.222991) (xy 1.119599 -279.27318) (xy 1.135415 -279.32621) (xy 1.143407 -279.380967)
			(xy 1.143407 -279.436305) (xy 1.135415 -279.491062) (xy 1.119599 -279.544092) (xy 1.09629 -279.594281)
			(xy 1.065976 -279.640577) (xy 1.048004 -279.66162) (xy 1.03813 -279.673379) (xy 1.023835 -279.700546)
			(xy 1.01646 -279.730345) (xy 1.016 -279.745694) (xy 1.016 -286.709866) (xy 86.877404 -286.709866)
			(xy 86.881424 -286.519215) (xy 86.893478 -286.328902) (xy 86.913544 -286.139267) (xy 86.941587 -285.950646)
			(xy 86.977556 -285.763376) (xy 87.021388 -285.577788) (xy 87.073005 -285.394213) (xy 87.132315 -285.212977)
			(xy 87.199213 -285.034402) (xy 87.273579 -284.858807) (xy 87.355281 -284.686502) (xy 87.444175 -284.517795)
			(xy 87.540101 -284.352985) (xy 87.64289 -284.192366) (xy 87.752359 -284.036223) (xy 87.868313 -283.884834)
			(xy 87.990547 -283.738467) (xy 88.118841 -283.597383) (xy 88.252969 -283.461834) (xy 88.392693 -283.332059)
			(xy 88.537763 -283.208289) (xy 88.687921 -283.090746) (xy 88.842902 -282.979637) (xy 89.002429 -282.87516)
			(xy 89.166218 -282.777501) (xy 89.333978 -282.686834) (xy 89.505412 -282.60332) (xy 89.680214 -282.527107)
			(xy 89.858073 -282.458331) (xy 90.038674 -282.397113) (xy 90.221694 -282.343564) (xy 90.40681 -282.297778)
			(xy 90.593691 -282.259836) (xy 90.782006 -282.229807) (xy 90.971419 -282.207742) (xy 91.161593 -282.193683)
			(xy 91.352192 -282.187653) (xy 91.542875 -282.189663) (xy 91.733304 -282.19971) (xy 91.92314 -282.217776)
			(xy 92.112046 -282.243829) (xy 92.299685 -282.277822) (xy 92.485725 -282.319695) (xy 92.669834 -282.369374)
			(xy 92.851685 -282.42677) (xy 93.030955 -282.491781) (xy 93.207325 -282.564292) (xy 93.380481 -282.644173)
			(xy 93.550116 -282.731283) (xy 93.715928 -282.825467) (xy 93.877622 -282.926558) (xy 94.03491 -283.034374)
			(xy 94.187513 -283.148726) (xy 94.335161 -283.269409) (xy 94.477589 -283.39621) (xy 94.614545 -283.528901)
			(xy 94.745786 -283.667249) (xy 94.871078 -283.811006) (xy 94.990198 -283.959917) (xy 95.102934 -284.113718)
			(xy 95.209087 -284.272134) (xy 95.308467 -284.434885) (xy 95.400897 -284.60168) (xy 95.486214 -284.772224)
			(xy 95.564266 -284.946212) (xy 95.634913 -285.123337) (xy 95.698031 -285.303282) (xy 95.753507 -285.485728)
			(xy 95.801242 -285.670351) (xy 95.841152 -285.856821) (xy 95.873165 -286.044809) (xy 95.897225 -286.233979)
			(xy 95.913288 -286.423995) (xy 95.921327 -286.614519) (xy 95.92183 -286.709866) (xy 95.921327 -286.805213)
			(xy 95.913288 -286.995737) (xy 95.897225 -287.185753) (xy 95.873165 -287.374923) (xy 95.841152 -287.562911)
			(xy 95.801242 -287.749381) (xy 95.753507 -287.934004) (xy 95.698031 -288.11645) (xy 95.634913 -288.296395)
			(xy 95.564266 -288.47352) (xy 95.486214 -288.647508) (xy 95.400897 -288.818052) (xy 95.308467 -288.984847)
			(xy 95.209087 -289.147598) (xy 95.102934 -289.306014) (xy 94.990198 -289.459815) (xy 94.871078 -289.608726)
			(xy 94.745786 -289.752483) (xy 94.614545 -289.890831) (xy 94.477589 -290.023522) (xy 94.335161 -290.150323)
			(xy 94.187513 -290.271006) (xy 94.03491 -290.385358) (xy 93.877622 -290.493174) (xy 93.715928 -290.594265)
			(xy 93.550116 -290.688449) (xy 93.380481 -290.775559) (xy 93.207325 -290.85544) (xy 93.030955 -290.927951)
			(xy 92.851685 -290.992962) (xy 92.669834 -291.050358) (xy 92.485725 -291.100037) (xy 92.299685 -291.14191)
			(xy 92.112046 -291.175903) (xy 91.92314 -291.201956) (xy 91.733304 -291.220022) (xy 91.542875 -291.230069)
			(xy 91.352192 -291.232079) (xy 91.161593 -291.226049) (xy 90.971419 -291.21199) (xy 90.782006 -291.189925)
			(xy 90.593691 -291.159896) (xy 90.40681 -291.121954) (xy 90.221694 -291.076168) (xy 90.038674 -291.022619)
			(xy 89.858073 -290.961401) (xy 89.680214 -290.892625) (xy 89.505412 -290.816412) (xy 89.333978 -290.732898)
			(xy 89.166218 -290.642231) (xy 89.002429 -290.544572) (xy 88.842902 -290.440095) (xy 88.687921 -290.328986)
			(xy 88.537763 -290.211443) (xy 88.392693 -290.087673) (xy 88.252969 -289.957898) (xy 88.118841 -289.822349)
			(xy 87.990547 -289.681265) (xy 87.868313 -289.534898) (xy 87.752359 -289.383509) (xy 87.64289 -289.227366)
			(xy 87.540101 -289.066747) (xy 87.444175 -288.901937) (xy 87.355281 -288.73323) (xy 87.273579 -288.560925)
			(xy 87.199213 -288.38533) (xy 87.132315 -288.206755) (xy 87.073005 -288.025519) (xy 87.021388 -287.841944)
			(xy 86.977556 -287.656356) (xy 86.941587 -287.469086) (xy 86.913544 -287.280465) (xy 86.893478 -287.09083)
			(xy 86.881424 -286.900517) (xy 86.877404 -286.709866) (xy 1.016 -286.709866) (xy 1.016 -291.771578)
			(xy 1.016492 -291.786921) (xy 1.023881 -291.816707) (xy 1.038164 -291.84387) (xy 1.048004 -291.855652)
			(xy 1.065976 -291.876695) (xy 1.09629 -291.922991) (xy 1.119599 -291.97318) (xy 1.135415 -292.02621)
			(xy 1.143407 -292.080967) (xy 1.143407 -292.136305) (xy 1.135415 -292.191062) (xy 1.119599 -292.244092)
			(xy 1.09629 -292.294281) (xy 1.065976 -292.340577) (xy 1.048004 -292.36162) (xy 1.03813 -292.373379)
			(xy 1.023835 -292.400546) (xy 1.01646 -292.430345) (xy 1.016 -292.445694) (xy 1.016 -295.89984) (xy 11.343648 -295.89984)
			(xy 11.34765 -295.694761) (xy 11.35965 -295.489994) (xy 11.379631 -295.285852) (xy 11.407561 -295.082644)
			(xy 11.443398 -294.880681) (xy 11.487088 -294.68027) (xy 11.538564 -294.481716) (xy 11.597748 -294.285321)
			(xy 11.664549 -294.091386) (xy 11.738865 -293.900204) (xy 11.820585 -293.712067) (xy 11.909582 -293.527262)
			(xy 12.005722 -293.34607) (xy 12.108858 -293.168767) (xy 12.218834 -292.995623) (xy 12.335481 -292.826902)
			(xy 12.458622 -292.66286) (xy 12.588069 -292.503748) (xy 12.723626 -292.349807) (xy 12.865086 -292.201272)
			(xy 13.012233 -292.05837) (xy 13.164844 -291.921318) (xy 13.322686 -291.790324) (xy 13.485519 -291.665588)
			(xy 13.653094 -291.547301) (xy 13.825157 -291.435641) (xy 14.001445 -291.33078) (xy 14.181691 -291.232877)
			(xy 14.365619 -291.142081) (xy 14.552949 -291.05853) (xy 14.743397 -290.982351) (xy 14.936671 -290.913662)
			(xy 15.132479 -290.852565) (xy 15.330521 -290.799154) (xy 15.530497 -290.753511) (xy 15.7321 -290.715705)
			(xy 15.935026 -290.685794) (xy 16.138964 -290.663822) (xy 16.343604 -290.649825) (xy 16.548634 -290.643822)
			(xy 16.753742 -290.645823) (xy 16.958616 -290.655825) (xy 17.162944 -290.673813) (xy 17.366415 -290.699759)
			(xy 17.568718 -290.733625) (xy 17.769546 -290.775357) (xy 17.968592 -290.824893) (xy 18.165555 -290.882158)
			(xy 18.360133 -290.947064) (xy 18.552031 -291.019512) (xy 18.740956 -291.099391) (xy 18.92662 -291.186582)
			(xy 19.108742 -291.280949) (xy 19.287042 -291.382351) (xy 19.461251 -291.490632) (xy 19.631103 -291.605627)
			(xy 19.796338 -291.727162) (xy 19.956706 -291.855051) (xy 20.111962 -291.989099) (xy 20.261869 -292.129103)
			(xy 20.406201 -292.274849) (xy 20.544735 -292.426116) (xy 20.677263 -292.582672) (xy 20.803581 -292.74428)
			(xy 20.923498 -292.910693) (xy 21.036831 -293.081659) (xy 21.143407 -293.256916) (xy 21.243064 -293.436197)
			(xy 21.33565 -293.619231) (xy 21.421025 -293.805737) (xy 21.499058 -293.995432) (xy 21.56963 -294.188028)
			(xy 21.632634 -294.38323) (xy 21.687974 -294.580742) (xy 21.735566 -294.780262) (xy 21.775337 -294.981488)
			(xy 21.807227 -295.184112) (xy 21.831187 -295.387825) (xy 21.847181 -295.592319) (xy 21.855184 -295.797281)
			(xy 21.855684 -295.89984) (xy 21.855184 -296.002399) (xy 21.847181 -296.207361) (xy 21.831187 -296.411855)
			(xy 21.807227 -296.615568) (xy 21.775337 -296.818192) (xy 21.735566 -297.019418) (xy 21.687974 -297.218938)
			(xy 21.632634 -297.41645) (xy 21.56963 -297.611652) (xy 21.499058 -297.804248) (xy 21.421025 -297.993943)
			(xy 21.33565 -298.180449) (xy 21.243064 -298.363483) (xy 21.143407 -298.542764) (xy 21.036831 -298.718021)
			(xy 20.923498 -298.888987) (xy 20.803581 -299.0554) (xy 20.677263 -299.217008) (xy 20.544735 -299.373564)
			(xy 20.406201 -299.524831) (xy 20.261869 -299.670577) (xy 20.111962 -299.810581) (xy 19.956706 -299.944629)
			(xy 19.796338 -300.072518) (xy 19.631103 -300.194053) (xy 19.461251 -300.309048) (xy 19.287042 -300.417329)
			(xy 19.108742 -300.518731) (xy 18.92662 -300.613098) (xy 18.740956 -300.700289) (xy 18.552031 -300.780168)
			(xy 18.360133 -300.852616) (xy 18.165555 -300.917522) (xy 17.968592 -300.974787) (xy 17.769546 -301.024323)
			(xy 17.568718 -301.066055) (xy 17.366415 -301.099921) (xy 17.162944 -301.125867) (xy 16.958616 -301.143855)
			(xy 16.753742 -301.153857) (xy 16.548634 -301.155858) (xy 16.343604 -301.149855) (xy 16.138964 -301.135858)
			(xy 15.935026 -301.113886) (xy 15.7321 -301.083975) (xy 15.530497 -301.046169) (xy 15.330521 -301.000526)
			(xy 15.132479 -300.947115) (xy 14.936671 -300.886018) (xy 14.743397 -300.817329) (xy 14.552949 -300.74115)
			(xy 14.365619 -300.657599) (xy 14.181691 -300.566803) (xy 14.001445 -300.4689) (xy 13.825157 -300.364039)
			(xy 13.653094 -300.252379) (xy 13.485519 -300.134092) (xy 13.322686 -300.009356) (xy 13.164844 -299.878362)
			(xy 13.012233 -299.74131) (xy 12.865086 -299.598408) (xy 12.723626 -299.449873) (xy 12.588069 -299.295932)
			(xy 12.458622 -299.13682) (xy 12.335481 -298.972778) (xy 12.218834 -298.804057) (xy 12.108858 -298.630913)
			(xy 12.005722 -298.45361) (xy 11.909582 -298.272418) (xy 11.820585 -298.087613) (xy 11.738865 -297.899476)
			(xy 11.664549 -297.708294) (xy 11.597748 -297.514359) (xy 11.538564 -297.317964) (xy 11.487088 -297.11941)
			(xy 11.443398 -296.918999) (xy 11.407561 -296.717036) (xy 11.379631 -296.513828) (xy 11.35965 -296.309686)
			(xy 11.34765 -296.104919) (xy 11.343648 -295.89984) (xy 1.016 -295.89984) (xy 1.016 -304.471578)
			(xy 1.016492 -304.486921) (xy 1.023881 -304.516707) (xy 1.038164 -304.54387) (xy 1.048004 -304.555652)
			(xy 1.065976 -304.576695) (xy 1.09629 -304.622991) (xy 1.119599 -304.67318) (xy 1.135415 -304.72621)
			(xy 1.143407 -304.780967) (xy 1.143407 -304.836305) (xy 1.135415 -304.891062) (xy 1.119599 -304.944092)
			(xy 1.09629 -304.994281) (xy 1.065976 -305.040577) (xy 1.048004 -305.06162) (xy 1.03813 -305.073379)
			(xy 1.023835 -305.100546) (xy 1.01646 -305.130345) (xy 1.016 -305.145694) (xy 1.016 -317.171578)
			(xy 1.016492 -317.186921) (xy 1.023881 -317.216707) (xy 1.038164 -317.24387) (xy 1.048004 -317.255652)
			(xy 1.065976 -317.276695) (xy 1.09629 -317.322991) (xy 1.119599 -317.37318) (xy 1.135415 -317.42621)
			(xy 1.143407 -317.480967) (xy 1.143407 -317.536305) (xy 1.135415 -317.591062) (xy 1.119599 -317.644092)
			(xy 1.09629 -317.694281) (xy 1.065976 -317.740577) (xy 1.048004 -317.76162) (xy 1.03813 -317.773379)
			(xy 1.023835 -317.800546) (xy 1.01646 -317.830345) (xy 1.016 -317.845694) (xy 1.016 -318.06007) (xy 39.818564 -318.06007)
			(xy 39.819058 -318.002661) (xy 39.826902 -317.888113) (xy 39.842544 -317.774366) (xy 39.865911 -317.661952)
			(xy 39.896896 -317.551394) (xy 39.935352 -317.443209) (xy 39.981101 -317.3379) (xy 40.03393 -317.235958)
			(xy 40.093592 -317.137859) (xy 40.159809 -317.04406) (xy 40.232272 -316.954998) (xy 40.310645 -316.871089)
			(xy 40.39456 -316.792723) (xy 40.483627 -316.720266) (xy 40.577431 -316.654056) (xy 40.675535 -316.594402)
			(xy 40.777481 -316.541581) (xy 40.882793 -316.495839) (xy 40.990981 -316.457391) (xy 41.101541 -316.426415)
			(xy 41.213957 -316.403056) (xy 41.327705 -316.387423) (xy 41.442254 -316.379588) (xy 41.557072 -316.379588)
			(xy 41.671621 -316.387423) (xy 41.785369 -316.403056) (xy 41.897785 -316.426415) (xy 42.008345 -316.457391)
			(xy 42.116533 -316.495839) (xy 42.221845 -316.541581) (xy 42.323791 -316.594402) (xy 42.421895 -316.654056)
			(xy 42.515699 -316.720266) (xy 42.604766 -316.792723) (xy 42.688681 -316.871089) (xy 42.767054 -316.954998)
			(xy 42.839517 -317.04406) (xy 42.905734 -317.137859) (xy 42.965396 -317.235958) (xy 43.018225 -317.3379)
			(xy 43.063974 -317.443209) (xy 43.10243 -317.551394) (xy 43.133415 -317.661952) (xy 43.156782 -317.774366)
			(xy 43.172424 -317.888113) (xy 43.180268 -318.002661) (xy 43.180762 -318.06007) (xy 43.180576 -318.093253)
			(xy 43.177909 -318.159567) (xy 43.175428 -318.192658) (xy 43.170272 -318.250942) (xy 43.152948 -318.366671)
			(xy 43.127616 -318.480914) (xy 43.094401 -318.593119) (xy 43.053462 -318.702742) (xy 43.004999 -318.809253)
			(xy 42.949245 -318.912135) (xy 42.886471 -319.010891) (xy 42.816981 -319.105042) (xy 42.741111 -319.194132)
			(xy 42.659229 -319.277729) (xy 42.571732 -319.35543) (xy 42.500813 -319.41008) (xy 93.154506 -319.41008)
			(xy 93.158522 -319.29381) (xy 93.170549 -319.178095) (xy 93.190531 -319.063485) (xy 93.218373 -318.950526)
			(xy 93.253942 -318.839758) (xy 93.297068 -318.731707) (xy 93.347545 -318.626889) (xy 93.405134 -318.525804)
			(xy 93.46956 -318.428932) (xy 93.540515 -318.336736) (xy 93.617662 -318.249655) (xy 93.700633 -318.168104)
			(xy 93.789033 -318.092472) (xy 93.88244 -318.023118) (xy 93.980409 -317.960375) (xy 94.082473 -317.904539)
			(xy 94.188147 -317.855878) (xy 94.296926 -317.814624) (xy 94.408291 -317.780973) (xy 94.521714 -317.755085)
			(xy 94.636651 -317.737084) (xy 94.752557 -317.727055) (xy 94.868879 -317.725047) (xy 94.985062 -317.731069)
			(xy 95.100553 -317.745092) (xy 95.214801 -317.76705) (xy 95.327262 -317.796837) (xy 95.4374 -317.834312)
			(xy 95.54469 -317.879297) (xy 95.648621 -317.931576) (xy 95.748697 -317.990901) (xy 95.844443 -318.056989)
			(xy 95.9354 -318.129525) (xy 96.021136 -318.208164) (xy 96.101243 -318.29253) (xy 96.175339 -318.382222)
			(xy 96.243069 -318.476812) (xy 96.304113 -318.57585) (xy 96.358178 -318.678863) (xy 96.405008 -318.78536)
			(xy 96.444379 -318.894835) (xy 96.476103 -319.006765) (xy 96.500029 -319.120617) (xy 96.516043 -319.235849)
			(xy 96.52407 -319.351911) (xy 96.524572 -319.41008) (xy 96.52407 -319.468249) (xy 96.516043 -319.584311)
			(xy 96.500029 -319.699543) (xy 96.476103 -319.813395) (xy 96.444379 -319.925325) (xy 96.405008 -320.0348)
			(xy 96.358178 -320.141297) (xy 96.304113 -320.24431) (xy 96.243069 -320.343348) (xy 96.175339 -320.437938)
			(xy 96.101243 -320.52763) (xy 96.021136 -320.611996) (xy 95.9354 -320.690635) (xy 95.844443 -320.763171)
			(xy 95.748697 -320.829259) (xy 95.648621 -320.888584) (xy 95.54469 -320.940863) (xy 95.4374 -320.985848)
			(xy 95.327262 -321.023323) (xy 95.214801 -321.05311) (xy 95.100553 -321.075068) (xy 94.985062 -321.089091)
			(xy 94.868879 -321.095113) (xy 94.752557 -321.093105) (xy 94.636651 -321.083076) (xy 94.521714 -321.065075)
			(xy 94.408291 -321.039187) (xy 94.296926 -321.005536) (xy 94.188147 -320.964282) (xy 94.082473 -320.915621)
			(xy 93.980409 -320.859785) (xy 93.88244 -320.797042) (xy 93.789033 -320.727688) (xy 93.700633 -320.652056)
			(xy 93.617662 -320.570505) (xy 93.540515 -320.483424) (xy 93.46956 -320.391228) (xy 93.405134 -320.294356)
			(xy 93.347545 -320.193271) (xy 93.297068 -320.088453) (xy 93.253942 -319.980402) (xy 93.218373 -319.869634)
			(xy 93.190531 -319.756675) (xy 93.170549 -319.642065) (xy 93.158522 -319.52635) (xy 93.154506 -319.41008)
			(xy 42.500813 -319.41008) (xy 42.479042 -319.426857) (xy 42.381609 -319.491665) (xy 42.279905 -319.54954)
			(xy 42.174422 -319.600202) (xy 42.065671 -319.643404) (xy 41.954179 -319.678939) (xy 41.840485 -319.706634)
			(xy 41.725141 -319.726354) (xy 41.608704 -319.738005) (xy 41.491739 -319.74153) (xy 41.374812 -319.736912)
			(xy 41.258489 -319.724173) (xy 41.143334 -319.703375) (xy 41.029905 -319.674618) (xy 40.91875 -319.638042)
			(xy 40.810407 -319.593825) (xy 40.705403 -319.542179) (xy 40.604244 -319.483356) (xy 40.507421 -319.41764)
			(xy 40.415403 -319.345349) (xy 40.328636 -319.266834) (xy 40.247539 -319.182474) (xy 40.172506 -319.092679)
			(xy 40.103899 -318.997883) (xy 40.042051 -318.898544) (xy 39.987262 -318.795145) (xy 39.939796 -318.688186)
			(xy 39.899884 -318.578185) (xy 39.86772 -318.465674) (xy 39.843457 -318.351199) (xy 39.827215 -318.235313)
			(xy 39.819072 -318.118579) (xy 39.818564 -318.06007) (xy 1.016 -318.06007) (xy 1.016 -329.871578)
			(xy 1.016492 -329.886921) (xy 1.023881 -329.916707) (xy 1.038164 -329.94387) (xy 1.048004 -329.955652)
			(xy 1.065976 -329.976695) (xy 1.09629 -330.022991) (xy 1.119599 -330.07318) (xy 1.135415 -330.12621)
			(xy 1.143407 -330.180967) (xy 1.143407 -330.236305) (xy 1.135415 -330.291062) (xy 1.119599 -330.344092)
			(xy 1.09629 -330.394281) (xy 1.065976 -330.440577) (xy 1.048004 -330.46162) (xy 1.03813 -330.473379)
			(xy 1.023835 -330.500546) (xy 1.01646 -330.530345) (xy 1.016 -330.545694) (xy 1.016 -331.16012) (xy 86.877404 -331.16012)
			(xy 86.881424 -330.969469) (xy 86.893478 -330.779156) (xy 86.913544 -330.589521) (xy 86.941587 -330.4009)
			(xy 86.977556 -330.21363) (xy 87.021388 -330.028042) (xy 87.073005 -329.844467) (xy 87.132315 -329.663231)
			(xy 87.199213 -329.484656) (xy 87.273579 -329.309061) (xy 87.355281 -329.136756) (xy 87.444175 -328.968049)
			(xy 87.540101 -328.803239) (xy 87.64289 -328.64262) (xy 87.752359 -328.486477) (xy 87.868313 -328.335088)
			(xy 87.990547 -328.188721) (xy 88.118841 -328.047637) (xy 88.252969 -327.912088) (xy 88.392693 -327.782313)
			(xy 88.537763 -327.658543) (xy 88.687921 -327.541) (xy 88.842902 -327.429891) (xy 89.002429 -327.325414)
			(xy 89.166218 -327.227755) (xy 89.333978 -327.137088) (xy 89.505412 -327.053574) (xy 89.680214 -326.977361)
			(xy 89.858073 -326.908585) (xy 90.038674 -326.847367) (xy 90.221694 -326.793818) (xy 90.40681 -326.748032)
			(xy 90.593691 -326.71009) (xy 90.782006 -326.680061) (xy 90.971419 -326.657996) (xy 91.161593 -326.643937)
			(xy 91.352192 -326.637907) (xy 91.542875 -326.639917) (xy 91.733304 -326.649964) (xy 91.92314 -326.66803)
			(xy 92.112046 -326.694083) (xy 92.299685 -326.728076) (xy 92.485725 -326.769949) (xy 92.669834 -326.819628)
			(xy 92.851685 -326.877024) (xy 93.030955 -326.942035) (xy 93.207325 -327.014546) (xy 93.380481 -327.094427)
			(xy 93.550116 -327.181537) (xy 93.715928 -327.275721) (xy 93.877622 -327.376812) (xy 94.03491 -327.484628)
			(xy 94.187513 -327.59898) (xy 94.335161 -327.719663) (xy 94.477589 -327.846464) (xy 94.614545 -327.979155)
			(xy 94.745786 -328.117503) (xy 94.871078 -328.26126) (xy 94.990198 -328.410171) (xy 95.102934 -328.563972)
			(xy 95.209087 -328.722388) (xy 95.308467 -328.885139) (xy 95.400897 -329.051934) (xy 95.486214 -329.222478)
			(xy 95.564266 -329.396466) (xy 95.634913 -329.573591) (xy 95.698031 -329.753536) (xy 95.753507 -329.935982)
			(xy 95.801242 -330.120605) (xy 95.841152 -330.307075) (xy 95.873165 -330.495063) (xy 95.897225 -330.684233)
			(xy 95.913288 -330.874249) (xy 95.921327 -331.064773) (xy 95.92183 -331.16012) (xy 95.921327 -331.255467)
			(xy 95.913288 -331.445991) (xy 95.897225 -331.636007) (xy 95.873165 -331.825177) (xy 95.841152 -332.013165)
			(xy 95.801242 -332.199635) (xy 95.753507 -332.384258) (xy 95.698031 -332.566704) (xy 95.634913 -332.746649)
			(xy 95.564266 -332.923774) (xy 95.486214 -333.097762) (xy 95.400897 -333.268306) (xy 95.308467 -333.435101)
			(xy 95.209087 -333.597852) (xy 95.102934 -333.756268) (xy 94.990198 -333.910069) (xy 94.871078 -334.05898)
			(xy 94.745786 -334.202737) (xy 94.614545 -334.341085) (xy 94.477589 -334.473776) (xy 94.335161 -334.600577)
			(xy 94.187513 -334.72126) (xy 94.03491 -334.835612) (xy 93.877622 -334.943428) (xy 93.715928 -335.044519)
			(xy 93.550116 -335.138703) (xy 93.380481 -335.225813) (xy 93.207325 -335.305694) (xy 93.030955 -335.378205)
			(xy 92.851685 -335.443216) (xy 92.669834 -335.500612) (xy 92.485725 -335.550291) (xy 92.299685 -335.592164)
			(xy 92.112046 -335.626157) (xy 91.92314 -335.65221) (xy 91.733304 -335.670276) (xy 91.542875 -335.680323)
			(xy 91.352192 -335.682333) (xy 91.161593 -335.676303) (xy 90.971419 -335.662244) (xy 90.782006 -335.640179)
			(xy 90.593691 -335.61015) (xy 90.40681 -335.572208) (xy 90.221694 -335.526422) (xy 90.038674 -335.472873)
			(xy 89.858073 -335.411655) (xy 89.680214 -335.342879) (xy 89.505412 -335.266666) (xy 89.333978 -335.183152)
			(xy 89.166218 -335.092485) (xy 89.002429 -334.994826) (xy 88.842902 -334.890349) (xy 88.687921 -334.77924)
			(xy 88.537763 -334.661697) (xy 88.392693 -334.537927) (xy 88.252969 -334.408152) (xy 88.118841 -334.272603)
			(xy 87.990547 -334.131519) (xy 87.868313 -333.985152) (xy 87.752359 -333.833763) (xy 87.64289 -333.67762)
			(xy 87.540101 -333.517001) (xy 87.444175 -333.352191) (xy 87.355281 -333.183484) (xy 87.273579 -333.011179)
			(xy 87.199213 -332.835584) (xy 87.132315 -332.657009) (xy 87.073005 -332.475773) (xy 87.021388 -332.292198)
			(xy 86.977556 -332.10661) (xy 86.941587 -331.91934) (xy 86.913544 -331.730719) (xy 86.893478 -331.541084)
			(xy 86.881424 -331.350771) (xy 86.877404 -331.16012) (xy 1.016 -331.16012) (xy 1.016 -341.019892)
			(xy 3.583178 -341.019892) (xy 3.583676 -340.962648) (xy 3.591778 -340.848447) (xy 3.607939 -340.735105)
			(xy 3.632078 -340.623191) (xy 3.664075 -340.513266) (xy 3.70377 -340.405879) (xy 3.750962 -340.30157)
			(xy 3.805417 -340.200862) (xy 3.86686 -340.104258) (xy 3.934984 -340.012244) (xy 4.009448 -339.92528)
			(xy 4.089877 -339.843803) (xy 4.17587 -339.76822) (xy 4.266995 -339.698911) (xy 4.362795 -339.636223)
			(xy 4.462791 -339.58047) (xy 4.56648 -339.531931) (xy 4.673344 -339.49085) (xy 4.782847 -339.457433)
			(xy 4.894439 -339.431847) (xy 5.007562 -339.414221) (xy 5.121648 -339.404642) (xy 5.236127 -339.40316)
			(xy 5.350423 -339.40978) (xy 5.463965 -339.42447) (xy 5.576183 -339.447157) (xy 5.686514 -339.477727)
			(xy 5.794406 -339.516026) (xy 5.899318 -339.561862) (xy 6.000724 -339.615007) (xy 6.098116 -339.675192)
			(xy 6.191005 -339.742118) (xy 6.278927 -339.815448) (xy 6.36144 -339.894815) (xy 6.438131 -339.97982)
			(xy 6.508616 -340.070039) (xy 6.57254 -340.165019) (xy 6.629585 -340.264283) (xy 6.679464 -340.367335)
			(xy 6.721926 -340.473657) (xy 6.75676 -340.582717) (xy 6.78379 -340.693968) (xy 6.802882 -340.806853)
			(xy 6.813939 -340.920806) (xy 6.816905 -341.035256) (xy 6.811767 -341.149628) (xy 6.800129 -341.249762)
			(xy 72.857112 -341.249762) (xy 72.861127 -341.04658) (xy 72.873166 -340.843715) (xy 72.89321 -340.641485)
			(xy 72.921228 -340.440204) (xy 72.957176 -340.240187) (xy 73.000998 -340.041746) (xy 73.052625 -339.845192)
			(xy 73.111977 -339.650831) (xy 73.178962 -339.458966) (xy 73.253474 -339.269897) (xy 73.335397 -339.08392)
			(xy 73.424604 -338.901324) (xy 73.520955 -338.722395) (xy 73.624299 -338.547413) (xy 73.734476 -338.37665)
			(xy 73.851313 -338.210372) (xy 73.974628 -338.048841) (xy 74.104228 -337.892307) (xy 74.239911 -337.741016)
			(xy 74.381466 -337.595203) (xy 74.52867 -337.455096) (xy 74.681294 -337.320914) (xy 74.839101 -337.192866)
			(xy 75.001843 -337.071153) (xy 75.169266 -336.955965) (xy 75.341109 -336.84748) (xy 75.517104 -336.745869)
			(xy 75.696976 -336.651291) (xy 75.880444 -336.563892) (xy 76.067222 -336.48381) (xy 76.257018 -336.41117)
			(xy 76.449535 -336.346084) (xy 76.644473 -336.288655) (xy 76.841528 -336.238972) (xy 77.040392 -336.197112)
			(xy 77.240754 -336.163142) (xy 77.442302 -336.137114) (xy 77.644721 -336.119069) (xy 77.847694 -336.109035)
			(xy 78.050906 -336.107027) (xy 78.254038 -336.113049) (xy 78.456774 -336.127092) (xy 78.658797 -336.149133)
			(xy 78.859791 -336.179138) (xy 79.059443 -336.21706) (xy 79.257441 -336.26284) (xy 79.453476 -336.316406)
			(xy 79.647241 -336.377676) (xy 79.838435 -336.446552) (xy 80.026758 -336.522929) (xy 80.211917 -336.606685)
			(xy 80.393623 -336.697692) (xy 80.571591 -336.795805) (xy 80.745544 -336.900874) (xy 80.915211 -337.012732)
			(xy 81.080325 -337.131206) (xy 81.240631 -337.256111) (xy 81.395877 -337.387251) (xy 81.54582 -337.524422)
			(xy 81.690228 -337.66741) (xy 81.828873 -337.815991) (xy 81.961541 -337.969934) (xy 82.088023 -338.128997)
			(xy 82.208123 -338.292934) (xy 82.321652 -338.461487) (xy 82.428433 -338.634394) (xy 82.5283 -338.811384)
			(xy 82.621097 -338.992181) (xy 82.706679 -339.176504) (xy 82.784912 -339.364063) (xy 82.855674 -339.554567)
			(xy 82.918855 -339.747718) (xy 82.974355 -339.943214) (xy 83.022089 -340.14075) (xy 83.061982 -340.340018)
			(xy 83.093971 -340.540706) (xy 83.118007 -340.742501) (xy 83.134052 -340.945088) (xy 83.14208 -341.148151)
			(xy 83.142582 -341.249762) (xy 83.14208 -341.351373) (xy 83.134052 -341.554436) (xy 83.118007 -341.757023)
			(xy 83.093971 -341.958818) (xy 83.061982 -342.159506) (xy 83.022089 -342.358774) (xy 82.974355 -342.55631)
			(xy 82.918855 -342.751806) (xy 82.855674 -342.944957) (xy 82.784912 -343.135461) (xy 82.706679 -343.32302)
			(xy 82.621097 -343.507343) (xy 82.5283 -343.68814) (xy 82.428433 -343.86513) (xy 82.321652 -344.038037)
			(xy 82.208123 -344.20659) (xy 82.088023 -344.370527) (xy 81.961541 -344.52959) (xy 81.828873 -344.683533)
			(xy 81.690228 -344.832114) (xy 81.54582 -344.975102) (xy 81.395877 -345.112273) (xy 81.240631 -345.243413)
			(xy 81.080325 -345.368318) (xy 80.915211 -345.486792) (xy 80.745544 -345.59865) (xy 80.571591 -345.703719)
			(xy 80.393623 -345.801832) (xy 80.211917 -345.892839) (xy 80.026758 -345.976595) (xy 79.838435 -346.052972)
			(xy 79.647241 -346.121848) (xy 79.453476 -346.183118) (xy 79.257441 -346.236684) (xy 79.059443 -346.282464)
			(xy 78.859791 -346.320386) (xy 78.658797 -346.350391) (xy 78.456774 -346.372432) (xy 78.254038 -346.386475)
			(xy 78.050906 -346.392497) (xy 77.847694 -346.390489) (xy 77.644721 -346.380455) (xy 77.442302 -346.36241)
			(xy 77.240754 -346.336382) (xy 77.040392 -346.302412) (xy 76.841528 -346.260552) (xy 76.644473 -346.210869)
			(xy 76.449535 -346.15344) (xy 76.257018 -346.088354) (xy 76.067222 -346.015714) (xy 75.880444 -345.935632)
			(xy 75.696976 -345.848233) (xy 75.517104 -345.753655) (xy 75.341109 -345.652044) (xy 75.169266 -345.543559)
			(xy 75.001843 -345.428371) (xy 74.839101 -345.306658) (xy 74.681294 -345.17861) (xy 74.52867 -345.044428)
			(xy 74.381466 -344.904321) (xy 74.239911 -344.758508) (xy 74.104228 -344.607217) (xy 73.974628 -344.450683)
			(xy 73.851313 -344.289152) (xy 73.734476 -344.122874) (xy 73.624299 -343.952111) (xy 73.520955 -343.777129)
			(xy 73.424604 -343.5982) (xy 73.335397 -343.415604) (xy 73.253474 -343.229627) (xy 73.178962 -343.040558)
			(xy 73.111977 -342.848693) (xy 73.052625 -342.654332) (xy 73.000998 -342.457778) (xy 72.957176 -342.259337)
			(xy 72.921228 -342.05932) (xy 72.89321 -341.858039) (xy 72.873166 -341.655809) (xy 72.861127 -341.452944)
			(xy 72.857112 -341.249762) (xy 6.800129 -341.249762) (xy 6.79855 -341.263351) (xy 6.77732 -341.375853)
			(xy 6.748183 -341.486571) (xy 6.711286 -341.594951) (xy 6.666813 -341.700448) (xy 6.614988 -341.802534)
			(xy 6.556069 -341.900698) (xy 6.490353 -341.994448) (xy 6.454648 -342.039194) (xy 6.454394 -342.039448)
			(xy 6.060186 -342.039448) (xy 6.021179 -342.071737) (xy 5.939048 -342.130983) (xy 5.896102 -342.157812)
			(xy 5.882524 -342.166761) (xy 5.860006 -342.190206) (xy 5.844123 -342.218568) (xy 5.8359 -342.250017)
			(xy 5.835396 -342.26627) (xy 5.835396 -342.5063) (xy 5.835142 -342.5063) (xy 5.780469 -342.529093)
			(xy 5.668424 -342.567559) (xy 5.553864 -342.597719) (xy 5.437404 -342.619413) (xy 5.319668 -342.632524)
			(xy 5.201288 -342.636981) (xy 5.0829 -342.632761) (xy 4.965138 -342.619886) (xy 4.848635 -342.598425)
			(xy 4.734015 -342.568494) (xy 4.621893 -342.530253) (xy 4.567174 -342.50757) (xy 4.56692 -342.50757)
			(xy 4.56692 -342.26754) (xy 4.566441 -342.251261) (xy 4.558186 -342.219766) (xy 4.542229 -342.191387)
			(xy 4.519608 -342.167969) (xy 4.50596 -342.159082) (xy 4.459776 -342.130343) (xy 4.371783 -342.066378)
			(xy 4.330192 -342.03132) (xy 3.938778 -342.03132) (xy 3.904941 -341.988409) (xy 3.842477 -341.898728)
			(xy 3.78621 -341.805035) (xy 3.736399 -341.707756) (xy 3.69327 -341.607335) (xy 3.657021 -341.504231)
			(xy 3.627816 -341.398915) (xy 3.60579 -341.291867) (xy 3.591042 -341.183577) (xy 3.583641 -341.074537)
			(xy 3.583178 -341.019892) (xy 1.016 -341.019892) (xy 1.016 -342.571578) (xy 1.016492 -342.586921)
			(xy 1.023881 -342.616707) (xy 1.038164 -342.64387) (xy 1.048004 -342.655652) (xy 1.065976 -342.676695)
			(xy 1.09629 -342.722991) (xy 1.119599 -342.77318) (xy 1.135415 -342.82621) (xy 1.143407 -342.880967)
			(xy 1.143407 -342.936305) (xy 1.135415 -342.991062) (xy 1.119599 -343.044092) (xy 1.09629 -343.094281)
			(xy 1.065976 -343.140577) (xy 1.048004 -343.16162) (xy 1.03813 -343.173379) (xy 1.023835 -343.200546)
			(xy 1.01646 -343.230345) (xy 1.016 -343.245694) (xy 1.016 -355.271578) (xy 1.016492 -355.286921)
			(xy 1.023881 -355.316707) (xy 1.038164 -355.34387) (xy 1.048004 -355.355652) (xy 1.065976 -355.376695)
			(xy 1.09629 -355.422991) (xy 1.119599 -355.47318) (xy 1.135415 -355.52621) (xy 1.143407 -355.580967)
			(xy 1.143407 -355.636305) (xy 1.135415 -355.691062) (xy 1.119599 -355.744092) (xy 1.09629 -355.794281)
			(xy 1.065976 -355.840577) (xy 1.048004 -355.86162) (xy 1.03813 -355.873379) (xy 1.023835 -355.900546)
			(xy 1.01646 -355.930345) (xy 1.016 -355.945694) (xy 1.016 -362.51007) (xy 39.818564 -362.51007) (xy 39.819058 -362.452661)
			(xy 39.826902 -362.338113) (xy 39.842544 -362.224366) (xy 39.865911 -362.111952) (xy 39.896896 -362.001394)
			(xy 39.935352 -361.893209) (xy 39.981101 -361.7879) (xy 40.03393 -361.685958) (xy 40.093592 -361.587859)
			(xy 40.159809 -361.49406) (xy 40.232272 -361.404998) (xy 40.310645 -361.321089) (xy 40.39456 -361.242723)
			(xy 40.483627 -361.170266) (xy 40.577431 -361.104056) (xy 40.675535 -361.044402) (xy 40.777481 -360.991581)
			(xy 40.882793 -360.945839) (xy 40.990981 -360.907391) (xy 41.101541 -360.876415) (xy 41.213957 -360.853056)
			(xy 41.327705 -360.837423) (xy 41.442254 -360.829588) (xy 41.557072 -360.829588) (xy 41.671621 -360.837423)
			(xy 41.785369 -360.853056) (xy 41.897785 -360.876415) (xy 42.008345 -360.907391) (xy 42.116533 -360.945839)
			(xy 42.221845 -360.991581) (xy 42.323791 -361.044402) (xy 42.421895 -361.104056) (xy 42.515699 -361.170266)
			(xy 42.604766 -361.242723) (xy 42.688681 -361.321089) (xy 42.767054 -361.404998) (xy 42.839517 -361.49406)
			(xy 42.905734 -361.587859) (xy 42.965396 -361.685958) (xy 43.018225 -361.7879) (xy 43.063974 -361.893209)
			(xy 43.10243 -362.001394) (xy 43.133415 -362.111952) (xy 43.156782 -362.224366) (xy 43.172424 -362.338113)
			(xy 43.180268 -362.452661) (xy 43.180762 -362.51007) (xy 43.180576 -362.543253) (xy 43.177909 -362.609567)
			(xy 43.175428 -362.642658) (xy 43.170272 -362.700942) (xy 43.152948 -362.816671) (xy 43.127616 -362.930914)
			(xy 43.094401 -363.043119) (xy 43.053462 -363.152742) (xy 43.004999 -363.259253) (xy 42.949245 -363.362135)
			(xy 42.886471 -363.460891) (xy 42.816981 -363.555042) (xy 42.741111 -363.644132) (xy 42.659229 -363.727729)
			(xy 42.571732 -363.80543) (xy 42.500813 -363.86008) (xy 93.154506 -363.86008) (xy 93.158522 -363.74381)
			(xy 93.170549 -363.628095) (xy 93.190531 -363.513485) (xy 93.218373 -363.400526) (xy 93.253942 -363.289758)
			(xy 93.297068 -363.181707) (xy 93.347545 -363.076889) (xy 93.405134 -362.975804) (xy 93.46956 -362.878932)
			(xy 93.540515 -362.786736) (xy 93.617662 -362.699655) (xy 93.700633 -362.618104) (xy 93.789033 -362.542472)
			(xy 93.88244 -362.473118) (xy 93.980409 -362.410375) (xy 94.082473 -362.354539) (xy 94.188147 -362.305878)
			(xy 94.296926 -362.264624) (xy 94.408291 -362.230973) (xy 94.521714 -362.205085) (xy 94.636651 -362.187084)
			(xy 94.752557 -362.177055) (xy 94.868879 -362.175047) (xy 94.985062 -362.181069) (xy 95.100553 -362.195092)
			(xy 95.214801 -362.21705) (xy 95.327262 -362.246837) (xy 95.4374 -362.284312) (xy 95.54469 -362.329297)
			(xy 95.648621 -362.381576) (xy 95.748697 -362.440901) (xy 95.844443 -362.506989) (xy 95.9354 -362.579525)
			(xy 96.021136 -362.658164) (xy 96.101243 -362.74253) (xy 96.175339 -362.832222) (xy 96.243069 -362.926812)
			(xy 96.304113 -363.02585) (xy 96.358178 -363.128863) (xy 96.405008 -363.23536) (xy 96.444379 -363.344835)
			(xy 96.476103 -363.456765) (xy 96.500029 -363.570617) (xy 96.516043 -363.685849) (xy 96.52407 -363.801911)
			(xy 96.524572 -363.86008) (xy 96.52407 -363.918249) (xy 96.516043 -364.034311) (xy 96.500029 -364.149543)
			(xy 96.476103 -364.263395) (xy 96.444379 -364.375325) (xy 96.405008 -364.4848) (xy 96.358178 -364.591297)
			(xy 96.304113 -364.69431) (xy 96.243069 -364.793348) (xy 96.175339 -364.887938) (xy 96.101243 -364.97763)
			(xy 96.021136 -365.061996) (xy 95.9354 -365.140635) (xy 95.844443 -365.213171) (xy 95.748697 -365.279259)
			(xy 95.648621 -365.338584) (xy 95.54469 -365.390863) (xy 95.4374 -365.435848) (xy 95.327262 -365.473323)
			(xy 95.214801 -365.50311) (xy 95.100553 -365.525068) (xy 94.985062 -365.539091) (xy 94.868879 -365.545113)
			(xy 94.752557 -365.543105) (xy 94.636651 -365.533076) (xy 94.521714 -365.515075) (xy 94.408291 -365.489187)
			(xy 94.296926 -365.455536) (xy 94.188147 -365.414282) (xy 94.082473 -365.365621) (xy 93.980409 -365.309785)
			(xy 93.88244 -365.247042) (xy 93.789033 -365.177688) (xy 93.700633 -365.102056) (xy 93.617662 -365.020505)
			(xy 93.540515 -364.933424) (xy 93.46956 -364.841228) (xy 93.405134 -364.744356) (xy 93.347545 -364.643271)
			(xy 93.297068 -364.538453) (xy 93.253942 -364.430402) (xy 93.218373 -364.319634) (xy 93.190531 -364.206675)
			(xy 93.170549 -364.092065) (xy 93.158522 -363.97635) (xy 93.154506 -363.86008) (xy 42.500813 -363.86008)
			(xy 42.479042 -363.876857) (xy 42.381609 -363.941665) (xy 42.279905 -363.99954) (xy 42.174422 -364.050202)
			(xy 42.065671 -364.093404) (xy 41.954179 -364.128939) (xy 41.840485 -364.156634) (xy 41.725141 -364.176354)
			(xy 41.608704 -364.188005) (xy 41.491739 -364.19153) (xy 41.374812 -364.186912) (xy 41.258489 -364.174173)
			(xy 41.143334 -364.153375) (xy 41.029905 -364.124618) (xy 40.91875 -364.088042) (xy 40.810407 -364.043825)
			(xy 40.705403 -363.992179) (xy 40.604244 -363.933356) (xy 40.507421 -363.86764) (xy 40.415403 -363.795349)
			(xy 40.328636 -363.716834) (xy 40.247539 -363.632474) (xy 40.172506 -363.542679) (xy 40.103899 -363.447883)
			(xy 40.042051 -363.348544) (xy 39.987262 -363.245145) (xy 39.939796 -363.138186) (xy 39.899884 -363.028185)
			(xy 39.86772 -362.915674) (xy 39.843457 -362.801199) (xy 39.827215 -362.685313) (xy 39.819072 -362.568579)
			(xy 39.818564 -362.51007) (xy 1.016 -362.51007) (xy 1.016 -367.971578) (xy 1.016492 -367.986921)
			(xy 1.023881 -368.016707) (xy 1.038164 -368.04387) (xy 1.048004 -368.055652) (xy 1.065976 -368.076695)
			(xy 1.09629 -368.122991) (xy 1.119599 -368.17318) (xy 1.135415 -368.22621) (xy 1.143407 -368.280967)
			(xy 1.143407 -368.336305) (xy 1.135415 -368.391062) (xy 1.119599 -368.444092) (xy 1.09629 -368.494281)
			(xy 1.065976 -368.540577) (xy 1.048004 -368.56162) (xy 1.03813 -368.573379) (xy 1.023835 -368.600546)
			(xy 1.01646 -368.630345) (xy 1.016 -368.645694) (xy 1.016 -375.61012) (xy 86.877404 -375.61012) (xy 86.881424 -375.419469)
			(xy 86.893478 -375.229156) (xy 86.913544 -375.039521) (xy 86.941587 -374.8509) (xy 86.977556 -374.66363)
			(xy 87.021388 -374.478042) (xy 87.073005 -374.294467) (xy 87.132315 -374.113231) (xy 87.199213 -373.934656)
			(xy 87.273579 -373.759061) (xy 87.355281 -373.586756) (xy 87.444175 -373.418049) (xy 87.540101 -373.253239)
			(xy 87.64289 -373.09262) (xy 87.752359 -372.936477) (xy 87.868313 -372.785088) (xy 87.990547 -372.638721)
			(xy 88.118841 -372.497637) (xy 88.252969 -372.362088) (xy 88.392693 -372.232313) (xy 88.537763 -372.108543)
			(xy 88.687921 -371.991) (xy 88.842902 -371.879891) (xy 89.002429 -371.775414) (xy 89.166218 -371.677755)
			(xy 89.333978 -371.587088) (xy 89.505412 -371.503574) (xy 89.680214 -371.427361) (xy 89.858073 -371.358585)
			(xy 90.038674 -371.297367) (xy 90.221694 -371.243818) (xy 90.40681 -371.198032) (xy 90.593691 -371.16009)
			(xy 90.782006 -371.130061) (xy 90.971419 -371.107996) (xy 91.161593 -371.093937) (xy 91.352192 -371.087907)
			(xy 91.542875 -371.089917) (xy 91.733304 -371.099964) (xy 91.92314 -371.11803) (xy 92.112046 -371.144083)
			(xy 92.299685 -371.178076) (xy 92.485725 -371.219949) (xy 92.669834 -371.269628) (xy 92.851685 -371.327024)
			(xy 93.030955 -371.392035) (xy 93.207325 -371.464546) (xy 93.380481 -371.544427) (xy 93.550116 -371.631537)
			(xy 93.715928 -371.725721) (xy 93.877622 -371.826812) (xy 94.03491 -371.934628) (xy 94.187513 -372.04898)
			(xy 94.335161 -372.169663) (xy 94.477589 -372.296464) (xy 94.614545 -372.429155) (xy 94.745786 -372.567503)
			(xy 94.871078 -372.71126) (xy 94.990198 -372.860171) (xy 95.102934 -373.013972) (xy 95.209087 -373.172388)
			(xy 95.308467 -373.335139) (xy 95.400897 -373.501934) (xy 95.486214 -373.672478) (xy 95.564266 -373.846466)
			(xy 95.634913 -374.023591) (xy 95.698031 -374.203536) (xy 95.753507 -374.385982) (xy 95.801242 -374.570605)
			(xy 95.841152 -374.757075) (xy 95.873165 -374.945063) (xy 95.897225 -375.134233) (xy 95.913288 -375.324249)
			(xy 95.921327 -375.514773) (xy 95.92183 -375.61012) (xy 95.921327 -375.705467) (xy 95.913288 -375.895991)
			(xy 95.897225 -376.086007) (xy 95.873165 -376.275177) (xy 95.841152 -376.463165) (xy 95.801242 -376.649635)
			(xy 95.753507 -376.834258) (xy 95.698031 -377.016704) (xy 95.634913 -377.196649) (xy 95.564266 -377.373774)
			(xy 95.486214 -377.547762) (xy 95.400897 -377.718306) (xy 95.308467 -377.885101) (xy 95.209087 -378.047852)
			(xy 95.102934 -378.206268) (xy 94.990198 -378.360069) (xy 94.871078 -378.50898) (xy 94.745786 -378.652737)
			(xy 94.614545 -378.791085) (xy 94.477589 -378.923776) (xy 94.335161 -379.050577) (xy 94.187513 -379.17126)
			(xy 94.03491 -379.285612) (xy 93.877622 -379.393428) (xy 93.715928 -379.494519) (xy 93.550116 -379.588703)
			(xy 93.380481 -379.675813) (xy 93.207325 -379.755694) (xy 93.030955 -379.828205) (xy 92.851685 -379.893216)
			(xy 92.669834 -379.950612) (xy 92.485725 -380.000291) (xy 92.299685 -380.042164) (xy 92.112046 -380.076157)
			(xy 91.92314 -380.10221) (xy 91.733304 -380.120276) (xy 91.542875 -380.130323) (xy 91.352192 -380.132333)
			(xy 91.161593 -380.126303) (xy 90.971419 -380.112244) (xy 90.782006 -380.090179) (xy 90.593691 -380.06015)
			(xy 90.40681 -380.022208) (xy 90.221694 -379.976422) (xy 90.038674 -379.922873) (xy 89.858073 -379.861655)
			(xy 89.680214 -379.792879) (xy 89.505412 -379.716666) (xy 89.333978 -379.633152) (xy 89.166218 -379.542485)
			(xy 89.002429 -379.444826) (xy 88.842902 -379.340349) (xy 88.687921 -379.22924) (xy 88.537763 -379.111697)
			(xy 88.392693 -378.987927) (xy 88.252969 -378.858152) (xy 88.118841 -378.722603) (xy 87.990547 -378.581519)
			(xy 87.868313 -378.435152) (xy 87.752359 -378.283763) (xy 87.64289 -378.12762) (xy 87.540101 -377.967001)
			(xy 87.444175 -377.802191) (xy 87.355281 -377.633484) (xy 87.273579 -377.461179) (xy 87.199213 -377.285584)
			(xy 87.132315 -377.107009) (xy 87.073005 -376.925773) (xy 87.021388 -376.742198) (xy 86.977556 -376.55661)
			(xy 86.941587 -376.36934) (xy 86.913544 -376.180719) (xy 86.893478 -375.991084) (xy 86.881424 -375.800771)
			(xy 86.877404 -375.61012) (xy 1.016 -375.61012) (xy 1.016 -380.671578) (xy 1.016492 -380.686921)
			(xy 1.023881 -380.716707) (xy 1.038164 -380.74387) (xy 1.048004 -380.755652) (xy 1.065976 -380.776695)
			(xy 1.09629 -380.822991) (xy 1.119599 -380.87318) (xy 1.135415 -380.92621) (xy 1.143407 -380.980967)
			(xy 1.143407 -381.036305) (xy 1.135415 -381.091062) (xy 1.119599 -381.144092) (xy 1.09629 -381.194281)
			(xy 1.065976 -381.240577) (xy 1.048004 -381.26162) (xy 1.03813 -381.273379) (xy 1.023835 -381.300546)
			(xy 1.01646 -381.330345) (xy 1.016 -381.345694) (xy 1.016 -384.79984) (xy 11.344156 -384.79984) (xy 11.348157 -384.594781)
			(xy 11.360157 -384.390034) (xy 11.380135 -384.185911) (xy 11.408063 -383.982723) (xy 11.443897 -383.780779)
			(xy 11.487582 -383.580388) (xy 11.539053 -383.381853) (xy 11.598231 -383.185477) (xy 11.665026 -382.99156)
			(xy 11.739335 -382.800397) (xy 11.821046 -382.612279) (xy 11.910035 -382.427492) (xy 12.006166 -382.246317)
			(xy 12.109292 -382.069031) (xy 12.219257 -381.895904) (xy 12.335893 -381.727199) (xy 12.459022 -381.563173)
			(xy 12.588457 -381.404076) (xy 12.724001 -381.25015) (xy 12.865447 -381.10163) (xy 13.01258 -380.958741)
			(xy 13.165176 -380.821702) (xy 13.323003 -380.690721) (xy 13.48582 -380.565997) (xy 13.653379 -380.447721)
			(xy 13.825425 -380.336073) (xy 14.001696 -380.231222) (xy 14.181924 -380.133328) (xy 14.365835 -380.042541)
			(xy 14.553147 -379.958998) (xy 14.743576 -379.882827) (xy 14.936832 -379.814143) (xy 15.132621 -379.753053)
			(xy 15.330644 -379.699647) (xy 15.5306 -379.654009) (xy 15.732184 -379.616206) (xy 15.93509 -379.586298)
			(xy 16.139008 -379.564328) (xy 16.343629 -379.550332) (xy 16.548639 -379.54433) (xy 16.753728 -379.546331)
			(xy 16.958582 -379.556332) (xy 17.16289 -379.574318) (xy 17.366341 -379.600262) (xy 17.568624 -379.634124)
			(xy 17.769433 -379.675852) (xy 17.96846 -379.725384) (xy 18.165404 -379.782643) (xy 18.359963 -379.847542)
			(xy 18.551842 -379.919983) (xy 18.740749 -379.999855) (xy 18.926395 -380.087037) (xy 19.108499 -380.181396)
			(xy 19.286783 -380.282787) (xy 19.460975 -380.391058) (xy 19.63081 -380.506042) (xy 19.796029 -380.627565)
			(xy 19.956381 -380.755442) (xy 20.111622 -380.889477) (xy 20.261516 -381.029468) (xy 20.405833 -381.1752)
			(xy 20.544354 -381.326452) (xy 20.676869 -381.482993) (xy 20.803175 -381.644585) (xy 20.92308 -381.810982)
			(xy 21.036402 -381.981931) (xy 21.142968 -382.157171) (xy 21.242615 -382.336435) (xy 21.335193 -382.519451)
			(xy 21.420559 -382.705939) (xy 21.498584 -382.895616) (xy 21.56915 -383.088193) (xy 21.632148 -383.283376)
			(xy 21.687483 -383.480869) (xy 21.73507 -383.68037) (xy 21.774837 -383.881576) (xy 21.806724 -384.084181)
			(xy 21.830682 -384.287875) (xy 21.846674 -384.492349) (xy 21.854676 -384.697291) (xy 21.855176 -384.79984)
			(xy 21.854676 -384.902389) (xy 21.846674 -385.107331) (xy 21.830682 -385.311805) (xy 21.806724 -385.515499)
			(xy 21.774837 -385.718104) (xy 21.73507 -385.91931) (xy 21.687483 -386.118811) (xy 21.632148 -386.316304)
			(xy 21.56915 -386.511487) (xy 21.498584 -386.704064) (xy 21.420559 -386.893741) (xy 21.335193 -387.080229)
			(xy 21.242615 -387.263245) (xy 21.142968 -387.442509) (xy 21.036402 -387.617749) (xy 20.92308 -387.788698)
			(xy 20.803175 -387.955095) (xy 20.676869 -388.116687) (xy 20.544354 -388.273228) (xy 20.405833 -388.42448)
			(xy 20.261516 -388.570212) (xy 20.111622 -388.710203) (xy 19.956381 -388.844238) (xy 19.796029 -388.972115)
			(xy 19.63081 -389.093638) (xy 19.460975 -389.208622) (xy 19.286783 -389.316893) (xy 19.108499 -389.418284)
			(xy 18.926395 -389.512643) (xy 18.740749 -389.599825) (xy 18.551842 -389.679697) (xy 18.359963 -389.752138)
			(xy 18.165404 -389.817037) (xy 17.96846 -389.874296) (xy 17.769433 -389.923828) (xy 17.568624 -389.965556)
			(xy 17.366341 -389.999418) (xy 17.16289 -390.025362) (xy 16.958582 -390.043348) (xy 16.753728 -390.053349)
			(xy 16.548639 -390.05535) (xy 16.343629 -390.049348) (xy 16.139008 -390.035352) (xy 15.93509 -390.013382)
			(xy 15.732184 -389.983474) (xy 15.5306 -389.945671) (xy 15.330644 -389.900033) (xy 15.132621 -389.846627)
			(xy 14.936832 -389.785537) (xy 14.743576 -389.716853) (xy 14.553147 -389.640682) (xy 14.365835 -389.557139)
			(xy 14.181924 -389.466352) (xy 14.001696 -389.368458) (xy 13.825425 -389.263607) (xy 13.653379 -389.151959)
			(xy 13.48582 -389.033683) (xy 13.323003 -388.908959) (xy 13.165176 -388.777978) (xy 13.01258 -388.640939)
			(xy 12.865447 -388.49805) (xy 12.724001 -388.34953) (xy 12.588457 -388.195604) (xy 12.459022 -388.036507)
			(xy 12.335893 -387.872481) (xy 12.219257 -387.703776) (xy 12.109292 -387.530649) (xy 12.006166 -387.353363)
			(xy 11.910035 -387.172188) (xy 11.821046 -386.987401) (xy 11.739335 -386.799283) (xy 11.665026 -386.60812)
			(xy 11.598231 -386.414203) (xy 11.539053 -386.217827) (xy 11.487582 -386.019292) (xy 11.443897 -385.818901)
			(xy 11.408063 -385.616957) (xy 11.380135 -385.413769) (xy 11.360157 -385.209646) (xy 11.348157 -385.004899)
			(xy 11.344156 -384.79984) (xy 1.016 -384.79984) (xy 1.016 -393.371578) (xy 1.016492 -393.386921)
			(xy 1.023881 -393.416707) (xy 1.038164 -393.44387) (xy 1.048004 -393.455652) (xy 1.065976 -393.476695)
			(xy 1.09629 -393.522991) (xy 1.119599 -393.57318) (xy 1.135415 -393.62621) (xy 1.143407 -393.680967)
			(xy 1.143407 -393.736305) (xy 1.135415 -393.791062) (xy 1.119599 -393.844092) (xy 1.09629 -393.894281)
			(xy 1.065976 -393.940577) (xy 1.048004 -393.96162) (xy 1.03813 -393.973379) (xy 1.023835 -394.000546)
			(xy 1.01646 -394.030345) (xy 1.016 -394.045694) (xy 1.016 -399.479084) (xy 5.677649 -399.479084)
			(xy 5.677649 -399.352948) (xy 5.685569 -399.22706) (xy 5.701379 -399.101918) (xy 5.725014 -398.978015)
			(xy 5.756383 -398.855842) (xy 5.795361 -398.735879) (xy 5.841795 -398.6186) (xy 5.895502 -398.504468)
			(xy 5.956269 -398.393933) (xy 6.023856 -398.287433) (xy 6.097997 -398.185386) (xy 6.1784 -398.088196)
			(xy 6.264746 -397.996246) (xy 6.356696 -397.9099) (xy 6.453886 -397.829497) (xy 6.555933 -397.755356)
			(xy 6.662433 -397.687769) (xy 6.772968 -397.627002) (xy 6.8871 -397.573295) (xy 7.004379 -397.526861)
			(xy 7.124342 -397.487883) (xy 7.246515 -397.456514) (xy 7.370418 -397.432879) (xy 7.49556 -397.417069)
			(xy 7.621448 -397.409149) (xy 7.747584 -397.409149) (xy 7.873472 -397.417069) (xy 7.998614 -397.432879)
			(xy 8.122517 -397.456514) (xy 8.24469 -397.487883) (xy 8.364653 -397.526861) (xy 8.481932 -397.573295)
			(xy 8.596064 -397.627002) (xy 8.706599 -397.687769) (xy 8.813099 -397.755356) (xy 8.915146 -397.829497)
			(xy 9.012336 -397.9099) (xy 9.104286 -397.996246) (xy 9.190632 -398.088196) (xy 9.271035 -398.185386)
			(xy 9.345176 -398.287433) (xy 9.412763 -398.393933) (xy 9.47353 -398.504468) (xy 9.527237 -398.6186)
			(xy 9.573671 -398.735879) (xy 9.612649 -398.855842) (xy 9.644018 -398.978015) (xy 9.667653 -399.101918)
			(xy 9.683463 -399.22706) (xy 9.691383 -399.352948) (xy 9.691878 -399.416016) (xy 9.691383 -399.479084)
			(xy 9.683463 -399.604972) (xy 9.667653 -399.730114) (xy 9.644018 -399.854017) (xy 9.612649 -399.97619)
			(xy 9.573671 -400.096153) (xy 9.527237 -400.213432) (xy 9.47353 -400.327564) (xy 9.412763 -400.438099)
			(xy 9.345176 -400.544599) (xy 9.271035 -400.646646) (xy 9.190632 -400.743836) (xy 9.104286 -400.835786)
			(xy 9.012336 -400.922132) (xy 8.915146 -401.002535) (xy 8.813099 -401.076676) (xy 8.706599 -401.144263)
			(xy 8.596064 -401.20503) (xy 8.481932 -401.258737) (xy 8.364653 -401.305171) (xy 8.24469 -401.344149)
			(xy 8.122517 -401.375518) (xy 7.998614 -401.399153) (xy 7.873472 -401.414963) (xy 7.747584 -401.422883)
			(xy 7.621448 -401.422883) (xy 7.49556 -401.414963) (xy 7.370418 -401.399153) (xy 7.246515 -401.375518)
			(xy 7.124342 -401.344149) (xy 7.004379 -401.305171) (xy 6.8871 -401.258737) (xy 6.772968 -401.20503)
			(xy 6.662433 -401.144263) (xy 6.555933 -401.076676) (xy 6.453886 -401.002535) (xy 6.356696 -400.922132)
			(xy 6.264746 -400.835786) (xy 6.1784 -400.743836) (xy 6.097997 -400.646646) (xy 6.023856 -400.544599)
			(xy 5.956269 -400.438099) (xy 5.895502 -400.327564) (xy 5.841795 -400.213432) (xy 5.795361 -400.096153)
			(xy 5.756383 -399.97619) (xy 5.725014 -399.854017) (xy 5.701379 -399.730114) (xy 5.685569 -399.604972)
			(xy 5.677649 -399.479084) (xy 1.016 -399.479084) (xy 1.016 -404.690326) (xy 1.016438 -404.705774)
			(xy 1.023876 -404.735763) (xy 1.038309 -404.763081) (xy 1.048258 -404.774908) (xy 1.066393 -404.795992)
			(xy 1.096996 -404.842427) (xy 1.120535 -404.892811) (xy 1.13651 -404.94608) (xy 1.144583 -405.001102)
			(xy 1.144584 -405.056715) (xy 1.136511 -405.111738) (xy 1.120536 -405.165006) (xy 1.096998 -405.215391)
			(xy 1.066395 -405.261825) (xy 1.048258 -405.282908) (xy 1.038292 -405.294723) (xy 1.02386 -405.322047)
			(xy 1.016425 -405.35204) (xy 1.016 -405.36749) (xy 1.016 -406.96007) (xy 39.818564 -406.96007) (xy 39.819058 -406.902661)
			(xy 39.826902 -406.788113) (xy 39.842544 -406.674366) (xy 39.865911 -406.561952) (xy 39.896896 -406.451394)
			(xy 39.935352 -406.343209) (xy 39.981101 -406.2379) (xy 40.03393 -406.135958) (xy 40.093592 -406.037859)
			(xy 40.159809 -405.94406) (xy 40.232272 -405.854998) (xy 40.310645 -405.771089) (xy 40.39456 -405.692723)
			(xy 40.483627 -405.620266) (xy 40.577431 -405.554056) (xy 40.675535 -405.494402) (xy 40.777481 -405.441581)
			(xy 40.882793 -405.395839) (xy 40.990981 -405.357391) (xy 41.101541 -405.326415) (xy 41.213957 -405.303056)
			(xy 41.327705 -405.287423) (xy 41.442254 -405.279588) (xy 41.557072 -405.279588) (xy 41.671621 -405.287423)
			(xy 41.785369 -405.303056) (xy 41.897785 -405.326415) (xy 42.008345 -405.357391) (xy 42.116533 -405.395839)
			(xy 42.221845 -405.441581) (xy 42.323791 -405.494402) (xy 42.421895 -405.554056) (xy 42.515699 -405.620266)
			(xy 42.604766 -405.692723) (xy 42.688681 -405.771089) (xy 42.767054 -405.854998) (xy 42.839517 -405.94406)
			(xy 42.905734 -406.037859) (xy 42.965396 -406.135958) (xy 43.018225 -406.2379) (xy 43.063974 -406.343209)
			(xy 43.10243 -406.451394) (xy 43.133415 -406.561952) (xy 43.156782 -406.674366) (xy 43.172424 -406.788113)
			(xy 43.180268 -406.902661) (xy 43.180762 -406.96007) (xy 43.180576 -406.993253) (xy 43.177909 -407.059567)
			(xy 43.175428 -407.092658) (xy 43.170272 -407.150942) (xy 43.152948 -407.266671) (xy 43.127616 -407.380914)
			(xy 43.094401 -407.493119) (xy 43.053462 -407.602742) (xy 43.004999 -407.709253) (xy 42.949245 -407.812135)
			(xy 42.886471 -407.910891) (xy 42.816981 -408.005042) (xy 42.741111 -408.094132) (xy 42.659229 -408.177729)
			(xy 42.571732 -408.25543) (xy 42.500813 -408.31008) (xy 93.154506 -408.31008) (xy 93.158522 -408.19381)
			(xy 93.170549 -408.078095) (xy 93.190531 -407.963485) (xy 93.218373 -407.850526) (xy 93.253942 -407.739758)
			(xy 93.297068 -407.631707) (xy 93.347545 -407.526889) (xy 93.405134 -407.425804) (xy 93.46956 -407.328932)
			(xy 93.540515 -407.236736) (xy 93.617662 -407.149655) (xy 93.700633 -407.068104) (xy 93.789033 -406.992472)
			(xy 93.88244 -406.923118) (xy 93.980409 -406.860375) (xy 94.082473 -406.804539) (xy 94.188147 -406.755878)
			(xy 94.296926 -406.714624) (xy 94.408291 -406.680973) (xy 94.521714 -406.655085) (xy 94.636651 -406.637084)
			(xy 94.752557 -406.627055) (xy 94.868879 -406.625047) (xy 94.985062 -406.631069) (xy 95.100553 -406.645092)
			(xy 95.214801 -406.66705) (xy 95.327262 -406.696837) (xy 95.4374 -406.734312) (xy 95.54469 -406.779297)
			(xy 95.648621 -406.831576) (xy 95.748697 -406.890901) (xy 95.844443 -406.956989) (xy 95.9354 -407.029525)
			(xy 96.021136 -407.108164) (xy 96.101243 -407.19253) (xy 96.175339 -407.282222) (xy 96.243069 -407.376812)
			(xy 96.304113 -407.47585) (xy 96.358178 -407.578863) (xy 96.405008 -407.68536) (xy 96.444379 -407.794835)
			(xy 96.476103 -407.906765) (xy 96.500029 -408.020617) (xy 96.516043 -408.135849) (xy 96.52407 -408.251911)
			(xy 96.524572 -408.31008) (xy 96.52407 -408.368249) (xy 96.516043 -408.484311) (xy 96.500029 -408.599543)
			(xy 96.476103 -408.713395) (xy 96.444379 -408.825325) (xy 96.405008 -408.9348) (xy 96.358178 -409.041297)
			(xy 96.304113 -409.14431) (xy 96.243069 -409.243348) (xy 96.175339 -409.337938) (xy 96.101243 -409.42763)
			(xy 96.021136 -409.511996) (xy 95.9354 -409.590635) (xy 95.844443 -409.663171) (xy 95.748697 -409.729259)
			(xy 95.648621 -409.788584) (xy 95.54469 -409.840863) (xy 95.4374 -409.885848) (xy 95.327262 -409.923323)
			(xy 95.214801 -409.95311) (xy 95.100553 -409.975068) (xy 94.985062 -409.989091) (xy 94.868879 -409.995113)
			(xy 94.752557 -409.993105) (xy 94.636651 -409.983076) (xy 94.521714 -409.965075) (xy 94.408291 -409.939187)
			(xy 94.296926 -409.905536) (xy 94.188147 -409.864282) (xy 94.082473 -409.815621) (xy 93.980409 -409.759785)
			(xy 93.88244 -409.697042) (xy 93.789033 -409.627688) (xy 93.700633 -409.552056) (xy 93.617662 -409.470505)
			(xy 93.540515 -409.383424) (xy 93.46956 -409.291228) (xy 93.405134 -409.194356) (xy 93.347545 -409.093271)
			(xy 93.297068 -408.988453) (xy 93.253942 -408.880402) (xy 93.218373 -408.769634) (xy 93.190531 -408.656675)
			(xy 93.170549 -408.542065) (xy 93.158522 -408.42635) (xy 93.154506 -408.31008) (xy 42.500813 -408.31008)
			(xy 42.479042 -408.326857) (xy 42.381609 -408.391665) (xy 42.279905 -408.44954) (xy 42.174422 -408.500202)
			(xy 42.065671 -408.543404) (xy 41.954179 -408.578939) (xy 41.840485 -408.606634) (xy 41.725141 -408.626354)
			(xy 41.608704 -408.638005) (xy 41.491739 -408.64153) (xy 41.374812 -408.636912) (xy 41.258489 -408.624173)
			(xy 41.143334 -408.603375) (xy 41.029905 -408.574618) (xy 40.91875 -408.538042) (xy 40.810407 -408.493825)
			(xy 40.705403 -408.442179) (xy 40.604244 -408.383356) (xy 40.507421 -408.31764) (xy 40.415403 -408.245349)
			(xy 40.328636 -408.166834) (xy 40.247539 -408.082474) (xy 40.172506 -407.992679) (xy 40.103899 -407.897883)
			(xy 40.042051 -407.798544) (xy 39.987262 -407.695145) (xy 39.939796 -407.588186) (xy 39.899884 -407.478185)
			(xy 39.86772 -407.365674) (xy 39.843457 -407.251199) (xy 39.827215 -407.135313) (xy 39.819072 -407.018579)
			(xy 39.818564 -406.96007) (xy 1.016 -406.96007) (xy 1.016 -408.641804) (xy 1.01644 -408.657313) (xy 1.023931 -408.687413)
			(xy 1.038474 -408.71481) (xy 1.048512 -408.72664) (xy 1.066871 -408.74776) (xy 1.097841 -408.794368)
			(xy 1.12167 -408.845001) (xy 1.137846 -408.898571) (xy 1.146021 -408.95393) (xy 1.146021 -409.00989)
			(xy 1.137846 -409.065249) (xy 1.12167 -409.118819) (xy 1.097841 -409.169452) (xy 1.066871 -409.21606)
			(xy 1.048512 -409.23718) (xy 1.038479 -409.249015) (xy 1.023938 -409.276412) (xy 1.016436 -409.306508)
			(xy 1.016 -409.322016) (xy 1.016 -410.909084) (xy 5.677649 -410.909084) (xy 5.677649 -410.782948)
			(xy 5.685569 -410.65706) (xy 5.701379 -410.531918) (xy 5.725014 -410.408015) (xy 5.756383 -410.285842)
			(xy 5.795361 -410.165879) (xy 5.841795 -410.0486) (xy 5.895502 -409.934468) (xy 5.956269 -409.823933)
			(xy 6.023856 -409.717433) (xy 6.097997 -409.615386) (xy 6.1784 -409.518196) (xy 6.264746 -409.426246)
			(xy 6.356696 -409.3399) (xy 6.453886 -409.259497) (xy 6.555933 -409.185356) (xy 6.662433 -409.117769)
			(xy 6.772968 -409.057002) (xy 6.8871 -409.003295) (xy 7.004379 -408.956861) (xy 7.124342 -408.917883)
			(xy 7.246515 -408.886514) (xy 7.370418 -408.862879) (xy 7.49556 -408.847069) (xy 7.621448 -408.839149)
			(xy 7.747584 -408.839149) (xy 7.873472 -408.847069) (xy 7.998614 -408.862879) (xy 8.122517 -408.886514)
			(xy 8.24469 -408.917883) (xy 8.364653 -408.956861) (xy 8.481932 -409.003295) (xy 8.596064 -409.057002)
			(xy 8.706599 -409.117769) (xy 8.813099 -409.185356) (xy 8.915146 -409.259497) (xy 9.012336 -409.3399)
			(xy 9.104286 -409.426246) (xy 9.190632 -409.518196) (xy 9.271035 -409.615386) (xy 9.345176 -409.717433)
			(xy 9.412763 -409.823933) (xy 9.47353 -409.934468) (xy 9.527237 -410.0486) (xy 9.573671 -410.165879)
			(xy 9.612649 -410.285842) (xy 9.644018 -410.408015) (xy 9.667653 -410.531918) (xy 9.683463 -410.65706)
			(xy 9.691383 -410.782948) (xy 9.691878 -410.846016) (xy 9.691383 -410.909084) (xy 9.683463 -411.034972)
			(xy 9.667653 -411.160114) (xy 9.644018 -411.284017) (xy 9.612649 -411.40619) (xy 9.573671 -411.526153)
			(xy 9.527237 -411.643432) (xy 9.47353 -411.757564) (xy 9.412763 -411.868099) (xy 9.345176 -411.974599)
			(xy 9.271035 -412.076646) (xy 9.190632 -412.173836) (xy 9.104286 -412.265786) (xy 9.012336 -412.352132)
			(xy 8.915146 -412.432535) (xy 8.813099 -412.506676) (xy 8.706599 -412.574263) (xy 8.596064 -412.63503)
			(xy 8.481932 -412.688737) (xy 8.364653 -412.735171) (xy 8.24469 -412.774149) (xy 8.122517 -412.805518)
			(xy 7.998614 -412.829153) (xy 7.873472 -412.844963) (xy 7.747584 -412.852883) (xy 7.621448 -412.852883)
			(xy 7.49556 -412.844963) (xy 7.370418 -412.829153) (xy 7.246515 -412.805518) (xy 7.124342 -412.774149)
			(xy 7.004379 -412.735171) (xy 6.8871 -412.688737) (xy 6.772968 -412.63503) (xy 6.662433 -412.574263)
			(xy 6.555933 -412.506676) (xy 6.453886 -412.432535) (xy 6.356696 -412.352132) (xy 6.264746 -412.265786)
			(xy 6.1784 -412.173836) (xy 6.097997 -412.076646) (xy 6.023856 -411.974599) (xy 5.956269 -411.868099)
			(xy 5.895502 -411.757564) (xy 5.841795 -411.643432) (xy 5.795361 -411.526153) (xy 5.756383 -411.40619)
			(xy 5.725014 -411.284017) (xy 5.701379 -411.160114) (xy 5.685569 -411.034972) (xy 5.677649 -410.909084)
			(xy 1.016 -410.909084) (xy 1.016 -418.771578) (xy 1.016492 -418.786921) (xy 1.023881 -418.816707)
			(xy 1.038164 -418.84387) (xy 1.048004 -418.855652) (xy 1.065976 -418.876695) (xy 1.09629 -418.922991)
			(xy 1.119599 -418.97318) (xy 1.135415 -419.02621) (xy 1.143407 -419.080967) (xy 1.143407 -419.136305)
			(xy 1.135415 -419.191062) (xy 1.119599 -419.244092) (xy 1.09629 -419.294281) (xy 1.065976 -419.340577)
			(xy 1.048004 -419.36162) (xy 1.03813 -419.373379) (xy 1.023835 -419.400546) (xy 1.01646 -419.430345)
			(xy 1.016 -419.445694) (xy 1.016 -420.06012) (xy 86.877404 -420.06012) (xy 86.881424 -419.869469)
			(xy 86.893478 -419.679156) (xy 86.913544 -419.489521) (xy 86.941587 -419.3009) (xy 86.977556 -419.11363)
			(xy 87.021388 -418.928042) (xy 87.073005 -418.744467) (xy 87.132315 -418.563231) (xy 87.199213 -418.384656)
			(xy 87.273579 -418.209061) (xy 87.355281 -418.036756) (xy 87.444175 -417.868049) (xy 87.540101 -417.703239)
			(xy 87.64289 -417.54262) (xy 87.752359 -417.386477) (xy 87.868313 -417.235088) (xy 87.990547 -417.088721)
			(xy 88.118841 -416.947637) (xy 88.252969 -416.812088) (xy 88.392693 -416.682313) (xy 88.537763 -416.558543)
			(xy 88.687921 -416.441) (xy 88.842902 -416.329891) (xy 89.002429 -416.225414) (xy 89.166218 -416.127755)
			(xy 89.333978 -416.037088) (xy 89.505412 -415.953574) (xy 89.680214 -415.877361) (xy 89.858073 -415.808585)
			(xy 90.038674 -415.747367) (xy 90.221694 -415.693818) (xy 90.40681 -415.648032) (xy 90.593691 -415.61009)
			(xy 90.782006 -415.580061) (xy 90.971419 -415.557996) (xy 91.161593 -415.543937) (xy 91.352192 -415.537907)
			(xy 91.542875 -415.539917) (xy 91.733304 -415.549964) (xy 91.92314 -415.56803) (xy 92.112046 -415.594083)
			(xy 92.299685 -415.628076) (xy 92.485725 -415.669949) (xy 92.669834 -415.719628) (xy 92.851685 -415.777024)
			(xy 93.030955 -415.842035) (xy 93.207325 -415.914546) (xy 93.380481 -415.994427) (xy 93.550116 -416.081537)
			(xy 93.715928 -416.175721) (xy 93.877622 -416.276812) (xy 94.03491 -416.384628) (xy 94.187513 -416.49898)
			(xy 94.335161 -416.619663) (xy 94.477589 -416.746464) (xy 94.614545 -416.879155) (xy 94.745786 -417.017503)
			(xy 94.871078 -417.16126) (xy 94.990198 -417.310171) (xy 95.102934 -417.463972) (xy 95.209087 -417.622388)
			(xy 95.308467 -417.785139) (xy 95.400897 -417.951934) (xy 95.486214 -418.122478) (xy 95.564266 -418.296466)
			(xy 95.634913 -418.473591) (xy 95.698031 -418.653536) (xy 95.753507 -418.835982) (xy 95.801242 -419.020605)
			(xy 95.841152 -419.207075) (xy 95.873165 -419.395063) (xy 95.897225 -419.584233) (xy 95.913288 -419.774249)
			(xy 95.921327 -419.964773) (xy 95.92183 -420.06012) (xy 95.921327 -420.155467) (xy 95.913288 -420.345991)
			(xy 95.897225 -420.536007) (xy 95.873165 -420.725177) (xy 95.841152 -420.913165) (xy 95.801242 -421.099635)
			(xy 95.753507 -421.284258) (xy 95.698031 -421.466704) (xy 95.634913 -421.646649) (xy 95.564266 -421.823774)
			(xy 95.486214 -421.997762) (xy 95.400897 -422.168306) (xy 95.308467 -422.335101) (xy 95.209087 -422.497852)
			(xy 95.102934 -422.656268) (xy 94.990198 -422.810069) (xy 94.871078 -422.95898) (xy 94.745786 -423.102737)
			(xy 94.614545 -423.241085) (xy 94.477589 -423.373776) (xy 94.335161 -423.500577) (xy 94.187513 -423.62126)
			(xy 94.03491 -423.735612) (xy 93.877622 -423.843428) (xy 93.715928 -423.944519) (xy 93.550116 -424.038703)
			(xy 93.380481 -424.125813) (xy 93.207325 -424.205694) (xy 93.030955 -424.278205) (xy 92.851685 -424.343216)
			(xy 92.669834 -424.400612) (xy 92.485725 -424.450291) (xy 92.299685 -424.492164) (xy 92.112046 -424.526157)
			(xy 91.92314 -424.55221) (xy 91.733304 -424.570276) (xy 91.542875 -424.580323) (xy 91.352192 -424.582333)
			(xy 91.161593 -424.576303) (xy 90.971419 -424.562244) (xy 90.782006 -424.540179) (xy 90.593691 -424.51015)
			(xy 90.40681 -424.472208) (xy 90.221694 -424.426422) (xy 90.038674 -424.372873) (xy 89.858073 -424.311655)
			(xy 89.680214 -424.242879) (xy 89.505412 -424.166666) (xy 89.333978 -424.083152) (xy 89.166218 -423.992485)
			(xy 89.002429 -423.894826) (xy 88.842902 -423.790349) (xy 88.687921 -423.67924) (xy 88.537763 -423.561697)
			(xy 88.392693 -423.437927) (xy 88.252969 -423.308152) (xy 88.118841 -423.172603) (xy 87.990547 -423.031519)
			(xy 87.868313 -422.885152) (xy 87.752359 -422.733763) (xy 87.64289 -422.57762) (xy 87.540101 -422.417001)
			(xy 87.444175 -422.252191) (xy 87.355281 -422.083484) (xy 87.273579 -421.911179) (xy 87.199213 -421.735584)
			(xy 87.132315 -421.557009) (xy 87.073005 -421.375773) (xy 87.021388 -421.192198) (xy 86.977556 -421.00661)
			(xy 86.941587 -420.81934) (xy 86.913544 -420.630719) (xy 86.893478 -420.441084) (xy 86.881424 -420.250771)
			(xy 86.877404 -420.06012) (xy 1.016 -420.06012) (xy 1.016 -430.149762) (xy 72.857112 -430.149762)
			(xy 72.861127 -429.94658) (xy 72.873166 -429.743715) (xy 72.89321 -429.541485) (xy 72.921228 -429.340204)
			(xy 72.957176 -429.140187) (xy 73.000998 -428.941746) (xy 73.052625 -428.745192) (xy 73.111977 -428.550831)
			(xy 73.178962 -428.358966) (xy 73.253474 -428.169897) (xy 73.335397 -427.98392) (xy 73.424604 -427.801324)
			(xy 73.520955 -427.622395) (xy 73.624299 -427.447413) (xy 73.734476 -427.27665) (xy 73.851313 -427.110372)
			(xy 73.974628 -426.948841) (xy 74.104228 -426.792307) (xy 74.239911 -426.641016) (xy 74.381466 -426.495203)
			(xy 74.52867 -426.355096) (xy 74.681294 -426.220914) (xy 74.839101 -426.092866) (xy 75.001843 -425.971153)
			(xy 75.169266 -425.855965) (xy 75.341109 -425.74748) (xy 75.517104 -425.645869) (xy 75.696976 -425.551291)
			(xy 75.880444 -425.463892) (xy 76.067222 -425.38381) (xy 76.257018 -425.31117) (xy 76.449535 -425.246084)
			(xy 76.644473 -425.188655) (xy 76.841528 -425.138972) (xy 77.040392 -425.097112) (xy 77.240754 -425.063142)
			(xy 77.442302 -425.037114) (xy 77.644721 -425.019069) (xy 77.847694 -425.009035) (xy 78.050906 -425.007027)
			(xy 78.254038 -425.013049) (xy 78.456774 -425.027092) (xy 78.658797 -425.049133) (xy 78.859791 -425.079138)
			(xy 79.059443 -425.11706) (xy 79.257441 -425.16284) (xy 79.453476 -425.216406) (xy 79.647241 -425.277676)
			(xy 79.838435 -425.346552) (xy 80.026758 -425.422929) (xy 80.211917 -425.506685) (xy 80.393623 -425.597692)
			(xy 80.571591 -425.695805) (xy 80.745544 -425.800874) (xy 80.915211 -425.912732) (xy 81.080325 -426.031206)
			(xy 81.240631 -426.156111) (xy 81.395877 -426.287251) (xy 81.54582 -426.424422) (xy 81.690228 -426.56741)
			(xy 81.828873 -426.715991) (xy 81.961541 -426.869934) (xy 82.088023 -427.028997) (xy 82.208123 -427.192934)
			(xy 82.321652 -427.361487) (xy 82.428433 -427.534394) (xy 82.5283 -427.711384) (xy 82.621097 -427.892181)
			(xy 82.706679 -428.076504) (xy 82.784912 -428.264063) (xy 82.855674 -428.454567) (xy 82.918855 -428.647718)
			(xy 82.974355 -428.843214) (xy 83.022089 -429.04075) (xy 83.061982 -429.240018) (xy 83.093971 -429.440706)
			(xy 83.118007 -429.642501) (xy 83.134052 -429.845088) (xy 83.14208 -430.048151) (xy 83.142582 -430.149762)
			(xy 83.14208 -430.251373) (xy 83.134052 -430.454436) (xy 83.118007 -430.657023) (xy 83.093971 -430.858818)
			(xy 83.061982 -431.059506) (xy 83.022089 -431.258774) (xy 82.974355 -431.45631) (xy 82.918855 -431.651806)
			(xy 82.855674 -431.844957) (xy 82.784912 -432.035461) (xy 82.706679 -432.22302) (xy 82.621097 -432.407343)
			(xy 82.5283 -432.58814) (xy 82.428433 -432.76513) (xy 82.321652 -432.938037) (xy 82.208123 -433.10659)
			(xy 82.088023 -433.270527) (xy 81.961541 -433.42959) (xy 81.828873 -433.583533) (xy 81.690228 -433.732114)
			(xy 81.54582 -433.875102) (xy 81.395877 -434.012273) (xy 81.240631 -434.143413) (xy 81.080325 -434.268318)
			(xy 80.915211 -434.386792) (xy 80.745544 -434.49865) (xy 80.571591 -434.603719) (xy 80.393623 -434.701832)
			(xy 80.211917 -434.792839) (xy 80.026758 -434.876595) (xy 79.838435 -434.952972) (xy 79.647241 -435.021848)
			(xy 79.453476 -435.083118) (xy 79.257441 -435.136684) (xy 79.059443 -435.182464) (xy 78.859791 -435.220386)
			(xy 78.658797 -435.250391) (xy 78.456774 -435.272432) (xy 78.254038 -435.286475) (xy 78.050906 -435.292497)
			(xy 77.847694 -435.290489) (xy 77.644721 -435.280455) (xy 77.442302 -435.26241) (xy 77.240754 -435.236382)
			(xy 77.040392 -435.202412) (xy 76.841528 -435.160552) (xy 76.644473 -435.110869) (xy 76.449535 -435.05344)
			(xy 76.257018 -434.988354) (xy 76.067222 -434.915714) (xy 75.880444 -434.835632) (xy 75.696976 -434.748233)
			(xy 75.517104 -434.653655) (xy 75.341109 -434.552044) (xy 75.169266 -434.443559) (xy 75.001843 -434.328371)
			(xy 74.839101 -434.206658) (xy 74.681294 -434.07861) (xy 74.52867 -433.944428) (xy 74.381466 -433.804321)
			(xy 74.239911 -433.658508) (xy 74.104228 -433.507217) (xy 73.974628 -433.350683) (xy 73.851313 -433.189152)
			(xy 73.734476 -433.022874) (xy 73.624299 -432.852111) (xy 73.520955 -432.677129) (xy 73.424604 -432.4982)
			(xy 73.335397 -432.315604) (xy 73.253474 -432.129627) (xy 73.178962 -431.940558) (xy 73.111977 -431.748693)
			(xy 73.052625 -431.554332) (xy 73.000998 -431.357778) (xy 72.957176 -431.159337) (xy 72.921228 -430.95932)
			(xy 72.89321 -430.758039) (xy 72.873166 -430.555809) (xy 72.861127 -430.352944) (xy 72.857112 -430.149762)
			(xy 1.016 -430.149762) (xy 1.016 -431.471578) (xy 1.016492 -431.486921) (xy 1.023881 -431.516707)
			(xy 1.038164 -431.54387) (xy 1.048004 -431.555652) (xy 1.065976 -431.576695) (xy 1.09629 -431.622991)
			(xy 1.119599 -431.67318) (xy 1.135415 -431.72621) (xy 1.143407 -431.780967) (xy 1.143407 -431.836305)
			(xy 1.135415 -431.891062) (xy 1.119599 -431.944092) (xy 1.09629 -431.994281) (xy 1.065976 -432.040577)
			(xy 1.048004 -432.06162) (xy 1.03813 -432.073379) (xy 1.023835 -432.100546) (xy 1.01646 -432.130345)
			(xy 1.016 -432.145694) (xy 1.016 -444.171578) (xy 1.016492 -444.186921) (xy 1.023881 -444.216707)
			(xy 1.038164 -444.24387) (xy 1.048004 -444.255652) (xy 1.065976 -444.276695) (xy 1.09629 -444.322991)
			(xy 1.119599 -444.37318) (xy 1.135415 -444.42621) (xy 1.143407 -444.480967) (xy 1.143407 -444.536305)
			(xy 1.135415 -444.591062) (xy 1.119599 -444.644092) (xy 1.09629 -444.694281) (xy 1.065976 -444.740577)
			(xy 1.048004 -444.76162) (xy 1.03813 -444.773379) (xy 1.023835 -444.800546) (xy 1.01646 -444.830345)
			(xy 1.016 -444.845694) (xy 1.016 -451.41007) (xy 39.818564 -451.41007) (xy 39.819058 -451.352661)
			(xy 39.826902 -451.238113) (xy 39.842544 -451.124366) (xy 39.865911 -451.011952) (xy 39.896896 -450.901394)
			(xy 39.935352 -450.793209) (xy 39.981101 -450.6879) (xy 40.03393 -450.585958) (xy 40.093592 -450.487859)
			(xy 40.159809 -450.39406) (xy 40.232272 -450.304998) (xy 40.310645 -450.221089) (xy 40.39456 -450.142723)
			(xy 40.483627 -450.070266) (xy 40.577431 -450.004056) (xy 40.675535 -449.944402) (xy 40.777481 -449.891581)
			(xy 40.882793 -449.845839) (xy 40.990981 -449.807391) (xy 41.101541 -449.776415) (xy 41.213957 -449.753056)
			(xy 41.327705 -449.737423) (xy 41.442254 -449.729588) (xy 41.557072 -449.729588) (xy 41.671621 -449.737423)
			(xy 41.785369 -449.753056) (xy 41.897785 -449.776415) (xy 42.008345 -449.807391) (xy 42.116533 -449.845839)
			(xy 42.221845 -449.891581) (xy 42.323791 -449.944402) (xy 42.421895 -450.004056) (xy 42.515699 -450.070266)
			(xy 42.604766 -450.142723) (xy 42.688681 -450.221089) (xy 42.767054 -450.304998) (xy 42.839517 -450.39406)
			(xy 42.905734 -450.487859) (xy 42.965396 -450.585958) (xy 43.018225 -450.6879) (xy 43.063974 -450.793209)
			(xy 43.10243 -450.901394) (xy 43.133415 -451.011952) (xy 43.156782 -451.124366) (xy 43.172424 -451.238113)
			(xy 43.180268 -451.352661) (xy 43.180762 -451.41007) (xy 43.180576 -451.443253) (xy 43.177909 -451.509567)
			(xy 43.175428 -451.542658) (xy 43.170272 -451.600942) (xy 43.152948 -451.716671) (xy 43.127616 -451.830914)
			(xy 43.094401 -451.943119) (xy 43.053462 -452.052742) (xy 43.004999 -452.159253) (xy 42.949245 -452.262135)
			(xy 42.886471 -452.360891) (xy 42.816981 -452.455042) (xy 42.741111 -452.544132) (xy 42.659229 -452.627729)
			(xy 42.571732 -452.70543) (xy 42.500813 -452.76008) (xy 93.154506 -452.76008) (xy 93.158522 -452.64381)
			(xy 93.170549 -452.528095) (xy 93.190531 -452.413485) (xy 93.218373 -452.300526) (xy 93.253942 -452.189758)
			(xy 93.297068 -452.081707) (xy 93.347545 -451.976889) (xy 93.405134 -451.875804) (xy 93.46956 -451.778932)
			(xy 93.540515 -451.686736) (xy 93.617662 -451.599655) (xy 93.700633 -451.518104) (xy 93.789033 -451.442472)
			(xy 93.88244 -451.373118) (xy 93.980409 -451.310375) (xy 94.082473 -451.254539) (xy 94.188147 -451.205878)
			(xy 94.296926 -451.164624) (xy 94.408291 -451.130973) (xy 94.521714 -451.105085) (xy 94.636651 -451.087084)
			(xy 94.752557 -451.077055) (xy 94.868879 -451.075047) (xy 94.985062 -451.081069) (xy 95.100553 -451.095092)
			(xy 95.214801 -451.11705) (xy 95.327262 -451.146837) (xy 95.4374 -451.184312) (xy 95.54469 -451.229297)
			(xy 95.648621 -451.281576) (xy 95.748697 -451.340901) (xy 95.844443 -451.406989) (xy 95.9354 -451.479525)
			(xy 96.021136 -451.558164) (xy 96.101243 -451.64253) (xy 96.175339 -451.732222) (xy 96.243069 -451.826812)
			(xy 96.304113 -451.92585) (xy 96.358178 -452.028863) (xy 96.405008 -452.13536) (xy 96.444379 -452.244835)
			(xy 96.476103 -452.356765) (xy 96.500029 -452.470617) (xy 96.516043 -452.585849) (xy 96.52407 -452.701911)
			(xy 96.524572 -452.76008) (xy 96.52407 -452.818249) (xy 96.516043 -452.934311) (xy 96.500029 -453.049543)
			(xy 96.476103 -453.163395) (xy 96.444379 -453.275325) (xy 96.405008 -453.3848) (xy 96.358178 -453.491297)
			(xy 96.304113 -453.59431) (xy 96.243069 -453.693348) (xy 96.175339 -453.787938) (xy 96.101243 -453.87763)
			(xy 96.021136 -453.961996) (xy 95.9354 -454.040635) (xy 95.844443 -454.113171) (xy 95.748697 -454.179259)
			(xy 95.648621 -454.238584) (xy 95.54469 -454.290863) (xy 95.4374 -454.335848) (xy 95.327262 -454.373323)
			(xy 95.214801 -454.40311) (xy 95.100553 -454.425068) (xy 94.985062 -454.439091) (xy 94.868879 -454.445113)
			(xy 94.752557 -454.443105) (xy 94.636651 -454.433076) (xy 94.521714 -454.415075) (xy 94.408291 -454.389187)
			(xy 94.296926 -454.355536) (xy 94.188147 -454.314282) (xy 94.082473 -454.265621) (xy 93.980409 -454.209785)
			(xy 93.88244 -454.147042) (xy 93.789033 -454.077688) (xy 93.700633 -454.002056) (xy 93.617662 -453.920505)
			(xy 93.540515 -453.833424) (xy 93.46956 -453.741228) (xy 93.405134 -453.644356) (xy 93.347545 -453.543271)
			(xy 93.297068 -453.438453) (xy 93.253942 -453.330402) (xy 93.218373 -453.219634) (xy 93.190531 -453.106675)
			(xy 93.170549 -452.992065) (xy 93.158522 -452.87635) (xy 93.154506 -452.76008) (xy 42.500813 -452.76008)
			(xy 42.479042 -452.776857) (xy 42.381609 -452.841665) (xy 42.279905 -452.89954) (xy 42.174422 -452.950202)
			(xy 42.065671 -452.993404) (xy 41.954179 -453.028939) (xy 41.840485 -453.056634) (xy 41.725141 -453.076354)
			(xy 41.608704 -453.088005) (xy 41.491739 -453.09153) (xy 41.374812 -453.086912) (xy 41.258489 -453.074173)
			(xy 41.143334 -453.053375) (xy 41.029905 -453.024618) (xy 40.91875 -452.988042) (xy 40.810407 -452.943825)
			(xy 40.705403 -452.892179) (xy 40.604244 -452.833356) (xy 40.507421 -452.76764) (xy 40.415403 -452.695349)
			(xy 40.328636 -452.616834) (xy 40.247539 -452.532474) (xy 40.172506 -452.442679) (xy 40.103899 -452.347883)
			(xy 40.042051 -452.248544) (xy 39.987262 -452.145145) (xy 39.939796 -452.038186) (xy 39.899884 -451.928185)
			(xy 39.86772 -451.815674) (xy 39.843457 -451.701199) (xy 39.827215 -451.585313) (xy 39.819072 -451.468579)
			(xy 39.818564 -451.41007) (xy 1.016 -451.41007) (xy 1.016 -456.871578) (xy 1.016492 -456.886921)
			(xy 1.023881 -456.916707) (xy 1.038164 -456.94387) (xy 1.048004 -456.955652) (xy 1.065976 -456.976695)
			(xy 1.09629 -457.022991) (xy 1.119599 -457.07318) (xy 1.135415 -457.12621) (xy 1.143407 -457.180967)
			(xy 1.143407 -457.236305) (xy 1.135415 -457.291062) (xy 1.119599 -457.344092) (xy 1.09629 -457.394281)
			(xy 1.065976 -457.440577) (xy 1.048004 -457.46162) (xy 1.03813 -457.473379) (xy 1.023835 -457.500546)
			(xy 1.01646 -457.530345) (xy 1.016 -457.545694) (xy 1.016 -464.509866) (xy 86.877404 -464.509866)
			(xy 86.881424 -464.319215) (xy 86.893478 -464.128902) (xy 86.913544 -463.939267) (xy 86.941587 -463.750646)
			(xy 86.977556 -463.563376) (xy 87.021388 -463.377788) (xy 87.073005 -463.194213) (xy 87.132315 -463.012977)
			(xy 87.199213 -462.834402) (xy 87.273579 -462.658807) (xy 87.355281 -462.486502) (xy 87.444175 -462.317795)
			(xy 87.540101 -462.152985) (xy 87.64289 -461.992366) (xy 87.752359 -461.836223) (xy 87.868313 -461.684834)
			(xy 87.990547 -461.538467) (xy 88.118841 -461.397383) (xy 88.252969 -461.261834) (xy 88.392693 -461.132059)
			(xy 88.537763 -461.008289) (xy 88.687921 -460.890746) (xy 88.842902 -460.779637) (xy 89.002429 -460.67516)
			(xy 89.166218 -460.577501) (xy 89.333978 -460.486834) (xy 89.505412 -460.40332) (xy 89.680214 -460.327107)
			(xy 89.858073 -460.258331) (xy 90.038674 -460.197113) (xy 90.221694 -460.143564) (xy 90.40681 -460.097778)
			(xy 90.593691 -460.059836) (xy 90.782006 -460.029807) (xy 90.971419 -460.007742) (xy 91.161593 -459.993683)
			(xy 91.352192 -459.987653) (xy 91.542875 -459.989663) (xy 91.733304 -459.99971) (xy 91.92314 -460.017776)
			(xy 92.112046 -460.043829) (xy 92.299685 -460.077822) (xy 92.485725 -460.119695) (xy 92.669834 -460.169374)
			(xy 92.851685 -460.22677) (xy 93.030955 -460.291781) (xy 93.207325 -460.364292) (xy 93.380481 -460.444173)
			(xy 93.550116 -460.531283) (xy 93.715928 -460.625467) (xy 93.877622 -460.726558) (xy 94.03491 -460.834374)
			(xy 94.187513 -460.948726) (xy 94.335161 -461.069409) (xy 94.477589 -461.19621) (xy 94.614545 -461.328901)
			(xy 94.745786 -461.467249) (xy 94.871078 -461.611006) (xy 94.990198 -461.759917) (xy 95.102934 -461.913718)
			(xy 95.209087 -462.072134) (xy 95.308467 -462.234885) (xy 95.400897 -462.40168) (xy 95.486214 -462.572224)
			(xy 95.564266 -462.746212) (xy 95.634913 -462.923337) (xy 95.698031 -463.103282) (xy 95.753507 -463.285728)
			(xy 95.801242 -463.470351) (xy 95.841152 -463.656821) (xy 95.873165 -463.844809) (xy 95.897225 -464.033979)
			(xy 95.913288 -464.223995) (xy 95.921327 -464.414519) (xy 95.92183 -464.509866) (xy 95.921327 -464.605213)
			(xy 95.913288 -464.795737) (xy 95.897225 -464.985753) (xy 95.873165 -465.174923) (xy 95.841152 -465.362911)
			(xy 95.801242 -465.549381) (xy 95.753507 -465.734004) (xy 95.698031 -465.91645) (xy 95.634913 -466.096395)
			(xy 95.564266 -466.27352) (xy 95.486214 -466.447508) (xy 95.400897 -466.618052) (xy 95.308467 -466.784847)
			(xy 95.209087 -466.947598) (xy 95.102934 -467.106014) (xy 94.990198 -467.259815) (xy 94.871078 -467.408726)
			(xy 94.745786 -467.552483) (xy 94.614545 -467.690831) (xy 94.477589 -467.823522) (xy 94.335161 -467.950323)
			(xy 94.187513 -468.071006) (xy 94.03491 -468.185358) (xy 93.877622 -468.293174) (xy 93.715928 -468.394265)
			(xy 93.550116 -468.488449) (xy 93.380481 -468.575559) (xy 93.207325 -468.65544) (xy 93.030955 -468.727951)
			(xy 92.851685 -468.792962) (xy 92.669834 -468.850358) (xy 92.485725 -468.900037) (xy 92.299685 -468.94191)
			(xy 92.112046 -468.975903) (xy 91.92314 -469.001956) (xy 91.733304 -469.020022) (xy 91.542875 -469.030069)
			(xy 91.352192 -469.032079) (xy 91.161593 -469.026049) (xy 90.971419 -469.01199) (xy 90.782006 -468.989925)
			(xy 90.593691 -468.959896) (xy 90.40681 -468.921954) (xy 90.221694 -468.876168) (xy 90.038674 -468.822619)
			(xy 89.858073 -468.761401) (xy 89.680214 -468.692625) (xy 89.505412 -468.616412) (xy 89.333978 -468.532898)
			(xy 89.166218 -468.442231) (xy 89.002429 -468.344572) (xy 88.842902 -468.240095) (xy 88.687921 -468.128986)
			(xy 88.537763 -468.011443) (xy 88.392693 -467.887673) (xy 88.252969 -467.757898) (xy 88.118841 -467.622349)
			(xy 87.990547 -467.481265) (xy 87.868313 -467.334898) (xy 87.752359 -467.183509) (xy 87.64289 -467.027366)
			(xy 87.540101 -466.866747) (xy 87.444175 -466.701937) (xy 87.355281 -466.53323) (xy 87.273579 -466.360925)
			(xy 87.199213 -466.18533) (xy 87.132315 -466.006755) (xy 87.073005 -465.825519) (xy 87.021388 -465.641944)
			(xy 86.977556 -465.456356) (xy 86.941587 -465.269086) (xy 86.913544 -465.080465) (xy 86.893478 -464.89083)
			(xy 86.881424 -464.700517) (xy 86.877404 -464.509866) (xy 1.016 -464.509866) (xy 1.016 -469.571578)
			(xy 1.016492 -469.586921) (xy 1.023881 -469.616707) (xy 1.038164 -469.64387) (xy 1.048004 -469.655652)
			(xy 1.065976 -469.676695) (xy 1.09629 -469.722991) (xy 1.119599 -469.77318) (xy 1.135415 -469.82621)
			(xy 1.143407 -469.880967) (xy 1.143407 -469.936305) (xy 1.135415 -469.991062) (xy 1.119599 -470.044092)
			(xy 1.09629 -470.094281) (xy 1.065976 -470.140577) (xy 1.048004 -470.16162) (xy 1.03813 -470.173379)
			(xy 1.023835 -470.200546) (xy 1.01646 -470.230345) (xy 1.016 -470.245694) (xy 1.016 -471.172032)
			(xy 6.671831 -471.172032) (xy 6.675786 -471.080195) (xy 6.687621 -470.989038) (xy 6.707248 -470.899235)
			(xy 6.734522 -470.811453) (xy 6.769242 -470.726339) (xy 6.81115 -470.644526) (xy 6.859936 -470.566618)
			(xy 6.915239 -470.493193) (xy 6.976649 -470.424793) (xy 7.043711 -470.361926) (xy 7.11593 -470.305056)
			(xy 7.19277 -470.254605) (xy 7.273663 -470.210946) (xy 7.358009 -470.174403) (xy 7.445185 -470.145246)
			(xy 7.534544 -470.123692) (xy 7.625425 -470.109898) (xy 7.717156 -470.103968) (xy 7.809057 -470.105946)
			(xy 7.900448 -470.115817) (xy 7.990652 -470.133507) (xy 8.079001 -470.158887) (xy 8.164841 -470.191767)
			(xy 8.247537 -470.231905) (xy 8.326477 -470.279004) (xy 8.401075 -470.332714) (xy 8.470781 -470.392638)
			(xy 8.535076 -470.458332) (xy 8.593487 -470.52931) (xy 8.645579 -470.605047) (xy 8.690968 -470.684982)
			(xy 8.729318 -470.768522) (xy 8.760343 -470.85505) (xy 8.783816 -470.943925) (xy 8.799562 -471.034489)
			(xy 8.807464 -471.126071) (xy 8.807958 -471.172032) (xy 8.807464 -471.217993) (xy 8.799562 -471.309575)
			(xy 8.783816 -471.400139) (xy 8.760343 -471.489014) (xy 8.729318 -471.575542) (xy 8.690968 -471.659082)
			(xy 8.645579 -471.739017) (xy 8.593487 -471.814754) (xy 8.535076 -471.885732) (xy 8.470781 -471.951426)
			(xy 8.401075 -472.01135) (xy 8.326477 -472.06506) (xy 8.247537 -472.112159) (xy 8.164841 -472.152297)
			(xy 8.079001 -472.185177) (xy 7.990652 -472.210557) (xy 7.900448 -472.228247) (xy 7.809057 -472.238118)
			(xy 7.717156 -472.240096) (xy 7.625425 -472.234166) (xy 7.534544 -472.220372) (xy 7.445185 -472.198818)
			(xy 7.358009 -472.169661) (xy 7.273663 -472.133118) (xy 7.19277 -472.089459) (xy 7.11593 -472.039008)
			(xy 7.043711 -471.982138) (xy 6.976649 -471.919271) (xy 6.915239 -471.850871) (xy 6.859936 -471.777446)
			(xy 6.81115 -471.699538) (xy 6.769242 -471.617725) (xy 6.734522 -471.532611) (xy 6.707248 -471.444829)
			(xy 6.687621 -471.355026) (xy 6.675786 -471.263869) (xy 6.671831 -471.172032) (xy 1.016 -471.172032)
			(xy 1.016 -473.69984) (xy 11.34441 -473.69984) (xy 11.348411 -473.494791) (xy 11.36041 -473.290054)
			(xy 11.380388 -473.085941) (xy 11.408314 -472.882762) (xy 11.444146 -472.680829) (xy 11.48783 -472.480446)
			(xy 11.539298 -472.281921) (xy 11.598473 -472.085555) (xy 11.665264 -471.891648) (xy 11.73957 -471.700494)
			(xy 11.821277 -471.512384) (xy 11.910262 -471.327606) (xy 12.006388 -471.14644) (xy 12.109509 -470.969163)
			(xy 12.219469 -470.796044) (xy 12.336099 -470.627347) (xy 12.459222 -470.463329) (xy 12.588651 -470.30424)
			(xy 12.724188 -470.150322) (xy 12.865627 -470.001808) (xy 13.012754 -469.858927) (xy 13.165342 -469.721894)
			(xy 13.323161 -469.59092) (xy 13.48597 -469.466202) (xy 13.653521 -469.347932) (xy 13.825559 -469.236288)
			(xy 14.001822 -469.131442) (xy 14.182041 -469.033553) (xy 14.365942 -468.94277) (xy 14.553246 -468.859232)
			(xy 14.743666 -468.783064) (xy 14.936912 -468.714384) (xy 15.132692 -468.653296) (xy 15.330705 -468.599894)
			(xy 15.530652 -468.554257) (xy 15.732226 -468.516457) (xy 15.935122 -468.486549) (xy 16.139031 -468.464581)
			(xy 16.343641 -468.450586) (xy 16.548641 -468.444584) (xy 16.75372 -468.446585) (xy 16.958564 -468.456585)
			(xy 17.162863 -468.474571) (xy 17.366304 -468.500513) (xy 17.568577 -468.534374) (xy 17.769376 -468.5761)
			(xy 17.968394 -468.625629) (xy 18.165328 -468.682885) (xy 18.359878 -468.747782) (xy 18.551748 -468.820219)
			(xy 18.740645 -468.900087) (xy 18.926283 -468.987265) (xy 19.108378 -469.081619) (xy 19.286653 -469.183006)
			(xy 19.460836 -469.291271) (xy 19.630663 -469.406249) (xy 19.795875 -469.527767) (xy 19.956219 -469.655637)
			(xy 20.111453 -469.789666) (xy 20.261339 -469.92965) (xy 20.405649 -470.075375) (xy 20.544163 -470.22662)
			(xy 20.676672 -470.383153) (xy 20.802972 -470.544738) (xy 20.922871 -470.711127) (xy 21.036188 -470.882067)
			(xy 21.142748 -471.057299) (xy 21.242391 -471.236554) (xy 21.334964 -471.419561) (xy 21.420326 -471.60604)
			(xy 21.498347 -471.795708) (xy 21.56891 -471.988276) (xy 21.631905 -472.18345) (xy 21.687237 -472.380933)
			(xy 21.734822 -472.580424) (xy 21.774587 -472.781621) (xy 21.806472 -472.984215) (xy 21.830429 -473.1879)
			(xy 21.84642 -473.392364) (xy 21.854422 -473.597296) (xy 21.854922 -473.69984) (xy 21.854422 -473.802384)
			(xy 21.84642 -474.007316) (xy 21.830429 -474.21178) (xy 21.806472 -474.415465) (xy 21.774587 -474.618059)
			(xy 21.734822 -474.819256) (xy 21.687237 -475.018747) (xy 21.631905 -475.21623) (xy 21.56891 -475.411404)
			(xy 21.498347 -475.603972) (xy 21.420326 -475.79364) (xy 21.334964 -475.980119) (xy 21.242391 -476.163126)
			(xy 21.142748 -476.342381) (xy 21.036188 -476.517613) (xy 20.922871 -476.688553) (xy 20.802972 -476.854942)
			(xy 20.676672 -477.016527) (xy 20.544163 -477.17306) (xy 20.405649 -477.324305) (xy 20.261339 -477.47003)
			(xy 20.111453 -477.610014) (xy 19.956219 -477.744043) (xy 19.795875 -477.871913) (xy 19.630663 -477.993431)
			(xy 19.460836 -478.108409) (xy 19.286653 -478.216674) (xy 19.108378 -478.318061) (xy 18.926283 -478.412415)
			(xy 18.740645 -478.499593) (xy 18.551748 -478.579461) (xy 18.359878 -478.651898) (xy 18.165328 -478.716795)
			(xy 17.968394 -478.774051) (xy 17.864503 -478.799906) (xy 74.3839 -478.799906) (xy 74.3839 -477.799908)
			(xy 74.384397 -477.715129) (xy 74.392344 -477.545758) (xy 74.408222 -477.376946) (xy 74.431995 -477.209063)
			(xy 74.46361 -477.04248) (xy 74.503 -476.877561) (xy 74.550075 -476.71467) (xy 74.604735 -476.554164)
			(xy 74.666857 -476.396397) (xy 74.736306 -476.241715) (xy 74.812929 -476.090458) (xy 74.896558 -475.942959)
			(xy 74.987008 -475.799542) (xy 75.084081 -475.660522) (xy 75.187564 -475.526205) (xy 75.297228 -475.396886)
			(xy 75.412834 -475.27285) (xy 75.534126 -475.154368) (xy 75.660839 -475.041702) (xy 75.792693 -474.935099)
			(xy 75.929399 -474.834794) (xy 76.070656 -474.741006) (xy 76.216154 -474.653943) (xy 76.365573 -474.573795)
			(xy 76.518585 -474.500739) (xy 76.674852 -474.434935) (xy 76.834032 -474.376528) (xy 76.995775 -474.325647)
			(xy 77.159725 -474.282402) (xy 77.325522 -474.24689) (xy 77.492801 -474.219188) (xy 77.661195 -474.199358)
			(xy 77.830333 -474.187442) (xy 77.999844 -474.183467) (xy 78.169355 -474.187442) (xy 78.338493 -474.199358)
			(xy 78.506887 -474.219188) (xy 78.674166 -474.24689) (xy 78.839963 -474.282402) (xy 79.003913 -474.325647)
			(xy 79.165656 -474.376528) (xy 79.324836 -474.434935) (xy 79.481103 -474.500739) (xy 79.634115 -474.573795)
			(xy 79.783534 -474.653943) (xy 79.929032 -474.741006) (xy 80.070289 -474.834794) (xy 80.206995 -474.935099)
			(xy 80.338849 -475.041702) (xy 80.465562 -475.154368) (xy 80.586854 -475.27285) (xy 80.70246 -475.396886)
			(xy 80.812124 -475.526205) (xy 80.915607 -475.660522) (xy 81.01268 -475.799542) (xy 81.10313 -475.942959)
			(xy 81.186759 -476.090458) (xy 81.263382 -476.241715) (xy 81.332831 -476.396397) (xy 81.394953 -476.554164)
			(xy 81.449613 -476.71467) (xy 81.496688 -476.877561) (xy 81.536078 -477.04248) (xy 81.567693 -477.209063)
			(xy 81.591466 -477.376946) (xy 81.607344 -477.545758) (xy 81.615291 -477.715129) (xy 81.615788 -477.799908)
			(xy 81.615788 -478.799906) (xy 81.615291 -478.884685) (xy 81.607344 -479.054056) (xy 81.591466 -479.222868)
			(xy 81.567693 -479.390751) (xy 81.536078 -479.557334) (xy 81.496688 -479.722253) (xy 81.449613 -479.885144)
			(xy 81.394953 -480.04565) (xy 81.332831 -480.203417) (xy 81.263382 -480.358099) (xy 81.186759 -480.509356)
			(xy 81.10313 -480.656855) (xy 81.01268 -480.800272) (xy 80.915607 -480.939292) (xy 80.812124 -481.073609)
			(xy 80.70246 -481.202928) (xy 80.586854 -481.326964) (xy 80.465562 -481.445446) (xy 80.338849 -481.558112)
			(xy 80.206995 -481.664715) (xy 80.070289 -481.76502) (xy 79.929032 -481.858808) (xy 79.783534 -481.945871)
			(xy 79.634115 -482.026019) (xy 79.481103 -482.099075) (xy 79.324836 -482.164879) (xy 79.165656 -482.223286)
			(xy 79.003913 -482.274167) (xy 78.839963 -482.317412) (xy 78.674166 -482.352924) (xy 78.506887 -482.380626)
			(xy 78.338493 -482.400456) (xy 78.169355 -482.412372) (xy 77.999844 -482.416347) (xy 77.830333 -482.412372)
			(xy 77.661195 -482.400456) (xy 77.492801 -482.380626) (xy 77.325522 -482.352924) (xy 77.159725 -482.317412)
			(xy 76.995775 -482.274167) (xy 76.834032 -482.223286) (xy 76.674852 -482.164879) (xy 76.518585 -482.099075)
			(xy 76.365573 -482.026019) (xy 76.216154 -481.945871) (xy 76.070656 -481.858808) (xy 75.929399 -481.76502)
			(xy 75.792693 -481.664715) (xy 75.660839 -481.558112) (xy 75.534126 -481.445446) (xy 75.412834 -481.326964)
			(xy 75.297228 -481.202928) (xy 75.187564 -481.073609) (xy 75.084081 -480.939292) (xy 74.987008 -480.800272)
			(xy 74.896558 -480.656855) (xy 74.812929 -480.509356) (xy 74.736306 -480.358099) (xy 74.666857 -480.203417)
			(xy 74.604735 -480.04565) (xy 74.550075 -479.885144) (xy 74.503 -479.722253) (xy 74.46361 -479.557334)
			(xy 74.431995 -479.390751) (xy 74.408222 -479.222868) (xy 74.392344 -479.054056) (xy 74.384397 -478.884685)
			(xy 74.3839 -478.799906) (xy 17.864503 -478.799906) (xy 17.769376 -478.82358) (xy 17.568577 -478.865306)
			(xy 17.366304 -478.899167) (xy 17.162863 -478.925109) (xy 16.958564 -478.943095) (xy 16.75372 -478.953095)
			(xy 16.548641 -478.955096) (xy 16.343641 -478.949094) (xy 16.139031 -478.935099) (xy 15.935122 -478.913131)
			(xy 15.732226 -478.883223) (xy 15.530652 -478.845423) (xy 15.330705 -478.799786) (xy 15.132692 -478.746384)
			(xy 14.936912 -478.685296) (xy 14.743666 -478.616616) (xy 14.553246 -478.540448) (xy 14.365942 -478.45691)
			(xy 14.182041 -478.366127) (xy 14.001822 -478.268238) (xy 13.825559 -478.163392) (xy 13.653521 -478.051748)
			(xy 13.48597 -477.933478) (xy 13.323161 -477.80876) (xy 13.165342 -477.677786) (xy 13.012754 -477.540753)
			(xy 12.865627 -477.397872) (xy 12.724188 -477.249358) (xy 12.588651 -477.09544) (xy 12.459222 -476.936351)
			(xy 12.336099 -476.772333) (xy 12.219469 -476.603636) (xy 12.109509 -476.430517) (xy 12.006388 -476.25324)
			(xy 11.910262 -476.072074) (xy 11.821277 -475.887296) (xy 11.73957 -475.699186) (xy 11.665264 -475.508032)
			(xy 11.598473 -475.314125) (xy 11.539298 -475.117759) (xy 11.48783 -474.919234) (xy 11.444146 -474.718851)
			(xy 11.408314 -474.516918) (xy 11.380388 -474.313739) (xy 11.36041 -474.109626) (xy 11.348411 -473.904889)
			(xy 11.34441 -473.69984) (xy 1.016 -473.69984) (xy 1.016 -480.172014) (xy 6.671831 -480.172014) (xy 6.675786 -480.080177)
			(xy 6.687621 -479.98902) (xy 6.707248 -479.899217) (xy 6.734522 -479.811435) (xy 6.769242 -479.726321)
			(xy 6.81115 -479.644508) (xy 6.859936 -479.5666) (xy 6.915239 -479.493175) (xy 6.976649 -479.424775)
			(xy 7.043711 -479.361908) (xy 7.11593 -479.305038) (xy 7.19277 -479.254587) (xy 7.273663 -479.210928)
			(xy 7.358009 -479.174385) (xy 7.445185 -479.145228) (xy 7.534544 -479.123674) (xy 7.625425 -479.10988)
			(xy 7.717156 -479.10395) (xy 7.809057 -479.105928) (xy 7.900448 -479.115799) (xy 7.990652 -479.133489)
			(xy 8.079001 -479.158869) (xy 8.164841 -479.191749) (xy 8.247537 -479.231887) (xy 8.326477 -479.278986)
			(xy 8.401075 -479.332696) (xy 8.470781 -479.39262) (xy 8.535076 -479.458314) (xy 8.593487 -479.529292)
			(xy 8.645579 -479.605029) (xy 8.690968 -479.684964) (xy 8.729318 -479.768504) (xy 8.760343 -479.855032)
			(xy 8.783816 -479.943907) (xy 8.799562 -480.034471) (xy 8.807464 -480.126053) (xy 8.807958 -480.172014)
			(xy 8.807464 -480.217975) (xy 8.799562 -480.309557) (xy 8.783816 -480.400121) (xy 8.760343 -480.488996)
			(xy 8.729318 -480.575524) (xy 8.690968 -480.659064) (xy 8.645579 -480.738999) (xy 8.593487 -480.814736)
			(xy 8.535076 -480.885714) (xy 8.470781 -480.951408) (xy 8.401075 -481.011332) (xy 8.326477 -481.065042)
			(xy 8.247537 -481.112141) (xy 8.164841 -481.152279) (xy 8.079001 -481.185159) (xy 7.990652 -481.210539)
			(xy 7.900448 -481.228229) (xy 7.809057 -481.2381) (xy 7.717156 -481.240078) (xy 7.625425 -481.234148)
			(xy 7.534544 -481.220354) (xy 7.445185 -481.1988) (xy 7.358009 -481.169643) (xy 7.273663 -481.1331)
			(xy 7.19277 -481.089441) (xy 7.11593 -481.03899) (xy 7.043711 -480.98212) (xy 6.976649 -480.919253)
			(xy 6.915239 -480.850853) (xy 6.859936 -480.777428) (xy 6.81115 -480.69952) (xy 6.769242 -480.617707)
			(xy 6.734522 -480.532593) (xy 6.707248 -480.444811) (xy 6.687621 -480.355008) (xy 6.675786 -480.263851)
			(xy 6.671831 -480.172014) (xy 1.016 -480.172014) (xy 1.016 -482.271578) (xy 1.016492 -482.286921)
			(xy 1.023881 -482.316707) (xy 1.038164 -482.34387) (xy 1.048004 -482.355652) (xy 1.065976 -482.376695)
			(xy 1.09629 -482.422991) (xy 1.119599 -482.47318) (xy 1.135415 -482.52621) (xy 1.143407 -482.580967)
			(xy 1.143407 -482.636305) (xy 1.135415 -482.691062) (xy 1.119599 -482.744092) (xy 1.09629 -482.794281)
			(xy 1.065976 -482.840577) (xy 1.048004 -482.86162) (xy 1.03813 -482.873379) (xy 1.023835 -482.900546)
			(xy 1.01646 -482.930345) (xy 1.016 -482.945694) (xy 1.016 -491.999778) (xy 6.671831 -491.999778)
			(xy 6.675786 -491.907941) (xy 6.687621 -491.816784) (xy 6.707248 -491.726981) (xy 6.734522 -491.639199)
			(xy 6.769242 -491.554085) (xy 6.81115 -491.472272) (xy 6.859936 -491.394364) (xy 6.915239 -491.320939)
			(xy 6.976649 -491.252539) (xy 7.043711 -491.189672) (xy 7.11593 -491.132802) (xy 7.19277 -491.082351)
			(xy 7.273663 -491.038692) (xy 7.358009 -491.002149) (xy 7.445185 -490.972992) (xy 7.534544 -490.951438)
			(xy 7.625425 -490.937644) (xy 7.717156 -490.931714) (xy 7.809057 -490.933692) (xy 7.900448 -490.943563)
			(xy 7.990652 -490.961253) (xy 8.079001 -490.986633) (xy 8.164841 -491.019513) (xy 8.247537 -491.059651)
			(xy 8.326477 -491.10675) (xy 8.401075 -491.16046) (xy 8.470781 -491.220384) (xy 8.535076 -491.286078)
			(xy 8.593487 -491.357056) (xy 8.645579 -491.432793) (xy 8.690968 -491.512728) (xy 8.729318 -491.596268)
			(xy 8.760343 -491.682796) (xy 8.783816 -491.771671) (xy 8.799562 -491.862235) (xy 8.807464 -491.953817)
			(xy 8.807958 -491.999778) (xy 8.807464 -492.045739) (xy 8.799562 -492.137321) (xy 8.783816 -492.227885)
			(xy 8.760343 -492.31676) (xy 8.729318 -492.403288) (xy 8.690968 -492.486828) (xy 8.645579 -492.566763)
			(xy 8.593487 -492.6425) (xy 8.535076 -492.713478) (xy 8.470781 -492.779172) (xy 8.401075 -492.839096)
			(xy 8.326477 -492.892806) (xy 8.247537 -492.939905) (xy 8.164841 -492.980043) (xy 8.079001 -493.012923)
			(xy 7.990652 -493.038303) (xy 7.900448 -493.055993) (xy 7.809057 -493.065864) (xy 7.717156 -493.067842)
			(xy 7.625425 -493.061912) (xy 7.534544 -493.048118) (xy 7.445185 -493.026564) (xy 7.358009 -492.997407)
			(xy 7.273663 -492.960864) (xy 7.19277 -492.917205) (xy 7.11593 -492.866754) (xy 7.043711 -492.809884)
			(xy 6.976649 -492.747017) (xy 6.915239 -492.678617) (xy 6.859936 -492.605192) (xy 6.81115 -492.527284)
			(xy 6.769242 -492.445471) (xy 6.734522 -492.360357) (xy 6.707248 -492.272575) (xy 6.687621 -492.182772)
			(xy 6.675786 -492.091615) (xy 6.671831 -491.999778) (xy 1.016 -491.999778) (xy 1.016 -494.971578)
			(xy 1.016492 -494.986921) (xy 1.023881 -495.016707) (xy 1.038164 -495.04387) (xy 1.048004 -495.055652)
			(xy 1.065976 -495.076695) (xy 1.09629 -495.122991) (xy 1.119599 -495.17318) (xy 1.135415 -495.22621)
			(xy 1.143407 -495.280967) (xy 1.143407 -495.336305) (xy 1.135415 -495.391062) (xy 1.119599 -495.444092)
			(xy 1.09629 -495.494281) (xy 1.065976 -495.540577) (xy 1.048004 -495.56162) (xy 1.03813 -495.573379)
			(xy 1.023835 -495.600546) (xy 1.01646 -495.630345) (xy 1.016 -495.645694) (xy 1.016 -495.86007) (xy 39.818564 -495.86007)
			(xy 39.819058 -495.802661) (xy 39.826902 -495.688113) (xy 39.842544 -495.574366) (xy 39.865911 -495.461952)
			(xy 39.896896 -495.351394) (xy 39.935352 -495.243209) (xy 39.981101 -495.1379) (xy 40.03393 -495.035958)
			(xy 40.093592 -494.937859) (xy 40.159809 -494.84406) (xy 40.232272 -494.754998) (xy 40.310645 -494.671089)
			(xy 40.39456 -494.592723) (xy 40.483627 -494.520266) (xy 40.577431 -494.454056) (xy 40.675535 -494.394402)
			(xy 40.777481 -494.341581) (xy 40.882793 -494.295839) (xy 40.990981 -494.257391) (xy 41.101541 -494.226415)
			(xy 41.213957 -494.203056) (xy 41.327705 -494.187423) (xy 41.442254 -494.179588) (xy 41.557072 -494.179588)
			(xy 41.671621 -494.187423) (xy 41.785369 -494.203056) (xy 41.897785 -494.226415) (xy 42.008345 -494.257391)
			(xy 42.116533 -494.295839) (xy 42.221845 -494.341581) (xy 42.323791 -494.394402) (xy 42.421895 -494.454056)
			(xy 42.515699 -494.520266) (xy 42.604766 -494.592723) (xy 42.688681 -494.671089) (xy 42.767054 -494.754998)
			(xy 42.839517 -494.84406) (xy 42.905734 -494.937859) (xy 42.965396 -495.035958) (xy 43.018225 -495.1379)
			(xy 43.063974 -495.243209) (xy 43.10243 -495.351394) (xy 43.133415 -495.461952) (xy 43.156782 -495.574366)
			(xy 43.172424 -495.688113) (xy 43.180268 -495.802661) (xy 43.180762 -495.86007) (xy 43.180576 -495.893253)
			(xy 43.177909 -495.959567) (xy 43.175428 -495.992658) (xy 43.170272 -496.050942) (xy 43.152948 -496.166671)
			(xy 43.127616 -496.280914) (xy 43.094401 -496.393119) (xy 43.053462 -496.502742) (xy 43.004999 -496.609253)
			(xy 42.949245 -496.712135) (xy 42.886471 -496.810891) (xy 42.816981 -496.905042) (xy 42.741111 -496.994132)
			(xy 42.659229 -497.077729) (xy 42.571732 -497.15543) (xy 42.500813 -497.21008) (xy 93.154506 -497.21008)
			(xy 93.158522 -497.09381) (xy 93.170549 -496.978095) (xy 93.190531 -496.863485) (xy 93.218373 -496.750526)
			(xy 93.253942 -496.639758) (xy 93.297068 -496.531707) (xy 93.347545 -496.426889) (xy 93.405134 -496.325804)
			(xy 93.46956 -496.228932) (xy 93.540515 -496.136736) (xy 93.617662 -496.049655) (xy 93.700633 -495.968104)
			(xy 93.789033 -495.892472) (xy 93.88244 -495.823118) (xy 93.980409 -495.760375) (xy 94.082473 -495.704539)
			(xy 94.188147 -495.655878) (xy 94.296926 -495.614624) (xy 94.408291 -495.580973) (xy 94.521714 -495.555085)
			(xy 94.636651 -495.537084) (xy 94.752557 -495.527055) (xy 94.868879 -495.525047) (xy 94.985062 -495.531069)
			(xy 95.100553 -495.545092) (xy 95.214801 -495.56705) (xy 95.327262 -495.596837) (xy 95.4374 -495.634312)
			(xy 95.54469 -495.679297) (xy 95.648621 -495.731576) (xy 95.748697 -495.790901) (xy 95.844443 -495.856989)
			(xy 95.9354 -495.929525) (xy 96.021136 -496.008164) (xy 96.101243 -496.09253) (xy 96.175339 -496.182222)
			(xy 96.243069 -496.276812) (xy 96.304113 -496.37585) (xy 96.358178 -496.478863) (xy 96.405008 -496.58536)
			(xy 96.444379 -496.694835) (xy 96.476103 -496.806765) (xy 96.500029 -496.920617) (xy 96.516043 -497.035849)
			(xy 96.52407 -497.151911) (xy 96.524572 -497.21008) (xy 96.52407 -497.268249) (xy 96.516043 -497.384311)
			(xy 96.500029 -497.499543) (xy 96.476103 -497.613395) (xy 96.444379 -497.725325) (xy 96.405008 -497.8348)
			(xy 96.358178 -497.941297) (xy 96.304113 -498.04431) (xy 96.243069 -498.143348) (xy 96.175339 -498.237938)
			(xy 96.101243 -498.32763) (xy 96.021136 -498.411996) (xy 95.9354 -498.490635) (xy 95.844443 -498.563171)
			(xy 95.748697 -498.629259) (xy 95.648621 -498.688584) (xy 95.54469 -498.740863) (xy 95.4374 -498.785848)
			(xy 95.327262 -498.823323) (xy 95.214801 -498.85311) (xy 95.100553 -498.875068) (xy 94.985062 -498.889091)
			(xy 94.868879 -498.895113) (xy 94.752557 -498.893105) (xy 94.636651 -498.883076) (xy 94.521714 -498.865075)
			(xy 94.408291 -498.839187) (xy 94.296926 -498.805536) (xy 94.188147 -498.764282) (xy 94.082473 -498.715621)
			(xy 93.980409 -498.659785) (xy 93.88244 -498.597042) (xy 93.789033 -498.527688) (xy 93.700633 -498.452056)
			(xy 93.617662 -498.370505) (xy 93.540515 -498.283424) (xy 93.46956 -498.191228) (xy 93.405134 -498.094356)
			(xy 93.347545 -497.993271) (xy 93.297068 -497.888453) (xy 93.253942 -497.780402) (xy 93.218373 -497.669634)
			(xy 93.190531 -497.556675) (xy 93.170549 -497.442065) (xy 93.158522 -497.32635) (xy 93.154506 -497.21008)
			(xy 42.500813 -497.21008) (xy 42.479042 -497.226857) (xy 42.381609 -497.291665) (xy 42.279905 -497.34954)
			(xy 42.174422 -497.400202) (xy 42.065671 -497.443404) (xy 41.954179 -497.478939) (xy 41.840485 -497.506634)
			(xy 41.725141 -497.526354) (xy 41.608704 -497.538005) (xy 41.491739 -497.54153) (xy 41.374812 -497.536912)
			(xy 41.258489 -497.524173) (xy 41.143334 -497.503375) (xy 41.029905 -497.474618) (xy 40.91875 -497.438042)
			(xy 40.810407 -497.393825) (xy 40.705403 -497.342179) (xy 40.604244 -497.283356) (xy 40.507421 -497.21764)
			(xy 40.415403 -497.145349) (xy 40.328636 -497.066834) (xy 40.247539 -496.982474) (xy 40.172506 -496.892679)
			(xy 40.103899 -496.797883) (xy 40.042051 -496.698544) (xy 39.987262 -496.595145) (xy 39.939796 -496.488186)
			(xy 39.899884 -496.378185) (xy 39.86772 -496.265674) (xy 39.843457 -496.151199) (xy 39.827215 -496.035313)
			(xy 39.819072 -495.918579) (xy 39.818564 -495.86007) (xy 1.016 -495.86007) (xy 1.016 -500.99976)
			(xy 6.671831 -500.99976) (xy 6.675786 -500.907923) (xy 6.687621 -500.816766) (xy 6.707248 -500.726963)
			(xy 6.734522 -500.639181) (xy 6.769242 -500.554067) (xy 6.81115 -500.472254) (xy 6.859936 -500.394346)
			(xy 6.915239 -500.320921) (xy 6.976649 -500.252521) (xy 7.043711 -500.189654) (xy 7.11593 -500.132784)
			(xy 7.19277 -500.082333) (xy 7.273663 -500.038674) (xy 7.358009 -500.002131) (xy 7.445185 -499.972974)
			(xy 7.534544 -499.95142) (xy 7.625425 -499.937626) (xy 7.717156 -499.931696) (xy 7.809057 -499.933674)
			(xy 7.900448 -499.943545) (xy 7.990652 -499.961235) (xy 8.079001 -499.986615) (xy 8.164841 -500.019495)
			(xy 8.247537 -500.059633) (xy 8.326477 -500.106732) (xy 8.401075 -500.160442) (xy 8.470781 -500.220366)
			(xy 8.535076 -500.28606) (xy 8.593487 -500.357038) (xy 8.645579 -500.432775) (xy 8.690968 -500.51271)
			(xy 8.729318 -500.59625) (xy 8.760343 -500.682778) (xy 8.783816 -500.771653) (xy 8.799562 -500.862217)
			(xy 8.807464 -500.953799) (xy 8.807958 -500.99976) (xy 8.807464 -501.045721) (xy 8.799562 -501.137303)
			(xy 8.783816 -501.227867) (xy 8.760343 -501.316742) (xy 8.729318 -501.40327) (xy 8.690968 -501.48681)
			(xy 8.645579 -501.566745) (xy 8.593487 -501.642482) (xy 8.535076 -501.71346) (xy 8.470781 -501.779154)
			(xy 8.401075 -501.839078) (xy 8.326477 -501.892788) (xy 8.247537 -501.939887) (xy 8.164841 -501.980025)
			(xy 8.079001 -502.012905) (xy 7.990652 -502.038285) (xy 7.900448 -502.055975) (xy 7.809057 -502.065846)
			(xy 7.717156 -502.067824) (xy 7.625425 -502.061894) (xy 7.534544 -502.0481) (xy 7.445185 -502.026546)
			(xy 7.358009 -501.997389) (xy 7.273663 -501.960846) (xy 7.19277 -501.917187) (xy 7.11593 -501.866736)
			(xy 7.043711 -501.809866) (xy 6.976649 -501.746999) (xy 6.915239 -501.678599) (xy 6.859936 -501.605174)
			(xy 6.81115 -501.527266) (xy 6.769242 -501.445453) (xy 6.734522 -501.360339) (xy 6.707248 -501.272557)
			(xy 6.687621 -501.182754) (xy 6.675786 -501.091597) (xy 6.671831 -500.99976) (xy 1.016 -500.99976)
			(xy 1.016 -507.671578) (xy 1.016492 -507.686921) (xy 1.023881 -507.716707) (xy 1.038164 -507.74387)
			(xy 1.048004 -507.755652) (xy 1.065976 -507.776695) (xy 1.09629 -507.822991) (xy 1.119599 -507.87318)
			(xy 1.135415 -507.92621) (xy 1.143407 -507.980967) (xy 1.143407 -508.036305) (xy 1.135415 -508.091062)
			(xy 1.119599 -508.144092) (xy 1.09629 -508.194281) (xy 1.065976 -508.240577) (xy 1.048004 -508.26162)
			(xy 1.03813 -508.273379) (xy 1.023835 -508.300546) (xy 1.01646 -508.330345) (xy 1.016 -508.345694)
			(xy 1.016 -508.96012) (xy 86.877404 -508.96012) (xy 86.881424 -508.769469) (xy 86.893478 -508.579156)
			(xy 86.913544 -508.389521) (xy 86.941587 -508.2009) (xy 86.977556 -508.01363) (xy 87.021388 -507.828042)
			(xy 87.073005 -507.644467) (xy 87.132315 -507.463231) (xy 87.199213 -507.284656) (xy 87.273579 -507.109061)
			(xy 87.355281 -506.936756) (xy 87.444175 -506.768049) (xy 87.540101 -506.603239) (xy 87.64289 -506.44262)
			(xy 87.752359 -506.286477) (xy 87.868313 -506.135088) (xy 87.990547 -505.988721) (xy 88.118841 -505.847637)
			(xy 88.252969 -505.712088) (xy 88.392693 -505.582313) (xy 88.537763 -505.458543) (xy 88.687921 -505.341)
			(xy 88.842902 -505.229891) (xy 89.002429 -505.125414) (xy 89.166218 -505.027755) (xy 89.333978 -504.937088)
			(xy 89.505412 -504.853574) (xy 89.680214 -504.777361) (xy 89.858073 -504.708585) (xy 90.038674 -504.647367)
			(xy 90.221694 -504.593818) (xy 90.40681 -504.548032) (xy 90.593691 -504.51009) (xy 90.782006 -504.480061)
			(xy 90.971419 -504.457996) (xy 91.161593 -504.443937) (xy 91.352192 -504.437907) (xy 91.542875 -504.439917)
			(xy 91.733304 -504.449964) (xy 91.92314 -504.46803) (xy 92.112046 -504.494083) (xy 92.299685 -504.528076)
			(xy 92.485725 -504.569949) (xy 92.669834 -504.619628) (xy 92.851685 -504.677024) (xy 93.030955 -504.742035)
			(xy 93.207325 -504.814546) (xy 93.380481 -504.894427) (xy 93.550116 -504.981537) (xy 93.715928 -505.075721)
			(xy 93.877622 -505.176812) (xy 94.03491 -505.284628) (xy 94.187513 -505.39898) (xy 94.335161 -505.519663)
			(xy 94.477589 -505.646464) (xy 94.614545 -505.779155) (xy 94.745786 -505.917503) (xy 94.871078 -506.06126)
			(xy 94.990198 -506.210171) (xy 95.102934 -506.363972) (xy 95.209087 -506.522388) (xy 95.308467 -506.685139)
			(xy 95.400897 -506.851934) (xy 95.486214 -507.022478) (xy 95.564266 -507.196466) (xy 95.634913 -507.373591)
			(xy 95.698031 -507.553536) (xy 95.753507 -507.735982) (xy 95.801242 -507.920605) (xy 95.841152 -508.107075)
			(xy 95.873165 -508.295063) (xy 95.897225 -508.484233) (xy 95.913288 -508.674249) (xy 95.921327 -508.864773)
			(xy 95.92183 -508.96012) (xy 95.921327 -509.055467) (xy 95.913288 -509.245991) (xy 95.897225 -509.436007)
			(xy 95.873165 -509.625177) (xy 95.841152 -509.813165) (xy 95.801242 -509.999635) (xy 95.753507 -510.184258)
			(xy 95.698031 -510.366704) (xy 95.634913 -510.546649) (xy 95.564266 -510.723774) (xy 95.486214 -510.897762)
			(xy 95.400897 -511.068306) (xy 95.308467 -511.235101) (xy 95.209087 -511.397852) (xy 95.102934 -511.556268)
			(xy 94.990198 -511.710069) (xy 94.871078 -511.85898) (xy 94.745786 -512.002737) (xy 94.614545 -512.141085)
			(xy 94.477589 -512.273776) (xy 94.335161 -512.400577) (xy 94.187513 -512.52126) (xy 94.03491 -512.635612)
			(xy 93.877622 -512.743428) (xy 93.715928 -512.844519) (xy 93.550116 -512.938703) (xy 93.380481 -513.025813)
			(xy 93.207325 -513.105694) (xy 93.030955 -513.178205) (xy 92.851685 -513.243216) (xy 92.669834 -513.300612)
			(xy 92.485725 -513.350291) (xy 92.299685 -513.392164) (xy 92.112046 -513.426157) (xy 91.92314 -513.45221)
			(xy 91.733304 -513.470276) (xy 91.542875 -513.480323) (xy 91.352192 -513.482333) (xy 91.161593 -513.476303)
			(xy 90.971419 -513.462244) (xy 90.782006 -513.440179) (xy 90.593691 -513.41015) (xy 90.40681 -513.372208)
			(xy 90.221694 -513.326422) (xy 90.038674 -513.272873) (xy 89.858073 -513.211655) (xy 89.680214 -513.142879)
			(xy 89.505412 -513.066666) (xy 89.333978 -512.983152) (xy 89.166218 -512.892485) (xy 89.002429 -512.794826)
			(xy 88.842902 -512.690349) (xy 88.687921 -512.57924) (xy 88.537763 -512.461697) (xy 88.392693 -512.337927)
			(xy 88.252969 -512.208152) (xy 88.118841 -512.072603) (xy 87.990547 -511.931519) (xy 87.868313 -511.785152)
			(xy 87.752359 -511.633763) (xy 87.64289 -511.47762) (xy 87.540101 -511.317001) (xy 87.444175 -511.152191)
			(xy 87.355281 -510.983484) (xy 87.273579 -510.811179) (xy 87.199213 -510.635584) (xy 87.132315 -510.457009)
			(xy 87.073005 -510.275773) (xy 87.021388 -510.092198) (xy 86.977556 -509.90661) (xy 86.941587 -509.71934)
			(xy 86.913544 -509.530719) (xy 86.893478 -509.341084) (xy 86.881424 -509.150771) (xy 86.877404 -508.96012)
			(xy 1.016 -508.96012) (xy 1.016 -511.049778) (xy 6.671831 -511.049778) (xy 6.675786 -510.957941)
			(xy 6.687621 -510.866784) (xy 6.707248 -510.776981) (xy 6.734522 -510.689199) (xy 6.769242 -510.604085)
			(xy 6.81115 -510.522272) (xy 6.859936 -510.444364) (xy 6.915239 -510.370939) (xy 6.976649 -510.302539)
			(xy 7.043711 -510.239672) (xy 7.11593 -510.182802) (xy 7.19277 -510.132351) (xy 7.273663 -510.088692)
			(xy 7.358009 -510.052149) (xy 7.445185 -510.022992) (xy 7.534544 -510.001438) (xy 7.625425 -509.987644)
			(xy 7.717156 -509.981714) (xy 7.809057 -509.983692) (xy 7.900448 -509.993563) (xy 7.990652 -510.011253)
			(xy 8.079001 -510.036633) (xy 8.164841 -510.069513) (xy 8.247537 -510.109651) (xy 8.326477 -510.15675)
			(xy 8.401075 -510.21046) (xy 8.470781 -510.270384) (xy 8.535076 -510.336078) (xy 8.593487 -510.407056)
			(xy 8.645579 -510.482793) (xy 8.690968 -510.562728) (xy 8.729318 -510.646268) (xy 8.760343 -510.732796)
			(xy 8.783816 -510.821671) (xy 8.799562 -510.912235) (xy 8.807464 -511.003817) (xy 8.807958 -511.049778)
			(xy 8.807464 -511.095739) (xy 8.799562 -511.187321) (xy 8.783816 -511.277885) (xy 8.760343 -511.36676)
			(xy 8.729318 -511.453288) (xy 8.690968 -511.536828) (xy 8.645579 -511.616763) (xy 8.593487 -511.6925)
			(xy 8.535076 -511.763478) (xy 8.470781 -511.829172) (xy 8.401075 -511.889096) (xy 8.326477 -511.942806)
			(xy 8.247537 -511.989905) (xy 8.164841 -512.030043) (xy 8.079001 -512.062923) (xy 7.990652 -512.088303)
			(xy 7.900448 -512.105993) (xy 7.809057 -512.115864) (xy 7.717156 -512.117842) (xy 7.625425 -512.111912)
			(xy 7.534544 -512.098118) (xy 7.445185 -512.076564) (xy 7.358009 -512.047407) (xy 7.273663 -512.010864)
			(xy 7.19277 -511.967205) (xy 7.11593 -511.916754) (xy 7.043711 -511.859884) (xy 6.976649 -511.797017)
			(xy 6.915239 -511.728617) (xy 6.859936 -511.655192) (xy 6.81115 -511.577284) (xy 6.769242 -511.495471)
			(xy 6.734522 -511.410357) (xy 6.707248 -511.322575) (xy 6.687621 -511.232772) (xy 6.675786 -511.141615)
			(xy 6.671831 -511.049778) (xy 1.016 -511.049778) (xy 1.016 -520.04976) (xy 6.671831 -520.04976) (xy 6.675786 -519.957923)
			(xy 6.687621 -519.866766) (xy 6.707248 -519.776963) (xy 6.734522 -519.689181) (xy 6.769242 -519.604067)
			(xy 6.81115 -519.522254) (xy 6.859936 -519.444346) (xy 6.915239 -519.370921) (xy 6.976649 -519.302521)
			(xy 7.043711 -519.239654) (xy 7.11593 -519.182784) (xy 7.19277 -519.132333) (xy 7.273663 -519.088674)
			(xy 7.358009 -519.052131) (xy 7.445185 -519.022974) (xy 7.534544 -519.00142) (xy 7.625425 -518.987626)
			(xy 7.717156 -518.981696) (xy 7.809057 -518.983674) (xy 7.900448 -518.993545) (xy 7.990652 -519.011235)
			(xy 8.079001 -519.036615) (xy 8.113324 -519.049762) (xy 72.857112 -519.049762) (xy 72.861127 -518.84658)
			(xy 72.873166 -518.643715) (xy 72.89321 -518.441485) (xy 72.921228 -518.240204) (xy 72.957176 -518.040187)
			(xy 73.000998 -517.841746) (xy 73.052625 -517.645192) (xy 73.111977 -517.450831) (xy 73.178962 -517.258966)
			(xy 73.253474 -517.069897) (xy 73.335397 -516.88392) (xy 73.424604 -516.701324) (xy 73.520955 -516.522395)
			(xy 73.624299 -516.347413) (xy 73.734476 -516.17665) (xy 73.851313 -516.010372) (xy 73.974628 -515.848841)
			(xy 74.104228 -515.692307) (xy 74.239911 -515.541016) (xy 74.381466 -515.395203) (xy 74.52867 -515.255096)
			(xy 74.681294 -515.120914) (xy 74.839101 -514.992866) (xy 75.001843 -514.871153) (xy 75.169266 -514.755965)
			(xy 75.341109 -514.64748) (xy 75.517104 -514.545869) (xy 75.696976 -514.451291) (xy 75.880444 -514.363892)
			(xy 76.067222 -514.28381) (xy 76.257018 -514.21117) (xy 76.449535 -514.146084) (xy 76.644473 -514.088655)
			(xy 76.841528 -514.038972) (xy 77.040392 -513.997112) (xy 77.240754 -513.963142) (xy 77.442302 -513.937114)
			(xy 77.644721 -513.919069) (xy 77.847694 -513.909035) (xy 78.050906 -513.907027) (xy 78.254038 -513.913049)
			(xy 78.456774 -513.927092) (xy 78.658797 -513.949133) (xy 78.859791 -513.979138) (xy 79.059443 -514.01706)
			(xy 79.257441 -514.06284) (xy 79.453476 -514.116406) (xy 79.647241 -514.177676) (xy 79.838435 -514.246552)
			(xy 80.026758 -514.322929) (xy 80.211917 -514.406685) (xy 80.393623 -514.497692) (xy 80.571591 -514.595805)
			(xy 80.745544 -514.700874) (xy 80.915211 -514.812732) (xy 81.080325 -514.931206) (xy 81.240631 -515.056111)
			(xy 81.395877 -515.187251) (xy 81.54582 -515.324422) (xy 81.690228 -515.46741) (xy 81.828873 -515.615991)
			(xy 81.961541 -515.769934) (xy 82.088023 -515.928997) (xy 82.208123 -516.092934) (xy 82.321652 -516.261487)
			(xy 82.428433 -516.434394) (xy 82.5283 -516.611384) (xy 82.621097 -516.792181) (xy 82.706679 -516.976504)
			(xy 82.784912 -517.164063) (xy 82.855674 -517.354567) (xy 82.918855 -517.547718) (xy 82.974355 -517.743214)
			(xy 83.022089 -517.94075) (xy 83.061982 -518.140018) (xy 83.093971 -518.340706) (xy 83.118007 -518.542501)
			(xy 83.134052 -518.745088) (xy 83.14208 -518.948151) (xy 83.142582 -519.049762) (xy 83.14208 -519.151373)
			(xy 83.134052 -519.354436) (xy 83.118007 -519.557023) (xy 83.093971 -519.758818) (xy 83.061982 -519.959506)
			(xy 83.022089 -520.158774) (xy 82.974355 -520.35631) (xy 82.918855 -520.551806) (xy 82.855674 -520.744957)
			(xy 82.784912 -520.935461) (xy 82.706679 -521.12302) (xy 82.621097 -521.307343) (xy 82.5283 -521.48814)
			(xy 82.428433 -521.66513) (xy 82.321652 -521.838037) (xy 82.208123 -522.00659) (xy 82.088023 -522.170527)
			(xy 81.961541 -522.32959) (xy 81.828873 -522.483533) (xy 81.690228 -522.632114) (xy 81.54582 -522.775102)
			(xy 81.395877 -522.912273) (xy 81.240631 -523.043413) (xy 81.080325 -523.168318) (xy 80.915211 -523.286792)
			(xy 80.745544 -523.39865) (xy 80.571591 -523.503719) (xy 80.393623 -523.601832) (xy 80.211917 -523.692839)
			(xy 80.026758 -523.776595) (xy 79.838435 -523.852972) (xy 79.647241 -523.921848) (xy 79.453476 -523.983118)
			(xy 79.257441 -524.036684) (xy 79.059443 -524.082464) (xy 78.859791 -524.120386) (xy 78.658797 -524.150391)
			(xy 78.456774 -524.172432) (xy 78.254038 -524.186475) (xy 78.050906 -524.192497) (xy 77.847694 -524.190489)
			(xy 77.644721 -524.180455) (xy 77.442302 -524.16241) (xy 77.240754 -524.136382) (xy 77.040392 -524.102412)
			(xy 76.841528 -524.060552) (xy 76.644473 -524.010869) (xy 76.449535 -523.95344) (xy 76.257018 -523.888354)
			(xy 76.067222 -523.815714) (xy 75.880444 -523.735632) (xy 75.696976 -523.648233) (xy 75.517104 -523.553655)
			(xy 75.341109 -523.452044) (xy 75.169266 -523.343559) (xy 75.001843 -523.228371) (xy 74.839101 -523.106658)
			(xy 74.681294 -522.97861) (xy 74.52867 -522.844428) (xy 74.381466 -522.704321) (xy 74.239911 -522.558508)
			(xy 74.104228 -522.407217) (xy 73.974628 -522.250683) (xy 73.851313 -522.089152) (xy 73.734476 -521.922874)
			(xy 73.624299 -521.752111) (xy 73.520955 -521.577129) (xy 73.424604 -521.3982) (xy 73.335397 -521.215604)
			(xy 73.253474 -521.029627) (xy 73.178962 -520.840558) (xy 73.111977 -520.648693) (xy 73.052625 -520.454332)
			(xy 73.000998 -520.257778) (xy 72.957176 -520.059337) (xy 72.921228 -519.85932) (xy 72.89321 -519.658039)
			(xy 72.873166 -519.455809) (xy 72.861127 -519.252944) (xy 72.857112 -519.049762) (xy 8.113324 -519.049762)
			(xy 8.164841 -519.069495) (xy 8.247537 -519.109633) (xy 8.326477 -519.156732) (xy 8.401075 -519.210442)
			(xy 8.470781 -519.270366) (xy 8.535076 -519.33606) (xy 8.593487 -519.407038) (xy 8.645579 -519.482775)
			(xy 8.690968 -519.56271) (xy 8.729318 -519.64625) (xy 8.760343 -519.732778) (xy 8.783816 -519.821653)
			(xy 8.799562 -519.912217) (xy 8.807464 -520.003799) (xy 8.807958 -520.04976) (xy 8.807464 -520.095721)
			(xy 8.799562 -520.187303) (xy 8.783816 -520.277867) (xy 8.760343 -520.366742) (xy 8.729318 -520.45327)
			(xy 8.690968 -520.53681) (xy 8.645579 -520.616745) (xy 8.593487 -520.692482) (xy 8.535076 -520.76346)
			(xy 8.470781 -520.829154) (xy 8.401075 -520.889078) (xy 8.326477 -520.942788) (xy 8.247537 -520.989887)
			(xy 8.164841 -521.030025) (xy 8.079001 -521.062905) (xy 7.990652 -521.088285) (xy 7.900448 -521.105975)
			(xy 7.809057 -521.115846) (xy 7.717156 -521.117824) (xy 7.625425 -521.111894) (xy 7.534544 -521.0981)
			(xy 7.445185 -521.076546) (xy 7.358009 -521.047389) (xy 7.273663 -521.010846) (xy 7.19277 -520.967187)
			(xy 7.11593 -520.916736) (xy 7.043711 -520.859866) (xy 6.976649 -520.796999) (xy 6.915239 -520.728599)
			(xy 6.859936 -520.655174) (xy 6.81115 -520.577266) (xy 6.769242 -520.495453) (xy 6.734522 -520.410339)
			(xy 6.707248 -520.322557) (xy 6.687621 -520.232754) (xy 6.675786 -520.141597) (xy 6.671831 -520.04976)
			(xy 1.016 -520.04976) (xy 1.016 -520.371578) (xy 1.016492 -520.386921) (xy 1.023881 -520.416707)
			(xy 1.038164 -520.44387) (xy 1.048004 -520.455652) (xy 1.065976 -520.476695) (xy 1.09629 -520.522991)
			(xy 1.119599 -520.57318) (xy 1.135415 -520.62621) (xy 1.143407 -520.680967) (xy 1.143407 -520.736305)
			(xy 1.135415 -520.791062) (xy 1.119599 -520.844092) (xy 1.09629 -520.894281) (xy 1.065976 -520.940577)
			(xy 1.048004 -520.96162) (xy 1.03813 -520.973379) (xy 1.023835 -521.000546) (xy 1.01646 -521.030345)
			(xy 1.016 -521.045694) (xy 1.016 -524.500094) (xy 1.016496 -524.531776) (xy 1.024766 -524.594598)
			(xy 1.041166 -524.655803) (xy 1.065414 -524.714344) (xy 1.097096 -524.769219) (xy 1.13567 -524.819489)
			(xy 1.180475 -524.864294) (xy 1.230745 -524.902868) (xy 1.28562 -524.93455) (xy 1.344161 -524.958798)
			(xy 1.405366 -524.975198) (xy 1.468188 -524.983468) (xy 1.49987 -524.983964) (xy 6.478778 -524.983964)
			(xy 6.494104 -524.9835) (xy 6.523871 -524.976184) (xy 6.551041 -524.961993) (xy 6.562852 -524.952214)
			(xy 6.58388 -524.934272) (xy 6.630136 -524.904011) (xy 6.680275 -524.880743) (xy 6.733248 -524.864955)
			(xy 6.787944 -524.856977) (xy 6.84322 -524.856977) (xy 6.897916 -524.864955) (xy 6.950889 -524.880743)
			(xy 7.001028 -524.904011) (xy 7.047284 -524.934272) (xy 7.068312 -524.952214) (xy 7.080084 -524.962052)
			(xy 7.10726 -524.976271) (xy 7.13705 -524.98357) (xy 7.152386 -524.983964) (xy 19.178778 -524.983964)
			(xy 19.194104 -524.9835) (xy 19.223871 -524.976184) (xy 19.251041 -524.961993) (xy 19.262852 -524.952214)
			(xy 19.28388 -524.934272) (xy 19.330136 -524.904011) (xy 19.380275 -524.880743) (xy 19.433248 -524.864955)
			(xy 19.487944 -524.856977) (xy 19.54322 -524.856977) (xy 19.597916 -524.864955) (xy 19.650889 -524.880743)
			(xy 19.701028 -524.904011) (xy 19.747284 -524.934272) (xy 19.768312 -524.952214) (xy 19.780084 -524.962052)
			(xy 19.80726 -524.976271) (xy 19.83705 -524.98357) (xy 19.852386 -524.983964) (xy 23.50008 -524.983964)
			(xy 23.570659 -524.984449) (xy 23.711596 -524.992364) (xy 23.851867 -525.008169) (xy 23.991032 -525.031814)
			(xy 24.128651 -525.063226) (xy 24.264293 -525.102306) (xy 24.397529 -525.14893) (xy 24.527942 -525.202952)
			(xy 24.65512 -525.264202) (xy 24.778663 -525.332488) (xy 24.898183 -525.407593) (xy 25.013303 -525.489282)
			(xy 25.123662 -525.577298) (xy 25.228911 -525.671364) (xy 25.32872 -525.771184) (xy 25.422775 -525.876443)
			(xy 25.510779 -525.986811) (xy 25.592456 -526.10194) (xy 25.667549 -526.221468) (xy 25.735821 -526.345018)
			(xy 25.797057 -526.472203) (xy 25.851065 -526.602621) (xy 25.897675 -526.735863) (xy 25.93674 -526.871508)
			(xy 25.968138 -527.009131) (xy 25.991769 -527.148298) (xy 26.007559 -527.288571) (xy 26.015458 -527.429509)
			(xy 26.01595 -527.500088) (xy 26.01595 -528.500086) (xy 26.016486 -528.531772) (xy 26.024792 -528.594597)
			(xy 26.041223 -528.655801) (xy 26.065499 -528.714339) (xy 26.097206 -528.769209) (xy 26.135801 -528.819472)
			(xy 26.180623 -528.864271) (xy 26.230908 -528.902839) (xy 26.285794 -528.934516) (xy 26.344345 -528.958761)
			(xy 26.405558 -528.975159) (xy 26.468388 -528.983431) (xy 26.500074 -528.983956)
		)
		(stroke
			(width 0)
			(type solid)
		)
		(fill yes)
		(layer "In4.Cu")
		(net "P12V")
	)
	(gr_arc
		(start 1.500124 -3.999992)
		(mid 0.439376 -4.439368)
		(end 0 -5.500116)
		(stroke
			(width 0.2)
			(type default)
		)
		(layer "In4.Cu")
	)
	(gr_arc
		(start 1.500124 -3.999992)
		(mid 0.439376 -4.439368)
		(end 0 -5.500116)
		(stroke
			(width 2.032)
			(type default)
		)
		(layer "In4.Cu")
	)
	(gr_line
		(start 1.500124 -3.999992)
		(end 23.50008 -3.999992)
		(stroke
			(width 0.2)
			(type default)
		)
		(layer "In4.Cu")
	)
	(gr_line
		(start 1.500124 -3.999992)
		(end 23.50008 -3.999992)
		(stroke
			(width 2.032)
			(type default)
		)
		(layer "In4.Cu")
	)
	(gr_line
		(start 16.459708 -384.696462)
		(end 16.64716 -384.696462)
		(stroke
			(width 2.54)
			(type default)
		)
		(layer "In4.Cu")
	)
	(gr_line
		(start 16.459708 -29.096462)
		(end 16.64716 -29.096462)
		(stroke
			(width 2.54)
			(type default)
		)
		(layer "In4.Cu")
	)
	(gr_line
		(start 16.459962 -473.596462)
		(end 16.647414 -473.596462)
		(stroke
			(width 2.54)
			(type default)
		)
		(layer "In4.Cu")
	)
	(gr_line
		(start 16.459962 -295.796462)
		(end 16.647414 -295.796462)
		(stroke
			(width 2.54)
			(type default)
		)
		(layer "In4.Cu")
	)
	(gr_line
		(start 16.459962 -206.896462)
		(end 16.647414 -206.896462)
		(stroke
			(width 2.54)
			(type default)
		)
		(layer "In4.Cu")
	)
	(gr_line
		(start 16.459962 -117.996462)
		(end 16.647414 -117.996462)
		(stroke
			(width 2.54)
			(type default)
		)
		(layer "In4.Cu")
	)
	(gr_circle
		(center 16.599662 -384.800094)
		(end 17.732756 -384.800094)
		(stroke
			(width 0.508)
			(type default)
		)
		(fill no)
		(layer "In4.Cu")
	)
	(gr_circle
		(center 16.599662 -384.800094)
		(end 18.616676 -384.800094)
		(stroke
			(width 1.27)
			(type default)
		)
		(fill no)
		(layer "In4.Cu")
	)
	(gr_circle
		(center 16.599662 -384.800094)
		(end 20.472146 -384.800094)
		(stroke
			(width 2.54)
			(type default)
		)
		(fill no)
		(layer "In4.Cu")
	)
	(gr_circle
		(center 16.599662 -29.200094)
		(end 17.732756 -29.200094)
		(stroke
			(width 0.508)
			(type default)
		)
		(fill no)
		(layer "In4.Cu")
	)
	(gr_circle
		(center 16.599662 -29.200094)
		(end 18.616676 -29.200094)
		(stroke
			(width 1.27)
			(type default)
		)
		(fill no)
		(layer "In4.Cu")
	)
	(gr_circle
		(center 16.599662 -29.200094)
		(end 20.472146 -29.200094)
		(stroke
			(width 2.54)
			(type default)
		)
		(fill no)
		(layer "In4.Cu")
	)
	(gr_circle
		(center 16.599916 -473.700094)
		(end 17.73301 -473.700094)
		(stroke
			(width 0.508)
			(type default)
		)
		(fill no)
		(layer "In4.Cu")
	)
	(gr_circle
		(center 16.599916 -473.700094)
		(end 18.61693 -473.700094)
		(stroke
			(width 1.27)
			(type default)
		)
		(fill no)
		(layer "In4.Cu")
	)
	(gr_circle
		(center 16.599916 -473.700094)
		(end 20.4724 -473.700094)
		(stroke
			(width 2.54)
			(type default)
		)
		(fill no)
		(layer "In4.Cu")
	)
	(gr_circle
		(center 16.599916 -473.69984)
		(end 21.791422 -473.69984)
		(stroke
			(width 0.127)
			(type default)
		)
		(fill no)
		(layer "In4.Cu")
	)
	(gr_circle
		(center 16.599916 -384.79984)
		(end 21.791676 -384.79984)
		(stroke
			(width 0.127)
			(type default)
		)
		(fill no)
		(layer "In4.Cu")
	)
	(gr_circle
		(center 16.599916 -295.900094)
		(end 17.73301 -295.900094)
		(stroke
			(width 0.508)
			(type default)
		)
		(fill no)
		(layer "In4.Cu")
	)
	(gr_circle
		(center 16.599916 -295.900094)
		(end 18.61693 -295.900094)
		(stroke
			(width 1.27)
			(type default)
		)
		(fill no)
		(layer "In4.Cu")
	)
	(gr_circle
		(center 16.599916 -295.900094)
		(end 20.4724 -295.900094)
		(stroke
			(width 2.54)
			(type default)
		)
		(fill no)
		(layer "In4.Cu")
	)
	(gr_circle
		(center 16.599916 -295.89984)
		(end 21.792184 -295.89984)
		(stroke
			(width 0.127)
			(type default)
		)
		(fill no)
		(layer "In4.Cu")
	)
	(gr_circle
		(center 16.599916 -207.000094)
		(end 17.73301 -207.000094)
		(stroke
			(width 0.508)
			(type default)
		)
		(fill no)
		(layer "In4.Cu")
	)
	(gr_circle
		(center 16.599916 -207.000094)
		(end 18.61693 -207.000094)
		(stroke
			(width 1.27)
			(type default)
		)
		(fill no)
		(layer "In4.Cu")
	)
	(gr_circle
		(center 16.599916 -207.000094)
		(end 20.4724 -207.000094)
		(stroke
			(width 2.54)
			(type default)
		)
		(fill no)
		(layer "In4.Cu")
	)
	(gr_circle
		(center 16.599916 -206.99984)
		(end 21.791676 -206.99984)
		(stroke
			(width 0.127)
			(type default)
		)
		(fill no)
		(layer "In4.Cu")
	)
	(gr_circle
		(center 16.599916 -118.100094)
		(end 17.73301 -118.100094)
		(stroke
			(width 0.508)
			(type default)
		)
		(fill no)
		(layer "In4.Cu")
	)
	(gr_circle
		(center 16.599916 -118.100094)
		(end 18.61693 -118.100094)
		(stroke
			(width 1.27)
			(type default)
		)
		(fill no)
		(layer "In4.Cu")
	)
	(gr_circle
		(center 16.599916 -118.100094)
		(end 20.4724 -118.100094)
		(stroke
			(width 2.54)
			(type default)
		)
		(fill no)
		(layer "In4.Cu")
	)
	(gr_circle
		(center 16.599916 -118.09984)
		(end 21.791422 -118.09984)
		(stroke
			(width 0.127)
			(type default)
		)
		(fill no)
		(layer "In4.Cu")
	)
	(gr_circle
		(center 16.599916 -29.19984)
		(end 21.792438 -29.19984)
		(stroke
			(width 0.127)
			(type default)
		)
		(fill no)
		(layer "In4.Cu")
	)
	(gr_line
		(start 16.64716 -384.696462)
		(end 16.783558 -384.83286)
		(stroke
			(width 2.54)
			(type default)
		)
		(layer "In4.Cu")
	)
	(gr_line
		(start 16.64716 -29.096462)
		(end 16.783558 -29.23286)
		(stroke
			(width 2.54)
			(type default)
		)
		(layer "In4.Cu")
	)
	(gr_line
		(start 16.647414 -473.596462)
		(end 16.783812 -473.73286)
		(stroke
			(width 2.54)
			(type default)
		)
		(layer "In4.Cu")
	)
	(gr_line
		(start 16.647414 -295.796462)
		(end 16.783812 -295.93286)
		(stroke
			(width 2.54)
			(type default)
		)
		(layer "In4.Cu")
	)
	(gr_line
		(start 16.647414 -206.896462)
		(end 16.783812 -207.03286)
		(stroke
			(width 2.54)
			(type default)
		)
		(layer "In4.Cu")
	)
	(gr_line
		(start 16.647414 -117.996462)
		(end 16.783812 -118.13286)
		(stroke
			(width 2.54)
			(type default)
		)
		(layer "In4.Cu")
	)
	(gr_line
		(start 16.655542 -384.986276)
		(end 16.655542 -384.892296)
		(stroke
			(width 2.54)
			(type default)
		)
		(layer "In4.Cu")
	)
	(gr_line
		(start 16.655542 -384.892296)
		(end 16.459708 -384.696462)
		(stroke
			(width 2.54)
			(type default)
		)
		(layer "In4.Cu")
	)
	(gr_line
		(start 16.655542 -29.386276)
		(end 16.655542 -29.292296)
		(stroke
			(width 2.54)
			(type default)
		)
		(layer "In4.Cu")
	)
	(gr_line
		(start 16.655542 -29.292296)
		(end 16.459708 -29.096462)
		(stroke
			(width 2.54)
			(type default)
		)
		(layer "In4.Cu")
	)
	(gr_line
		(start 16.655796 -473.886276)
		(end 16.655796 -473.792296)
		(stroke
			(width 2.54)
			(type default)
		)
		(layer "In4.Cu")
	)
	(gr_line
		(start 16.655796 -473.792296)
		(end 16.459962 -473.596462)
		(stroke
			(width 2.54)
			(type default)
		)
		(layer "In4.Cu")
	)
	(gr_line
		(start 16.655796 -296.086276)
		(end 16.655796 -295.992296)
		(stroke
			(width 2.54)
			(type default)
		)
		(layer "In4.Cu")
	)
	(gr_line
		(start 16.655796 -295.992296)
		(end 16.459962 -295.796462)
		(stroke
			(width 2.54)
			(type default)
		)
		(layer "In4.Cu")
	)
	(gr_line
		(start 16.655796 -207.186276)
		(end 16.655796 -207.092296)
		(stroke
			(width 2.54)
			(type default)
		)
		(layer "In4.Cu")
	)
	(gr_line
		(start 16.655796 -207.092296)
		(end 16.459962 -206.896462)
		(stroke
			(width 2.54)
			(type default)
		)
		(layer "In4.Cu")
	)
	(gr_line
		(start 16.655796 -118.286276)
		(end 16.655796 -118.192296)
		(stroke
			(width 2.54)
			(type default)
		)
		(layer "In4.Cu")
	)
	(gr_line
		(start 16.655796 -118.192296)
		(end 16.459962 -117.996462)
		(stroke
			(width 2.54)
			(type default)
		)
		(layer "In4.Cu")
	)
	(gr_line
		(start 23.50008 -525.999964)
		(end 1.500124 -525.999964)
		(stroke
			(width 0.2)
			(type default)
		)
		(layer "In4.Cu")
	)
	(gr_line
		(start 23.50008 -525.999964)
		(end 1.500124 -525.999964)
		(stroke
			(width 2.032)
			(type default)
		)
		(layer "In4.Cu")
	)
	(gr_arc
		(start 23.50008 -3.999992)
		(mid 24.560648 -3.56069)
		(end 24.99995 -2.500122)
		(stroke
			(width 0.2)
			(type default)
		)
		(layer "In4.Cu")
	)
	(gr_arc
		(start 23.50008 -3.999992)
		(mid 24.560648 -3.56069)
		(end 24.99995 -2.500122)
		(stroke
			(width 2.032)
			(type default)
		)
		(layer "In4.Cu")
	)
	(gr_line
		(start 24.99995 -528.500086)
		(end 24.99995 -527.500088)
		(stroke
			(width 0.2)
			(type default)
		)
		(layer "In4.Cu")
	)
	(gr_line
		(start 24.99995 -528.500086)
		(end 24.99995 -527.500088)
		(stroke
			(width 2.032)
			(type default)
		)
		(layer "In4.Cu")
	)
	(gr_arc
		(start 24.99995 -528.500086)
		(mid 25.439426 -529.560658)
		(end 26.500074 -529.999956)
		(stroke
			(width 0.2)
			(type default)
		)
		(layer "In4.Cu")
	)
	(gr_arc
		(start 24.99995 -528.500086)
		(mid 25.439426 -529.560658)
		(end 26.500074 -529.999956)
		(stroke
			(width 2.032)
			(type default)
		)
		(layer "In4.Cu")
	)
	(gr_arc
		(start 24.99995 -527.500088)
		(mid 24.560738 -526.439356)
		(end 23.50008 -525.999964)
		(stroke
			(width 0.2)
			(type default)
		)
		(layer "In4.Cu")
	)
	(gr_arc
		(start 24.99995 -527.500088)
		(mid 24.560738 -526.439356)
		(end 23.50008 -525.999964)
		(stroke
			(width 2.032)
			(type default)
		)
		(layer "In4.Cu")
	)
	(gr_line
		(start 24.99995 -2.500122)
		(end 24.99995 -1.500124)
		(stroke
			(width 0.2)
			(type default)
		)
		(layer "In4.Cu")
	)
	(gr_line
		(start 24.99995 -2.500122)
		(end 24.99995 -1.500124)
		(stroke
			(width 2.032)
			(type default)
		)
		(layer "In4.Cu")
	)
	(gr_arc
		(start 26.500074 0)
		(mid 25.439325 -0.439375)
		(end 24.99995 -1.500124)
		(stroke
			(width 0.2)
			(type default)
		)
		(layer "In4.Cu")
	)
	(gr_arc
		(start 26.500074 0)
		(mid 25.439325 -0.439375)
		(end 24.99995 -1.500124)
		(stroke
			(width 2.032)
			(type default)
		)
		(layer "In4.Cu")
	)
	(gr_line
		(start 26.500074 0)
		(end 101.000052 0)
		(stroke
			(width 0.2)
			(type default)
		)
		(layer "In4.Cu")
	)
	(gr_line
		(start 26.500074 0)
		(end 101.000052 0)
		(stroke
			(width 2.032)
			(type default)
		)
		(layer "In4.Cu")
	)
	(gr_arc
		(start 75.3999 -478.799906)
		(mid 77.999844 -481.39985)
		(end 80.599788 -478.799906)
		(stroke
			(width 2.032)
			(type default)
		)
		(layer "In4.Cu")
	)
	(gr_line
		(start 75.3999 -477.799908)
		(end 75.3999 -478.799906)
		(stroke
			(width 2.032)
			(type default)
		)
		(layer "In4.Cu")
	)
	(gr_line
		(start 76.752196 -479.517202)
		(end 77.094334 -479.85934)
		(stroke
			(width 2.032)
			(type default)
		)
		(layer "In4.Cu")
	)
	(gr_line
		(start 76.752196 -479.22053)
		(end 76.752196 -479.517202)
		(stroke
			(width 2.032)
			(type default)
		)
		(layer "In4.Cu")
	)
	(gr_line
		(start 76.752196 -479.22053)
		(end 76.752196 -478.216468)
		(stroke
			(width 2.032)
			(type default)
		)
		(layer "In4.Cu")
	)
	(gr_line
		(start 76.752196 -478.216468)
		(end 78.029816 -476.938848)
		(stroke
			(width 2.032)
			(type default)
		)
		(layer "In4.Cu")
	)
	(gr_line
		(start 77.003148 -479.471482)
		(end 76.752196 -479.22053)
		(stroke
			(width 2.032)
			(type default)
		)
		(layer "In4.Cu")
	)
	(gr_line
		(start 77.094334 -479.85934)
		(end 78.143862 -478.809812)
		(stroke
			(width 2.032)
			(type default)
		)
		(layer "In4.Cu")
	)
	(gr_line
		(start 77.85989 -32.196024)
		(end 78.047342 -32.196024)
		(stroke
			(width 2.54)
			(type default)
		)
		(layer "In4.Cu")
	)
	(gr_line
		(start 77.860144 -518.94613)
		(end 78.047596 -518.94613)
		(stroke
			(width 2.54)
			(type default)
		)
		(layer "In4.Cu")
	)
	(gr_line
		(start 77.860144 -430.04613)
		(end 78.047596 -430.04613)
		(stroke
			(width 2.54)
			(type default)
		)
		(layer "In4.Cu")
	)
	(gr_line
		(start 77.860144 -341.14613)
		(end 78.047596 -341.14613)
		(stroke
			(width 2.54)
			(type default)
		)
		(layer "In4.Cu")
	)
	(gr_line
		(start 77.860144 -209.996024)
		(end 78.047596 -209.996024)
		(stroke
			(width 2.54)
			(type default)
		)
		(layer "In4.Cu")
	)
	(gr_line
		(start 77.860398 -121.096024)
		(end 78.04785 -121.096024)
		(stroke
			(width 2.54)
			(type default)
		)
		(layer "In4.Cu")
	)
	(gr_circle
		(center 77.999844 -32.299656)
		(end 79.132938 -32.299656)
		(stroke
			(width 0.508)
			(type default)
		)
		(fill no)
		(layer "In4.Cu")
	)
	(gr_circle
		(center 77.999844 -32.299656)
		(end 80.016858 -32.299656)
		(stroke
			(width 1.27)
			(type default)
		)
		(fill no)
		(layer "In4.Cu")
	)
	(gr_circle
		(center 77.999844 -32.299656)
		(end 81.872328 -32.299656)
		(stroke
			(width 2.54)
			(type default)
		)
		(fill no)
		(layer "In4.Cu")
	)
	(gr_circle
		(center 78.000098 -519.049762)
		(end 79.133192 -519.049762)
		(stroke
			(width 0.508)
			(type default)
		)
		(fill no)
		(layer "In4.Cu")
	)
	(gr_circle
		(center 78.000098 -519.049762)
		(end 80.017112 -519.049762)
		(stroke
			(width 1.27)
			(type default)
		)
		(fill no)
		(layer "In4.Cu")
	)
	(gr_circle
		(center 78.000098 -519.049762)
		(end 81.872582 -519.049762)
		(stroke
			(width 2.54)
			(type default)
		)
		(fill no)
		(layer "In4.Cu")
	)
	(gr_circle
		(center 78.000098 -430.149762)
		(end 79.133192 -430.149762)
		(stroke
			(width 0.508)
			(type default)
		)
		(fill no)
		(layer "In4.Cu")
	)
	(gr_circle
		(center 78.000098 -430.149762)
		(end 80.017112 -430.149762)
		(stroke
			(width 1.27)
			(type default)
		)
		(fill no)
		(layer "In4.Cu")
	)
	(gr_circle
		(center 78.000098 -430.149762)
		(end 81.872582 -430.149762)
		(stroke
			(width 2.54)
			(type default)
		)
		(fill no)
		(layer "In4.Cu")
	)
	(gr_circle
		(center 78.000098 -341.249762)
		(end 79.133192 -341.249762)
		(stroke
			(width 0.508)
			(type default)
		)
		(fill no)
		(layer "In4.Cu")
	)
	(gr_circle
		(center 78.000098 -341.249762)
		(end 80.017112 -341.249762)
		(stroke
			(width 1.27)
			(type default)
		)
		(fill no)
		(layer "In4.Cu")
	)
	(gr_circle
		(center 78.000098 -341.249762)
		(end 81.872582 -341.249762)
		(stroke
			(width 2.54)
			(type default)
		)
		(fill no)
		(layer "In4.Cu")
	)
	(gr_circle
		(center 78.000098 -210.099656)
		(end 79.133192 -210.099656)
		(stroke
			(width 0.508)
			(type default)
		)
		(fill no)
		(layer "In4.Cu")
	)
	(gr_circle
		(center 78.000098 -210.099656)
		(end 80.017112 -210.099656)
		(stroke
			(width 1.27)
			(type default)
		)
		(fill no)
		(layer "In4.Cu")
	)
	(gr_circle
		(center 78.000098 -210.099656)
		(end 81.872582 -210.099656)
		(stroke
			(width 2.54)
			(type default)
		)
		(fill no)
		(layer "In4.Cu")
	)
	(gr_circle
		(center 78.000352 -121.199656)
		(end 79.133446 -121.199656)
		(stroke
			(width 0.508)
			(type default)
		)
		(fill no)
		(layer "In4.Cu")
	)
	(gr_circle
		(center 78.000352 -121.199656)
		(end 80.017366 -121.199656)
		(stroke
			(width 1.27)
			(type default)
		)
		(fill no)
		(layer "In4.Cu")
	)
	(gr_circle
		(center 78.000352 -121.199656)
		(end 81.872836 -121.199656)
		(stroke
			(width 2.54)
			(type default)
		)
		(fill no)
		(layer "In4.Cu")
	)
	(gr_line
		(start 78.029816 -476.938848)
		(end 79.079344 -476.938848)
		(stroke
			(width 2.032)
			(type default)
		)
		(layer "In4.Cu")
	)
	(gr_line
		(start 78.047342 -32.196024)
		(end 78.18374 -32.332422)
		(stroke
			(width 2.54)
			(type default)
		)
		(layer "In4.Cu")
	)
	(gr_line
		(start 78.047596 -518.94613)
		(end 78.183994 -519.082528)
		(stroke
			(width 2.54)
			(type default)
		)
		(layer "In4.Cu")
	)
	(gr_line
		(start 78.047596 -430.04613)
		(end 78.183994 -430.182528)
		(stroke
			(width 2.54)
			(type default)
		)
		(layer "In4.Cu")
	)
	(gr_line
		(start 78.047596 -341.14613)
		(end 78.183994 -341.282528)
		(stroke
			(width 2.54)
			(type default)
		)
		(layer "In4.Cu")
	)
	(gr_line
		(start 78.047596 -209.996024)
		(end 78.183994 -210.132422)
		(stroke
			(width 2.54)
			(type default)
		)
		(layer "In4.Cu")
	)
	(gr_line
		(start 78.04785 -121.096024)
		(end 78.184248 -121.232422)
		(stroke
			(width 2.54)
			(type default)
		)
		(layer "In4.Cu")
	)
	(gr_line
		(start 78.052676 -478.307654)
		(end 78.052676 -478.581466)
		(stroke
			(width 2.032)
			(type default)
		)
		(layer "In4.Cu")
	)
	(gr_line
		(start 78.055724 -32.485838)
		(end 78.055724 -32.391858)
		(stroke
			(width 2.54)
			(type default)
		)
		(layer "In4.Cu")
	)
	(gr_line
		(start 78.055724 -32.391858)
		(end 77.85989 -32.196024)
		(stroke
			(width 2.54)
			(type default)
		)
		(layer "In4.Cu")
	)
	(gr_line
		(start 78.055978 -519.235944)
		(end 78.055978 -519.141964)
		(stroke
			(width 2.54)
			(type default)
		)
		(layer "In4.Cu")
	)
	(gr_line
		(start 78.055978 -519.141964)
		(end 77.860144 -518.94613)
		(stroke
			(width 2.54)
			(type default)
		)
		(layer "In4.Cu")
	)
	(gr_line
		(start 78.055978 -430.335944)
		(end 78.055978 -430.241964)
		(stroke
			(width 2.54)
			(type default)
		)
		(layer "In4.Cu")
	)
	(gr_line
		(start 78.055978 -430.241964)
		(end 77.860144 -430.04613)
		(stroke
			(width 2.54)
			(type default)
		)
		(layer "In4.Cu")
	)
	(gr_line
		(start 78.055978 -341.435944)
		(end 78.055978 -341.341964)
		(stroke
			(width 2.54)
			(type default)
		)
		(layer "In4.Cu")
	)
	(gr_line
		(start 78.055978 -341.341964)
		(end 77.860144 -341.14613)
		(stroke
			(width 2.54)
			(type default)
		)
		(layer "In4.Cu")
	)
	(gr_line
		(start 78.055978 -210.285838)
		(end 78.055978 -210.191858)
		(stroke
			(width 2.54)
			(type default)
		)
		(layer "In4.Cu")
	)
	(gr_line
		(start 78.055978 -210.191858)
		(end 77.860144 -209.996024)
		(stroke
			(width 2.54)
			(type default)
		)
		(layer "In4.Cu")
	)
	(gr_line
		(start 78.056232 -121.385838)
		(end 78.056232 -121.291858)
		(stroke
			(width 2.54)
			(type default)
		)
		(layer "In4.Cu")
	)
	(gr_line
		(start 78.056232 -121.291858)
		(end 77.860398 -121.096024)
		(stroke
			(width 2.54)
			(type default)
		)
		(layer "In4.Cu")
	)
	(gr_line
		(start 78.143862 -478.809812)
		(end 78.143862 -478.216468)
		(stroke
			(width 2.032)
			(type default)
		)
		(layer "In4.Cu")
	)
	(gr_line
		(start 78.143862 -478.216468)
		(end 78.052676 -478.307654)
		(stroke
			(width 2.032)
			(type default)
		)
		(layer "In4.Cu")
	)
	(gr_line
		(start 78.919578 -479.471482)
		(end 77.003148 -479.471482)
		(stroke
			(width 2.032)
			(type default)
		)
		(layer "In4.Cu")
	)
	(gr_line
		(start 79.079344 -476.938848)
		(end 79.330296 -477.1898)
		(stroke
			(width 2.032)
			(type default)
		)
		(layer "In4.Cu")
	)
	(gr_line
		(start 79.330296 -479.060764)
		(end 78.919578 -479.471482)
		(stroke
			(width 2.032)
			(type default)
		)
		(layer "In4.Cu")
	)
	(gr_line
		(start 79.330296 -477.1898)
		(end 79.330296 -479.060764)
		(stroke
			(width 2.032)
			(type default)
		)
		(layer "In4.Cu")
	)
	(gr_line
		(start 80.599788 -478.799906)
		(end 80.599788 -477.799908)
		(stroke
			(width 2.032)
			(type default)
		)
		(layer "In4.Cu")
	)
	(gr_arc
		(start 80.599788 -477.799908)
		(mid 77.999844 -475.199964)
		(end 75.3999 -477.799908)
		(stroke
			(width 2.032)
			(type default)
		)
		(layer "In4.Cu")
	)
	(gr_line
		(start 101.000052 -529.999956)
		(end 26.500074 -529.999956)
		(stroke
			(width 0.2)
			(type default)
		)
		(layer "In4.Cu")
	)
	(gr_line
		(start 101.000052 -529.999956)
		(end 26.500074 -529.999956)
		(stroke
			(width 2.032)
			(type default)
		)
		(layer "In4.Cu")
	)
	(gr_arc
		(start 101.000052 -529.999956)
		(mid 102.41428 -529.414185)
		(end 103.000048 -527.99996)
		(stroke
			(width 0.2)
			(type default)
		)
		(layer "In4.Cu")
	)
	(gr_arc
		(start 101.000052 -529.999956)
		(mid 102.41428 -529.414185)
		(end 103.000048 -527.99996)
		(stroke
			(width 2.032)
			(type default)
		)
		(layer "In4.Cu")
	)
	(gr_arc
		(start 103.000048 -1.999996)
		(mid 102.414258 -0.585805)
		(end 101.000052 0)
		(stroke
			(width 0.2)
			(type default)
		)
		(layer "In4.Cu")
	)
	(gr_arc
		(start 103.000048 -1.999996)
		(mid 102.414258 -0.585805)
		(end 101.000052 0)
		(stroke
			(width 2.032)
			(type default)
		)
		(layer "In4.Cu")
	)
	(gr_line
		(start 103.000048 -1.999996)
		(end 103.000048 -527.99996)
		(stroke
			(width 0.2)
			(type default)
		)
		(layer "In4.Cu")
	)
	(gr_line
		(start 103.000048 -1.999996)
		(end 103.000048 -527.99996)
		(stroke
			(width 2.032)
			(type default)
		)
		(layer "In4.Cu")
	)
	(gr_poly
		(pts
			(xy 19.47672 -372.827042) (xy 19.493367 -372.843009) (xy 19.531305 -372.869237) (xy 19.573352 -372.88819)
			(xy 19.61813 -372.899244) (xy 19.664167 -372.902037) (xy 19.709952 -372.896477) (xy 19.753983 -372.882747)
			(xy 19.794813 -372.861297) (xy 19.831103 -372.832832) (xy 19.86166 -372.798285) (xy 19.885483 -372.758792)
			(xy 19.901788 -372.715649) (xy 19.910041 -372.670272) (xy 19.910552 -372.64721) (xy 19.910552 -351.452688)
			(xy 19.588988 -351.131378) (xy 19.588988 -320.570098) (xy 12.208002 -313.189112) (xy 9.309862 -313.189112)
			(xy 9.286624 -313.189634) (xy 9.240924 -313.198092) (xy 9.197524 -313.214718) (xy 9.15787 -313.238959)
			(xy 9.123285 -313.270006) (xy 9.094922 -313.306824) (xy 9.073727 -313.348186) (xy 9.060405 -313.392712)
			(xy 9.055402 -313.438918) (xy 9.058884 -313.485263) (xy 9.064244 -313.507882) (xy 9.072511 -313.540975)
			(xy 9.082747 -313.608416) (xy 9.085697 -313.676566) (xy 9.081327 -313.74464) (xy 9.069687 -313.811854)
			(xy 9.050913 -313.877433) (xy 9.025219 -313.940623) (xy 8.992902 -314.000696) (xy 8.954333 -314.056959)
			(xy 8.909958 -314.108766) (xy 8.885428 -314.132468) (xy 8.866378 -314.150756) (xy 8.84555 -314.198762)
			(xy 8.84555 -314.224924) (xy 8.846048 -314.241574) (xy 8.854674 -314.273738) (xy 8.871331 -314.302573)
			(xy 8.894886 -314.326114) (xy 8.92373 -314.342755) (xy 8.955899 -314.351362) (xy 8.97255 -314.351924)
			(xy 8.987536 -314.351924) (xy 9.33196 -314.696348) (xy 12.175996 -314.696348) (xy 12.180067 -314.640726)
			(xy 12.192193 -314.586289) (xy 12.212116 -314.534198) (xy 12.239412 -314.485563) (xy 12.273498 -314.44142)
			(xy 12.313647 -314.402711) (xy 12.359005 -314.37026) (xy 12.408605 -314.344759) (xy 12.461389 -314.326752)
			(xy 12.516232 -314.316622) (xy 12.571966 -314.314585) (xy 12.627403 -314.320685) (xy 12.68136 -314.334791)
			(xy 12.732689 -314.356603) (xy 12.780295 -314.385657) (xy 12.823163 -314.421332) (xy 12.86038 -314.462869)
			(xy 12.891153 -314.509382) (xy 12.914825 -314.559879) (xy 12.930893 -314.613286) (xy 12.939013 -314.668462)
			(xy 12.939522 -314.696348) (xy 12.939013 -314.724234) (xy 12.930893 -314.77941) (xy 12.914825 -314.832817)
			(xy 12.891153 -314.883314) (xy 12.86038 -314.929827) (xy 12.823163 -314.971364) (xy 12.780295 -315.007039)
			(xy 12.732689 -315.036093) (xy 12.68136 -315.057905) (xy 12.627403 -315.072011) (xy 12.571966 -315.078111)
			(xy 12.516232 -315.076074) (xy 12.461389 -315.065944) (xy 12.408605 -315.047937) (xy 12.359005 -315.022436)
			(xy 12.313647 -314.989985) (xy 12.273498 -314.951276) (xy 12.239412 -314.907133) (xy 12.212116 -314.858498)
			(xy 12.192193 -314.806407) (xy 12.180067 -314.75197) (xy 12.175996 -314.696348) (xy 9.33196 -314.696348)
			(xy 11.335004 -316.699392) (xy 11.335004 -316.960504) (xy 13.816838 -319.442338) (xy 14.63624 -319.442338)
			(xy 14.640311 -319.386716) (xy 14.652437 -319.332279) (xy 14.67236 -319.280188) (xy 14.699656 -319.231553)
			(xy 14.733742 -319.18741) (xy 14.773891 -319.148701) (xy 14.819249 -319.11625) (xy 14.868849 -319.090749)
			(xy 14.921633 -319.072742) (xy 14.976476 -319.062612) (xy 15.03221 -319.060575) (xy 15.087647 -319.066675)
			(xy 15.141604 -319.080781) (xy 15.192933 -319.102593) (xy 15.240539 -319.131647) (xy 15.283407 -319.167322)
			(xy 15.320624 -319.208859) (xy 15.351397 -319.255372) (xy 15.375069 -319.305869) (xy 15.391137 -319.359276)
			(xy 15.399257 -319.414452) (xy 15.399766 -319.442338) (xy 15.399257 -319.470224) (xy 15.391137 -319.5254)
			(xy 15.375069 -319.578807) (xy 15.351397 -319.629304) (xy 15.320624 -319.675817) (xy 15.283407 -319.717354)
			(xy 15.240539 -319.753029) (xy 15.192933 -319.782083) (xy 15.141604 -319.803895) (xy 15.087647 -319.818001)
			(xy 15.03221 -319.824101) (xy 14.976476 -319.822064) (xy 14.921633 -319.811934) (xy 14.868849 -319.793927)
			(xy 14.819249 -319.768426) (xy 14.773891 -319.735975) (xy 14.733742 -319.697266) (xy 14.699656 -319.653123)
			(xy 14.67236 -319.604488) (xy 14.652437 -319.552397) (xy 14.640311 -319.49796) (xy 14.63624 -319.442338)
			(xy 13.816838 -319.442338) (xy 16.812768 -322.438268) (xy 16.812768 -331.56017) (xy 16.813199 -331.582055)
			(xy 16.820651 -331.625185) (xy 16.83539 -331.666398) (xy 16.856981 -331.704471) (xy 16.884782 -331.738277)
			(xy 16.91797 -331.766813) (xy 16.955561 -331.789233) (xy 16.99644 -331.804872) (xy 17.039397 -331.813268)
			(xy 17.083156 -331.81417) (xy 17.104868 -331.811376) (xy 17.132016 -331.807721) (xy 17.186793 -331.807304)
			(xy 17.241067 -331.814726) (xy 17.293721 -331.829832) (xy 17.343674 -331.852312) (xy 17.389899 -331.881704)
			(xy 17.431446 -331.917405) (xy 17.467461 -331.95868) (xy 17.497203 -332.004681) (xy 17.520061 -332.054462)
			(xy 17.535566 -332.107) (xy 17.543399 -332.161216) (xy 17.543398 -332.215994) (xy 17.535564 -332.27021)
			(xy 17.520058 -332.322748) (xy 17.497198 -332.372528) (xy 17.467454 -332.418528) (xy 17.431439 -332.459802)
			(xy 17.389891 -332.495502) (xy 17.343665 -332.524893) (xy 17.293711 -332.547372) (xy 17.241057 -332.562476)
			(xy 17.186783 -332.569896) (xy 17.132006 -332.569479) (xy 17.104868 -332.565756) (xy 17.083165 -332.562929)
			(xy 17.039413 -332.56388) (xy 16.99647 -332.57231) (xy 16.955605 -332.587969) (xy 16.918025 -332.610395)
			(xy 16.884841 -332.638925) (xy 16.857033 -332.672717) (xy 16.835423 -332.710772) (xy 16.820649 -332.751966)
			(xy 16.813148 -332.795081) (xy 16.812768 -332.816962) (xy 16.812768 -337.363562) (xy 17.484342 -337.363562)
			(xy 17.488413 -337.30794) (xy 17.500539 -337.253503) (xy 17.520462 -337.201412) (xy 17.547758 -337.152777)
			(xy 17.581844 -337.108634) (xy 17.621993 -337.069925) (xy 17.667351 -337.037474) (xy 17.716951 -337.011973)
			(xy 17.769735 -336.993966) (xy 17.824578 -336.983836) (xy 17.880312 -336.981799) (xy 17.935749 -336.987899)
			(xy 17.989706 -337.002005) (xy 18.041035 -337.023817) (xy 18.088641 -337.052871) (xy 18.131509 -337.088546)
			(xy 18.168726 -337.130083) (xy 18.199499 -337.176596) (xy 18.223171 -337.227093) (xy 18.239239 -337.2805)
			(xy 18.247359 -337.335676) (xy 18.247868 -337.363562) (xy 18.247359 -337.391448) (xy 18.239239 -337.446624)
			(xy 18.223171 -337.500031) (xy 18.199499 -337.550528) (xy 18.168726 -337.597041) (xy 18.131509 -337.638578)
			(xy 18.088641 -337.674253) (xy 18.041035 -337.703307) (xy 17.989706 -337.725119) (xy 17.935749 -337.739225)
			(xy 17.880312 -337.745325) (xy 17.824578 -337.743288) (xy 17.769735 -337.733158) (xy 17.716951 -337.715151)
			(xy 17.667351 -337.68965) (xy 17.621993 -337.657199) (xy 17.581844 -337.61849) (xy 17.547758 -337.574347)
			(xy 17.520462 -337.525712) (xy 17.500539 -337.473621) (xy 17.488413 -337.419184) (xy 17.484342 -337.363562)
			(xy 16.812768 -337.363562) (xy 16.812768 -370.162836)
		)
		(stroke
			(width 0)
			(type solid)
		)
		(fill yes)
		(layer "In5.Cu")
		(net "GND")
	)
	(gr_poly
		(pts
			(xy 101.000052 -529.49094) (xy 101.055822 -529.490433) (xy 101.167051 -529.482101) (xy 101.277346 -529.46548)
			(xy 101.38609 -529.440662) (xy 101.492675 -529.407788) (xy 101.596506 -529.367039) (xy 101.697001 -529.318645)
			(xy 101.793598 -529.262876) (xy 101.885758 -529.200044) (xy 101.972964 -529.130501) (xy 102.054729 -529.054635)
			(xy 102.130596 -528.97287) (xy 102.20014 -528.885664) (xy 102.262972 -528.793505) (xy 102.318742 -528.696908)
			(xy 102.367136 -528.596413) (xy 102.407885 -528.492583) (xy 102.44076 -528.385998) (xy 102.465578 -528.277253)
			(xy 102.4822 -528.166959) (xy 102.490533 -528.05573) (xy 102.491032 -527.99996) (xy 102.491032 -1.999996)
			(xy 102.490523 -1.944227) (xy 102.482188 -1.833002) (xy 102.465563 -1.72271) (xy 102.440743 -1.613969)
			(xy 102.407866 -1.507387) (xy 102.367116 -1.40356) (xy 102.31872 -1.303069) (xy 102.26295 -1.206475)
			(xy 102.200118 -1.11432) (xy 102.130574 -1.027117) (xy 102.054708 -0.945356) (xy 101.972944 -0.869492)
			(xy 101.885739 -0.799951) (xy 101.793581 -0.737122) (xy 101.696985 -0.681355) (xy 101.596492 -0.632964)
			(xy 101.492664 -0.592217) (xy 101.386081 -0.559343) (xy 101.277339 -0.534527) (xy 101.167047 -0.517907)
			(xy 101.055821 -0.509575) (xy 101.000052 -0.509016) (xy 26.500074 -0.509016) (xy 26.454278 -0.509546)
			(xy 26.363077 -0.517999) (xy 26.273045 -0.534832) (xy 26.184949 -0.559899) (xy 26.099543 -0.592988)
			(xy 26.017554 -0.633817) (xy 25.939682 -0.682036) (xy 25.866592 -0.737234) (xy 25.798906 -0.798941)
			(xy 25.737202 -0.86663) (xy 25.682007 -0.939724) (xy 25.633792 -1.017598) (xy 25.592968 -1.099589)
			(xy 25.559883 -1.184997) (xy 25.53482 -1.273093) (xy 25.517992 -1.363126) (xy 25.509543 -1.454328)
			(xy 25.508966 -1.500124) (xy 25.508966 -2.500122) (xy 25.50847 -2.563238) (xy 25.500544 -2.689221)
			(xy 25.484723 -2.814458) (xy 25.461069 -2.938455) (xy 25.429676 -3.060721) (xy 25.390668 -3.180775)
			(xy 25.344199 -3.298143) (xy 25.290452 -3.412362) (xy 25.229639 -3.52298) (xy 25.162 -3.629561) (xy 25.087803 -3.731685)
			(xy 25.007339 -3.828949) (xy 24.920927 -3.920968) (xy 24.828907 -4.00738) (xy 24.731644 -4.087844)
			(xy 24.62952 -4.162041) (xy 24.522938 -4.22968) (xy 24.41232 -4.290493) (xy 24.298101 -4.34424) (xy 24.180733 -4.390709)
			(xy 24.060679 -4.429717) (xy 23.938413 -4.46111) (xy 23.814416 -4.484763) (xy 23.689179 -4.500584)
			(xy 23.563196 -4.50851) (xy 23.50008 -4.509008) (xy 1.500124 -4.509008) (xy 1.454327 -4.509537) (xy 1.363123 -4.517988)
			(xy 1.273088 -4.534819) (xy 1.18499 -4.559885) (xy 1.099581 -4.592972) (xy 1.017589 -4.6338) (xy 0.939714 -4.682018)
			(xy 0.86662 -4.737216) (xy 0.798931 -4.798923) (xy 0.737224 -4.866612) (xy 0.682026 -4.939706) (xy 0.633808 -5.017581)
			(xy 0.59298 -5.099573) (xy 0.559893 -5.184982) (xy 0.534827 -5.27308) (xy 0.517996 -5.363115) (xy 0.509545 -5.454319)
			(xy 0.509016 -5.500116) (xy 0.509016 -204.031088) (xy 0.911098 -204.031088) (xy 0.911098 -202.252326)
			(xy 1.015492 -202.147932) (xy 1.015492 -5.514594) (xy 1.01507 -5.482255) (xy 1.021763 -5.417929)
			(xy 1.036946 -5.355063) (xy 1.06035 -5.294772) (xy 1.091558 -5.238126) (xy 1.130019 -5.186131) (xy 1.175048 -5.139708)
			(xy 1.225848 -5.099682) (xy 1.281516 -5.066762) (xy 1.341066 -5.041533) (xy 1.403441 -5.024442) (xy 1.467534 -5.015793)
			(xy 1.49987 -5.01523) (xy 1.500124 -5.01523) (xy 1.500124 -5.015484) (xy 23.266908 -5.015484) (xy 23.266908 -5.01523)
			(xy 23.50008 -5.01523) (xy 23.570631 -5.014727) (xy 23.711511 -5.006802) (xy 23.851725 -4.990991)
			(xy 23.990832 -4.967345) (xy 24.128395 -4.935937) (xy 24.26398 -4.896866) (xy 24.397162 -4.850255)
			(xy 24.527521 -4.796251) (xy 24.654648 -4.735024) (xy 24.778142 -4.666765) (xy 24.897614 -4.591691)
			(xy 25.01269 -4.510037) (xy 25.123008 -4.422059) (xy 25.228219 -4.328035) (xy 25.327994 -4.228261)
			(xy 25.422018 -4.123049) (xy 25.509995 -4.012732) (xy 25.59165 -3.897656) (xy 25.666724 -3.778183)
			(xy 25.734983 -3.654689) (xy 25.796211 -3.527563) (xy 25.850215 -3.397204) (xy 25.896826 -3.264022)
			(xy 25.935897 -3.128437) (xy 25.967305 -2.990874) (xy 25.990951 -2.851767) (xy 26.006762 -2.711553)
			(xy 26.014687 -2.570673) (xy 26.015188 -2.500122) (xy 26.015188 -1.500124) (xy 26.01562 -1.46838)
			(xy 26.023881 -1.405431) (xy 26.04029 -1.3441) (xy 26.064566 -1.285437) (xy 26.096294 -1.230445)
			(xy 26.13493 -1.180067) (xy 26.179813 -1.135165) (xy 26.230175 -1.096507) (xy 26.285154 -1.064756)
			(xy 26.343807 -1.040455) (xy 26.405131 -1.024021) (xy 26.468076 -1.015734) (xy 26.49982 -1.015238)
			(xy 26.500074 -1.015238) (xy 26.500074 -1.015492) (xy 101.000052 -1.015492) (xy 101.045544 -1.016051)
			(xy 101.13614 -1.024442) (xy 101.225575 -1.041156) (xy 101.313087 -1.066052) (xy 101.397928 -1.098916)
			(xy 101.479375 -1.139468) (xy 101.556732 -1.187362) (xy 101.629341 -1.24219) (xy 101.69658 -1.303483)
			(xy 101.757877 -1.370719) (xy 101.812709 -1.443325) (xy 101.860607 -1.52068) (xy 101.901163 -1.602124)
			(xy 101.934032 -1.686964) (xy 101.958932 -1.774474) (xy 101.975651 -1.863909) (xy 101.984046 -1.954504)
			(xy 101.984556 -1.999996) (xy 101.984556 -486.544366) (xy 101.98481 -486.544366) (xy 101.98481 -486.547414)
			(xy 101.984556 -486.549954) (xy 101.984556 -527.99996) (xy 101.984056 -528.045454) (xy 101.975664 -528.136053)
			(xy 101.958948 -528.225491) (xy 101.93405 -528.313006) (xy 101.901184 -528.397849) (xy 101.860628 -528.479298)
			(xy 101.812731 -528.556657) (xy 101.757899 -528.629267) (xy 101.696601 -528.696507) (xy 101.629361 -528.757804)
			(xy 101.556751 -528.812635) (xy 101.479391 -528.860532) (xy 101.397942 -528.901087) (xy 101.313098 -528.933953)
			(xy 101.225583 -528.95885) (xy 101.136145 -528.975565) (xy 101.045546 -528.983957) (xy 101.000052 -528.984464)
			(xy 26.500074 -528.984464) (xy 26.500074 -528.984718) (xy 26.49982 -528.984718) (xy 26.468088 -528.984217)
			(xy 26.405167 -528.975935) (xy 26.343864 -528.959512) (xy 26.285231 -528.935226) (xy 26.230269 -528.903495)
			(xy 26.179919 -528.864861) (xy 26.135043 -528.819986) (xy 26.096408 -528.769636) (xy 26.064676 -528.714675)
			(xy 26.04039 -528.656041) (xy 26.023966 -528.594739) (xy 26.015683 -528.531818) (xy 26.015188 -528.500086)
			(xy 26.015188 -527.500088) (xy 26.014716 -527.429524) (xy 26.006818 -527.288618) (xy 25.991032 -527.148377)
			(xy 25.967407 -527.009241) (xy 25.936016 -526.871649) (xy 25.89696 -526.736034) (xy 25.850361 -526.602822)
			(xy 25.796365 -526.472433) (xy 25.735143 -526.345277) (xy 25.666887 -526.221754) (xy 25.591812 -526.102252)
			(xy 25.510154 -525.987148) (xy 25.42217 -525.876805) (xy 25.328137 -525.771568) (xy 25.278588 -525.721326)
			(xy 25.228345 -525.671786) (xy 25.123129 -525.577747) (xy 25.012807 -525.489756) (xy 24.897725 -525.408088)
			(xy 24.778244 -525.333002) (xy 24.654742 -525.264732) (xy 24.527607 -525.203494) (xy 24.397238 -525.14948)
			(xy 24.264046 -525.102861) (xy 24.12845 -525.063783) (xy 23.990875 -525.032368) (xy 23.851756 -525.008716)
			(xy 23.71153 -524.992902) (xy 23.570638 -524.984974) (xy 23.50008 -524.984472) (xy 1.514856 -524.984472)
			(xy 1.481877 -524.984932) (xy 1.416287 -524.977997) (xy 1.352242 -524.962233) (xy 1.290926 -524.937933)
			(xy 1.233471 -524.905544) (xy 1.180938 -524.865664) (xy 1.157224 -524.84274) (xy 1.135152 -524.81995)
			(xy 1.096547 -524.769602) (xy 1.064848 -524.714643) (xy 1.040598 -524.656016) (xy 1.02421 -524.594724)
			(xy 1.015968 -524.531817) (xy 1.015492 -524.500094) (xy 1.015492 -204.135482) (xy 0.911098 -204.031088)
			(xy 0.509016 -204.031088) (xy 0.509016 -524.500094) (xy 0.509529 -524.54588) (xy 0.517978 -524.637062)
			(xy 0.534804 -524.727075) (xy 0.559864 -524.815152) (xy 0.592944 -524.900541) (xy 0.633761 -524.982513)
			(xy 0.681968 -525.06037) (xy 0.737153 -525.133446) (xy 0.798845 -525.201119) (xy 0.866518 -525.262811)
			(xy 0.939594 -525.317996) (xy 1.017451 -525.366203) (xy 1.099423 -525.40702) (xy 1.184812 -525.4401)
			(xy 1.272889 -525.46516) (xy 1.362902 -525.481986) (xy 1.454084 -525.490435) (xy 1.49987 -525.490948)
			(xy 23.50008 -525.490948) (xy 23.563202 -525.491433) (xy 23.689196 -525.499359) (xy 23.814444 -525.515182)
			(xy 23.93845 -525.538839) (xy 24.060727 -525.570236) (xy 24.180791 -525.60925) (xy 24.298167 -525.655726)
			(xy 24.412394 -525.709482) (xy 24.523019 -525.770304) (xy 24.629607 -525.837954) (xy 24.731736 -525.912163)
			(xy 24.829004 -525.992639) (xy 24.921025 -526.079064) (xy 25.007438 -526.171097) (xy 25.087902 -526.268376)
			(xy 25.162097 -526.370515) (xy 25.229732 -526.477111) (xy 25.29054 -526.587745) (xy 25.34428 -526.701979)
			(xy 25.390741 -526.819362) (xy 25.429739 -526.93943) (xy 25.46112 -527.061711) (xy 25.48476 -527.185721)
			(xy 25.500566 -527.310971) (xy 25.508475 -527.436966) (xy 25.508966 -527.500088) (xy 25.508966 -528.500086)
			(xy 25.509507 -528.545875) (xy 25.517982 -528.637061) (xy 25.534832 -528.727076) (xy 25.559914 -528.815153)
			(xy 25.593014 -528.90054) (xy 25.633851 -528.98251) (xy 25.682074 -529.060363) (xy 25.737274 -529.133435)
			(xy 25.79898 -529.201104) (xy 25.866665 -529.262792) (xy 25.939752 -529.317973) (xy 26.017618 -529.366176)
			(xy 26.099598 -529.406991) (xy 26.184994 -529.440069) (xy 26.273077 -529.465128) (xy 26.363097 -529.481954)
			(xy 26.454285 -529.490405) (xy 26.500074 -529.49094)
		)
		(stroke
			(width 0)
			(type solid)
		)
		(fill yes)
		(layer "In5.Cu")
		(net "GND")
	)
	(gr_poly
		(pts
			(xy 101.041454 -357.419402) (xy 101.058094 -357.43533) (xy 101.096004 -357.461489) (xy 101.138007 -357.480388)
			(xy 101.182729 -357.491406) (xy 101.228704 -357.494183) (xy 101.274427 -357.488629) (xy 101.3184 -357.474924)
			(xy 101.359183 -357.453519) (xy 101.39544 -357.425113) (xy 101.425983 -357.390638) (xy 101.449813 -357.351222)
			(xy 101.466148 -357.308157) (xy 101.474454 -357.262853) (xy 101.475032 -357.239824) (xy 101.475032 -242.563142)
			(xy 101.205538 -242.293648) (xy 101.035358 -242.293648) (xy 93.939868 -249.389138) (xy 79.86395 -249.389138)
			(xy 79.06893 -250.183904) (xy 74.92626 -254.326574) (xy 77.665721 -254.326574) (xy 77.669612 -254.272225)
			(xy 77.681199 -254.218982) (xy 77.700245 -254.167931) (xy 77.726362 -254.120111) (xy 77.75902 -254.076494)
			(xy 77.797553 -254.037969) (xy 77.841177 -254.00532) (xy 77.889003 -253.979212) (xy 77.940058 -253.960176)
			(xy 77.993302 -253.948601) (xy 78.047652 -253.944721) (xy 78.102001 -253.948616) (xy 78.155242 -253.960206)
			(xy 78.206292 -253.979255) (xy 78.254111 -254.005376) (xy 78.276196 -254.021336) (xy 78.295208 -254.034932)
			(xy 78.337091 -254.055664) (xy 78.382059 -254.06839) (xy 78.428596 -254.07268) (xy 78.475133 -254.06839)
			(xy 78.520101 -254.055664) (xy 78.561984 -254.034932) (xy 78.580996 -254.021336) (xy 78.603043 -254.005316)
			(xy 78.650871 -253.979189) (xy 78.701931 -253.960135) (xy 78.755183 -253.948542) (xy 78.809543 -253.944646)
			(xy 78.863904 -253.948526) (xy 78.91716 -253.960103) (xy 78.968225 -253.979142) (xy 79.016062 -254.005255)
			(xy 79.059694 -254.03791) (xy 79.098235 -254.076443) (xy 79.1309 -254.120069) (xy 79.157023 -254.167899)
			(xy 79.176073 -254.21896) (xy 79.187662 -254.272213) (xy 79.191554 -254.326574) (xy 80.470113 -254.326574)
			(xy 80.474004 -254.272223) (xy 80.485591 -254.218979) (xy 80.504638 -254.167926) (xy 80.530757 -254.120104)
			(xy 80.563416 -254.076485) (xy 80.601951 -254.03796) (xy 80.645576 -254.00531) (xy 80.693405 -253.979202)
			(xy 80.744462 -253.960167) (xy 80.797708 -253.948592) (xy 80.85206 -253.944713) (xy 80.906411 -253.948609)
			(xy 80.959654 -253.9602) (xy 81.010705 -253.979252) (xy 81.058525 -254.005375) (xy 81.08061 -254.021336)
			(xy 81.099622 -254.034932) (xy 81.141505 -254.055664) (xy 81.186473 -254.06839) (xy 81.23301 -254.07268)
			(xy 81.279547 -254.06839) (xy 81.324515 -254.055664) (xy 81.366398 -254.034932) (xy 81.38541 -254.021336)
			(xy 81.407457 -254.005318) (xy 81.455284 -253.979193) (xy 81.506343 -253.960141) (xy 81.559593 -253.948549)
			(xy 81.613951 -253.944654) (xy 81.66831 -253.948535) (xy 81.721564 -253.960113) (xy 81.772627 -253.979152)
			(xy 81.820461 -254.005265) (xy 81.864092 -254.037919) (xy 81.902631 -254.076451) (xy 81.935295 -254.120075)
			(xy 81.961417 -254.167904) (xy 81.980466 -254.218964) (xy 81.992054 -254.272215) (xy 81.995946 -254.326574)
			(xy 81.992062 -254.380932) (xy 81.980481 -254.434185) (xy 81.961439 -254.485248) (xy 81.935323 -254.53308)
			(xy 81.902666 -254.576709) (xy 81.864132 -254.615246) (xy 81.820506 -254.647907) (xy 81.772675 -254.674026)
			(xy 81.721614 -254.693072) (xy 81.668363 -254.704657) (xy 81.614004 -254.708546) (xy 81.559645 -254.704658)
			(xy 81.506393 -254.693074) (xy 81.455332 -254.674029) (xy 81.407501 -254.647911) (xy 81.38541 -254.631952)
			(xy 81.366398 -254.618356) (xy 81.324515 -254.597624) (xy 81.279547 -254.584898) (xy 81.23301 -254.580608)
			(xy 81.186473 -254.584898) (xy 81.141505 -254.597624) (xy 81.099622 -254.618356) (xy 81.08061 -254.631952)
			(xy 81.05848 -254.647853) (xy 81.010657 -254.67397) (xy 80.959603 -254.693014) (xy 80.906359 -254.704599)
			(xy 80.852007 -254.708487) (xy 80.797656 -254.704601) (xy 80.744411 -254.693019) (xy 80.693357 -254.673976)
			(xy 80.645532 -254.647861) (xy 80.601911 -254.615206) (xy 80.563382 -254.576675) (xy 80.530728 -254.533052)
			(xy 80.504616 -254.485226) (xy 80.485576 -254.434171) (xy 80.473996 -254.380925) (xy 80.470113 -254.326574)
			(xy 79.191554 -254.326574) (xy 79.18767 -254.380934) (xy 79.176088 -254.434189) (xy 79.157045 -254.485253)
			(xy 79.130929 -254.533087) (xy 79.09827 -254.576717) (xy 79.059734 -254.615255) (xy 79.016106 -254.647916)
			(xy 78.968273 -254.674036) (xy 78.91721 -254.693082) (xy 78.863957 -254.704667) (xy 78.809596 -254.708554)
			(xy 78.755236 -254.704665) (xy 78.701982 -254.69308) (xy 78.650919 -254.674033) (xy 78.603087 -254.647912)
			(xy 78.580996 -254.631952) (xy 78.561984 -254.618356) (xy 78.520101 -254.597624) (xy 78.475133 -254.584898)
			(xy 78.428596 -254.580608) (xy 78.382059 -254.584898) (xy 78.337091 -254.597624) (xy 78.295208 -254.618356)
			(xy 78.276196 -254.631952) (xy 78.254067 -254.647852) (xy 78.206244 -254.673967) (xy 78.155192 -254.693009)
			(xy 78.101949 -254.704592) (xy 78.047599 -254.708479) (xy 77.99325 -254.704592) (xy 77.940007 -254.693009)
			(xy 77.888955 -254.673966) (xy 77.841132 -254.647852) (xy 77.797513 -254.615197) (xy 77.758986 -254.576666)
			(xy 77.726334 -254.533045) (xy 77.700223 -254.485221) (xy 77.681184 -254.434167) (xy 77.669605 -254.380923)
			(xy 77.665721 -254.326574) (xy 74.92626 -254.326574) (xy 73.397811 -255.855023) (xy 77.615846 -255.855023)
			(xy 77.619731 -255.800662) (xy 77.631313 -255.747407) (xy 77.650357 -255.696343) (xy 77.676474 -255.648509)
			(xy 77.709134 -255.604878) (xy 77.74767 -255.566341) (xy 77.791299 -255.53368) (xy 77.839133 -255.507561)
			(xy 77.890197 -255.488516) (xy 77.943451 -255.476932) (xy 77.997812 -255.473046) (xy 78.052173 -255.476936)
			(xy 78.105427 -255.488523) (xy 78.156489 -255.507571) (xy 78.204321 -255.533693) (xy 78.226412 -255.549654)
			(xy 78.245424 -255.56325) (xy 78.287307 -255.583982) (xy 78.332275 -255.596708) (xy 78.378812 -255.600998)
			(xy 78.425349 -255.596708) (xy 78.470317 -255.583982) (xy 78.5122 -255.56325) (xy 78.531212 -255.549654)
			(xy 78.553336 -255.533746) (xy 78.601158 -255.507632) (xy 78.65221 -255.488591) (xy 78.705453 -255.477008)
			(xy 78.759802 -255.473121) (xy 78.814151 -255.477009) (xy 78.867393 -255.488591) (xy 78.918445 -255.507634)
			(xy 78.966267 -255.533748) (xy 79.009886 -255.566403) (xy 79.048413 -255.604932) (xy 79.081065 -255.648553)
			(xy 79.107176 -255.696377) (xy 79.126215 -255.74743) (xy 79.137795 -255.800674) (xy 79.141679 -255.855023)
			(xy 80.420237 -255.855023) (xy 80.424123 -255.80066) (xy 80.435705 -255.747403) (xy 80.45475 -255.696337)
			(xy 80.480869 -255.648502) (xy 80.51353 -255.60487) (xy 80.552068 -255.566332) (xy 80.595699 -255.53367)
			(xy 80.643535 -255.507551) (xy 80.6946 -255.488506) (xy 80.747857 -255.476923) (xy 80.80222 -255.473037)
			(xy 80.856583 -255.476929) (xy 80.909838 -255.488517) (xy 80.960902 -255.507568) (xy 81.008734 -255.533692)
			(xy 81.030826 -255.549654) (xy 81.049838 -255.56325) (xy 81.091721 -255.583982) (xy 81.136689 -255.596708)
			(xy 81.183226 -255.600998) (xy 81.229763 -255.596708) (xy 81.274731 -255.583982) (xy 81.316614 -255.56325)
			(xy 81.335626 -255.549654) (xy 81.357749 -255.533748) (xy 81.405571 -255.507636) (xy 81.456621 -255.488596)
			(xy 81.509862 -255.477015) (xy 81.56421 -255.473129) (xy 81.618556 -255.477018) (xy 81.671797 -255.488601)
			(xy 81.722847 -255.507644) (xy 81.770667 -255.533758) (xy 81.814284 -255.566412) (xy 81.852809 -255.604941)
			(xy 81.88546 -255.64856) (xy 81.91157 -255.696383) (xy 81.930608 -255.747434) (xy 81.942187 -255.800676)
			(xy 81.946071 -255.855023) (xy 81.94218 -255.90937) (xy 81.930595 -255.96261) (xy 81.911551 -256.013659)
			(xy 81.885435 -256.061478) (xy 81.85278 -256.105094) (xy 81.814249 -256.143618) (xy 81.770629 -256.176267)
			(xy 81.722805 -256.202375) (xy 81.671753 -256.221412) (xy 81.618511 -256.232989) (xy 81.564164 -256.236871)
			(xy 81.509817 -256.232978) (xy 81.456578 -256.221391) (xy 81.405529 -256.202345) (xy 81.357711 -256.176228)
			(xy 81.335626 -256.16027) (xy 81.316614 -256.146674) (xy 81.274731 -256.125942) (xy 81.229763 -256.113216)
			(xy 81.183226 -256.108926) (xy 81.136689 -256.113216) (xy 81.091721 -256.125942) (xy 81.049838 -256.146674)
			(xy 81.030826 -256.16027) (xy 81.008773 -256.176283) (xy 80.960943 -256.202413) (xy 80.909882 -256.22147)
			(xy 80.856628 -256.233065) (xy 80.802266 -256.236963) (xy 80.747902 -256.233083) (xy 80.694644 -256.221507)
			(xy 80.643576 -256.202468) (xy 80.595738 -256.176354) (xy 80.552103 -256.143698) (xy 80.51356 -256.105164)
			(xy 80.480893 -256.061537) (xy 80.454769 -256.013704) (xy 80.435718 -255.962641) (xy 80.424129 -255.909385)
			(xy 80.420237 -255.855023) (xy 79.141679 -255.855023) (xy 79.137788 -255.909372) (xy 79.126203 -255.962613)
			(xy 79.107157 -256.013664) (xy 79.08104 -256.061485) (xy 79.048384 -256.105102) (xy 79.009852 -256.143627)
			(xy 78.966229 -256.176277) (xy 78.918403 -256.202385) (xy 78.867349 -256.221421) (xy 78.814105 -256.232998)
			(xy 78.759756 -256.236879) (xy 78.705407 -256.232985) (xy 78.652166 -256.221397) (xy 78.601116 -256.202349)
			(xy 78.553297 -256.176229) (xy 78.531212 -256.16027) (xy 78.5122 -256.146674) (xy 78.470317 -256.125942)
			(xy 78.425349 -256.113216) (xy 78.378812 -256.108926) (xy 78.332275 -256.113216) (xy 78.287307 -256.125942)
			(xy 78.245424 -256.146674) (xy 78.226412 -256.16027) (xy 78.204359 -256.176282) (xy 78.156531 -256.20241)
			(xy 78.10547 -256.221464) (xy 78.052218 -256.233058) (xy 77.997858 -256.236954) (xy 77.943496 -256.233074)
			(xy 77.89024 -256.221497) (xy 77.839174 -256.202458) (xy 77.791338 -256.176345) (xy 77.747705 -256.143689)
			(xy 77.709164 -256.105156) (xy 77.676499 -256.06153) (xy 77.650376 -256.013699) (xy 77.631326 -255.962637)
			(xy 77.619737 -255.909383) (xy 77.615846 -255.855023) (xy 73.397811 -255.855023) (xy 71.67292 -257.579914)
			(xy 77.632351 -257.579914) (xy 77.636237 -257.525554) (xy 77.647821 -257.472299) (xy 77.666866 -257.421236)
			(xy 77.692984 -257.373403) (xy 77.725645 -257.329774) (xy 77.764182 -257.291237) (xy 77.807812 -257.258578)
			(xy 77.855646 -257.232461) (xy 77.906711 -257.213417) (xy 77.959965 -257.201836) (xy 78.014326 -257.197951)
			(xy 78.068687 -257.201843) (xy 78.12194 -257.213432) (xy 78.173001 -257.232483) (xy 78.220832 -257.258606)
			(xy 78.242922 -257.274568) (xy 78.261934 -257.288164) (xy 78.303817 -257.308896) (xy 78.348785 -257.321622)
			(xy 78.395322 -257.325912) (xy 78.441859 -257.321622) (xy 78.486827 -257.308896) (xy 78.52871 -257.288164)
			(xy 78.547722 -257.274568) (xy 78.569832 -257.258642) (xy 78.617655 -257.232528) (xy 78.668707 -257.213486)
			(xy 78.72195 -257.201903) (xy 78.776299 -257.198016) (xy 78.830648 -257.201903) (xy 78.883891 -257.213485)
			(xy 78.934943 -257.232527) (xy 78.982766 -257.258641) (xy 79.026385 -257.291295) (xy 79.064914 -257.329825)
			(xy 79.097566 -257.373445) (xy 79.123678 -257.421269) (xy 79.142718 -257.472322) (xy 79.154299 -257.525565)
			(xy 79.158184 -257.579914) (xy 80.436743 -257.579914) (xy 80.440629 -257.525552) (xy 80.452213 -257.472296)
			(xy 80.471259 -257.42123) (xy 80.497379 -257.373396) (xy 80.530041 -257.329765) (xy 80.56858 -257.291228)
			(xy 80.612212 -257.258568) (xy 80.660048 -257.232451) (xy 80.711114 -257.213408) (xy 80.764371 -257.201826)
			(xy 80.818734 -257.197943) (xy 80.873096 -257.201836) (xy 80.926351 -257.213427) (xy 80.977414 -257.232479)
			(xy 81.025245 -257.258605) (xy 81.047336 -257.274568) (xy 81.066348 -257.288164) (xy 81.108231 -257.308896)
			(xy 81.153199 -257.321622) (xy 81.199736 -257.325912) (xy 81.246273 -257.321622) (xy 81.291241 -257.308896)
			(xy 81.333124 -257.288164) (xy 81.352136 -257.274568) (xy 81.374246 -257.258643) (xy 81.422067 -257.232532)
			(xy 81.473118 -257.213491) (xy 81.52636 -257.20191) (xy 81.580707 -257.198024) (xy 81.635054 -257.201912)
			(xy 81.688295 -257.213495) (xy 81.739345 -257.232537) (xy 81.787166 -257.258651) (xy 81.830783 -257.291304)
			(xy 81.86931 -257.329833) (xy 81.901961 -257.373452) (xy 81.928072 -257.421274) (xy 81.947111 -257.472326)
			(xy 81.958691 -257.525567) (xy 81.962576 -257.579914) (xy 81.958687 -257.634262) (xy 81.947103 -257.687502)
			(xy 81.92806 -257.738552) (xy 81.901945 -257.786372) (xy 81.869291 -257.829989) (xy 81.830761 -257.868515)
			(xy 81.787141 -257.901165) (xy 81.739319 -257.927275) (xy 81.688267 -257.946313) (xy 81.635026 -257.957892)
			(xy 81.580678 -257.961776) (xy 81.526331 -257.957886) (xy 81.473091 -257.946301) (xy 81.422041 -257.927256)
			(xy 81.374222 -257.901141) (xy 81.352136 -257.885184) (xy 81.333124 -257.871588) (xy 81.291241 -257.850856)
			(xy 81.246273 -257.83813) (xy 81.199736 -257.83384) (xy 81.153199 -257.83813) (xy 81.108231 -257.850856)
			(xy 81.066348 -257.871588) (xy 81.047336 -257.885184) (xy 81.025269 -257.901179) (xy 80.97744 -257.927309)
			(xy 80.926379 -257.946365) (xy 80.873125 -257.95796) (xy 80.818763 -257.961857) (xy 80.7644 -257.957978)
			(xy 80.711142 -257.946401) (xy 80.660074 -257.927361) (xy 80.612236 -257.901247) (xy 80.568602 -257.868591)
			(xy 80.53006 -257.830056) (xy 80.497394 -257.786429) (xy 80.471271 -257.738596) (xy 80.452221 -257.687532)
			(xy 80.440633 -257.634277) (xy 80.436743 -257.579914) (xy 79.158184 -257.579914) (xy 79.154295 -257.634263)
			(xy 79.14271 -257.687506) (xy 79.123666 -257.738557) (xy 79.097551 -257.786379) (xy 79.064895 -257.829997)
			(xy 79.026364 -257.868524) (xy 78.982742 -257.901174) (xy 78.934917 -257.927285) (xy 78.883863 -257.946323)
			(xy 78.83062 -257.957901) (xy 78.77627 -257.961784) (xy 78.721921 -257.957893) (xy 78.668679 -257.946306)
			(xy 78.617629 -257.92726) (xy 78.569808 -257.901142) (xy 78.547722 -257.885184) (xy 78.52871 -257.871588)
			(xy 78.486827 -257.850856) (xy 78.441859 -257.83813) (xy 78.395322 -257.83384) (xy 78.348785 -257.83813)
			(xy 78.303817 -257.850856) (xy 78.261934 -257.871588) (xy 78.242922 -257.885184) (xy 78.220856 -257.901178)
			(xy 78.173027 -257.927306) (xy 78.121967 -257.94636) (xy 78.068715 -257.957953) (xy 78.014355 -257.961849)
			(xy 77.959994 -257.957969) (xy 77.906738 -257.946391) (xy 77.855673 -257.927351) (xy 77.807837 -257.901238)
			(xy 77.764204 -257.868582) (xy 77.725664 -257.830048) (xy 77.693 -257.786422) (xy 77.666878 -257.73859)
			(xy 77.647829 -257.687528) (xy 77.636241 -257.634275) (xy 77.632351 -257.579914) (xy 71.67292 -257.579914)
			(xy 70.005921 -259.246913) (xy 77.64538 -259.246913) (xy 77.649266 -259.192559) (xy 77.660848 -259.139311)
			(xy 77.67989 -259.088253) (xy 77.706004 -259.040425) (xy 77.73866 -258.996801) (xy 77.777192 -258.958268)
			(xy 77.820815 -258.925611) (xy 77.868642 -258.899495) (xy 77.919699 -258.880451) (xy 77.972947 -258.868868)
			(xy 78.027301 -258.86498) (xy 78.081655 -258.868868) (xy 78.134903 -258.880452) (xy 78.18596 -258.899496)
			(xy 78.233787 -258.925612) (xy 78.255876 -258.94157) (xy 78.274888 -258.955166) (xy 78.316771 -258.975898)
			(xy 78.361739 -258.988624) (xy 78.408276 -258.992914) (xy 78.454813 -258.988624) (xy 78.499781 -258.975898)
			(xy 78.541664 -258.955166) (xy 78.560676 -258.94157) (xy 78.582785 -258.925638) (xy 78.630611 -258.899516)
			(xy 78.681668 -258.880467) (xy 78.734916 -258.868879) (xy 78.789272 -258.864987) (xy 78.843627 -258.868871)
			(xy 78.896877 -258.880451) (xy 78.947937 -258.899492) (xy 78.995767 -258.925607) (xy 79.039393 -258.958263)
			(xy 79.077927 -258.996796) (xy 79.110585 -259.04042) (xy 79.136701 -259.088249) (xy 79.155745 -259.139308)
			(xy 79.167327 -259.192557) (xy 79.171213 -259.246913) (xy 80.449772 -259.246913) (xy 80.453658 -259.192557)
			(xy 80.46524 -259.139307) (xy 80.484283 -259.088248) (xy 80.510399 -259.040418) (xy 80.543056 -258.996793)
			(xy 80.581589 -258.958259) (xy 80.625215 -258.925601) (xy 80.673044 -258.899485) (xy 80.724103 -258.880441)
			(xy 80.777353 -258.868858) (xy 80.831709 -258.864972) (xy 80.886065 -258.868861) (xy 80.939314 -258.880446)
			(xy 80.990373 -258.899492) (xy 81.0382 -258.925611) (xy 81.06029 -258.94157) (xy 81.079302 -258.955166)
			(xy 81.121185 -258.975898) (xy 81.166153 -258.988624) (xy 81.21269 -258.992914) (xy 81.259227 -258.988624)
			(xy 81.304195 -258.975898) (xy 81.346078 -258.955166) (xy 81.36509 -258.94157) (xy 81.387199 -258.925639)
			(xy 81.435024 -258.899519) (xy 81.486079 -258.880472) (xy 81.539326 -258.868886) (xy 81.593679 -258.864995)
			(xy 81.648033 -258.86888) (xy 81.701281 -258.880461) (xy 81.752339 -258.899502) (xy 81.800166 -258.925617)
			(xy 81.843791 -258.958272) (xy 81.882323 -258.996804) (xy 81.914979 -259.040427) (xy 81.941095 -259.088255)
			(xy 81.960137 -259.139312) (xy 81.971719 -259.192559) (xy 81.975605 -259.246913) (xy 81.971715 -259.301267)
			(xy 81.96013 -259.354514) (xy 81.941084 -259.405569) (xy 81.914965 -259.453395) (xy 81.882306 -259.497016)
			(xy 81.843771 -259.535545) (xy 81.800144 -259.568198) (xy 81.752315 -259.594309) (xy 81.701256 -259.613347)
			(xy 81.648007 -259.624924) (xy 81.593653 -259.628805) (xy 81.5393 -259.624911) (xy 81.486054 -259.61332)
			(xy 81.435 -259.59427) (xy 81.387177 -259.568147) (xy 81.36509 -259.552186) (xy 81.346078 -259.53859)
			(xy 81.304195 -259.517858) (xy 81.259227 -259.505132) (xy 81.21269 -259.500842) (xy 81.166153 -259.505132)
			(xy 81.121185 -259.517858) (xy 81.079302 -259.53859) (xy 81.06029 -259.552186) (xy 81.038223 -259.568175)
			(xy 80.990397 -259.594297) (xy 80.93934 -259.613346) (xy 80.886091 -259.624935) (xy 80.831736 -259.628828)
			(xy 80.777379 -259.624945) (xy 80.724129 -259.613366) (xy 80.673068 -259.594326) (xy 80.625237 -259.568213)
			(xy 80.581609 -259.535559) (xy 80.543073 -259.497027) (xy 80.510413 -259.453404) (xy 80.484294 -259.405576)
			(xy 80.465247 -259.354518) (xy 80.453662 -259.301269) (xy 80.449772 -259.246913) (xy 79.171213 -259.246913)
			(xy 79.167324 -259.301269) (xy 79.155737 -259.354517) (xy 79.13669 -259.405575) (xy 79.110571 -259.453402)
			(xy 79.07791 -259.497024) (xy 79.039373 -259.535554) (xy 78.995744 -259.568207) (xy 78.947913 -259.594319)
			(xy 78.896852 -259.613356) (xy 78.843601 -259.624933) (xy 78.789245 -259.628813) (xy 78.73489 -259.624918)
			(xy 78.681643 -259.613326) (xy 78.630587 -259.594273) (xy 78.582763 -259.568148) (xy 78.560676 -259.552186)
			(xy 78.541664 -259.53859) (xy 78.499781 -259.517858) (xy 78.454813 -259.505132) (xy 78.408276 -259.500842)
			(xy 78.361739 -259.505132) (xy 78.316771 -259.517858) (xy 78.274888 -259.53859) (xy 78.255876 -259.552186)
			(xy 78.233809 -259.568174) (xy 78.185984 -259.594293) (xy 78.134928 -259.613341) (xy 78.081681 -259.624928)
			(xy 78.027328 -259.62882) (xy 77.972973 -259.624936) (xy 77.919725 -259.613356) (xy 77.868666 -259.594316)
			(xy 77.820837 -259.568203) (xy 77.777212 -259.535549) (xy 77.738677 -259.497019) (xy 77.706019 -259.453397)
			(xy 77.679901 -259.405571) (xy 77.660855 -259.354514) (xy 77.64927 -259.301267) (xy 77.64538 -259.246913)
			(xy 70.005921 -259.246913) (xy 68.374218 -260.878616) (xy 77.628883 -260.878616) (xy 77.632768 -260.824262)
			(xy 77.644349 -260.771015) (xy 77.663391 -260.719958) (xy 77.689504 -260.672131) (xy 77.722159 -260.628506)
			(xy 77.760689 -260.589974) (xy 77.804312 -260.557316) (xy 77.852138 -260.5312) (xy 77.903193 -260.512156)
			(xy 77.95644 -260.500572) (xy 78.010793 -260.496683) (xy 78.065146 -260.50057) (xy 78.118393 -260.512152)
			(xy 78.16945 -260.531194) (xy 78.217277 -260.557309) (xy 78.239366 -260.573266) (xy 78.258378 -260.586862)
			(xy 78.300261 -260.607594) (xy 78.345229 -260.62032) (xy 78.391766 -260.62461) (xy 78.438303 -260.62032)
			(xy 78.483271 -260.607594) (xy 78.525154 -260.586862) (xy 78.544166 -260.573266) (xy 78.566279 -260.557338)
			(xy 78.614106 -260.531215) (xy 78.665163 -260.512166) (xy 78.718412 -260.500576) (xy 78.772768 -260.496684)
			(xy 78.827125 -260.500567) (xy 78.880376 -260.512148) (xy 78.931437 -260.531189) (xy 78.979267 -260.557304)
			(xy 79.022894 -260.58996) (xy 79.061429 -260.628494) (xy 79.094087 -260.672119) (xy 79.120204 -260.719949)
			(xy 79.139248 -260.771009) (xy 79.15083 -260.824259) (xy 79.154716 -260.878616) (xy 80.433275 -260.878616)
			(xy 80.43716 -260.82426) (xy 80.448742 -260.771011) (xy 80.467784 -260.719953) (xy 80.493899 -260.672124)
			(xy 80.526555 -260.628498) (xy 80.565087 -260.589964) (xy 80.608711 -260.557307) (xy 80.656539 -260.53119)
			(xy 80.707597 -260.512146) (xy 80.760846 -260.500562) (xy 80.815201 -260.496675) (xy 80.869556 -260.500562)
			(xy 80.922805 -260.512146) (xy 80.973863 -260.531191) (xy 81.02169 -260.557308) (xy 81.04378 -260.573266)
			(xy 81.062792 -260.586862) (xy 81.104675 -260.607594) (xy 81.149643 -260.62032) (xy 81.19618 -260.62461)
			(xy 81.242717 -260.62032) (xy 81.287685 -260.607594) (xy 81.329568 -260.586862) (xy 81.34858 -260.573266)
			(xy 81.370693 -260.557339) (xy 81.418518 -260.531219) (xy 81.469574 -260.512171) (xy 81.522822 -260.500583)
			(xy 81.577176 -260.496692) (xy 81.631531 -260.500577) (xy 81.68478 -260.512158) (xy 81.735838 -260.531199)
			(xy 81.783667 -260.557314) (xy 81.827292 -260.58997) (xy 81.865825 -260.628502) (xy 81.898482 -260.672126)
			(xy 81.924597 -260.719954) (xy 81.94364 -260.771012) (xy 81.955222 -260.824261) (xy 81.959108 -260.878616)
			(xy 81.955218 -260.93297) (xy 81.943631 -260.986218) (xy 81.924585 -261.037274) (xy 81.898465 -261.0851)
			(xy 81.865805 -261.128722) (xy 81.827268 -261.167251) (xy 81.783641 -261.199903) (xy 81.73581 -261.226014)
			(xy 81.68475 -261.245051) (xy 81.6315 -261.256628) (xy 81.577145 -261.260508) (xy 81.522791 -261.256612)
			(xy 81.469544 -261.24502) (xy 81.41849 -261.225968) (xy 81.370667 -261.199844) (xy 81.34858 -261.183882)
			(xy 81.329568 -261.170286) (xy 81.287685 -261.149554) (xy 81.242717 -261.136828) (xy 81.19618 -261.132538)
			(xy 81.149643 -261.136828) (xy 81.104675 -261.149554) (xy 81.062792 -261.170286) (xy 81.04378 -261.183882)
			(xy 81.021717 -261.199875) (xy 80.973891 -261.225996) (xy 80.922835 -261.245045) (xy 80.869587 -261.256633)
			(xy 80.815232 -261.260525) (xy 80.760877 -261.256642) (xy 80.707627 -261.245063) (xy 80.656568 -261.226023)
			(xy 80.608738 -261.19991) (xy 80.565111 -261.167256) (xy 80.526575 -261.128725) (xy 80.493916 -261.085103)
			(xy 80.467797 -261.037276) (xy 80.448751 -260.986219) (xy 80.437165 -260.932971) (xy 80.433275 -260.878616)
			(xy 79.154716 -260.878616) (xy 79.150826 -260.932972) (xy 79.139239 -260.986221) (xy 79.120191 -261.03728)
			(xy 79.094071 -261.085107) (xy 79.061409 -261.12873) (xy 79.022871 -261.16726) (xy 78.979241 -261.199913)
			(xy 78.931408 -261.226024) (xy 78.880346 -261.245061) (xy 78.827094 -261.256637) (xy 78.772737 -261.260516)
			(xy 78.718381 -261.256619) (xy 78.665133 -261.245026) (xy 78.614077 -261.225972) (xy 78.566253 -261.199845)
			(xy 78.544166 -261.183882) (xy 78.525154 -261.170286) (xy 78.483271 -261.149554) (xy 78.438303 -261.136828)
			(xy 78.391766 -261.132538) (xy 78.345229 -261.136828) (xy 78.300261 -261.149554) (xy 78.258378 -261.170286)
			(xy 78.239366 -261.183882) (xy 78.217303 -261.199874) (xy 78.169478 -261.225993) (xy 78.118423 -261.245039)
			(xy 78.065177 -261.256626) (xy 78.010824 -261.260517) (xy 77.956471 -261.256633) (xy 77.903223 -261.245053)
			(xy 77.852166 -261.226013) (xy 77.804338 -261.1999) (xy 77.760713 -261.167247) (xy 77.722179 -261.128717)
			(xy 77.689521 -261.085096) (xy 77.663404 -261.03727) (xy 77.644358 -260.986215) (xy 77.632773 -260.932969)
			(xy 77.628883 -260.878616) (xy 68.374218 -260.878616) (xy 66.688417 -262.564417) (xy 77.595733 -262.564417)
			(xy 77.59962 -262.510052) (xy 77.611204 -262.456794) (xy 77.63025 -262.405727) (xy 77.656371 -262.357891)
			(xy 77.689034 -262.314259) (xy 77.727575 -262.275721) (xy 77.771208 -262.24306) (xy 77.819046 -262.216942)
			(xy 77.870114 -262.197898) (xy 77.923373 -262.186317) (xy 77.977737 -262.182433) (xy 78.032101 -262.186327)
			(xy 78.085358 -262.197919) (xy 78.136422 -262.216973) (xy 78.184255 -262.2431) (xy 78.206346 -262.259064)
			(xy 78.225358 -262.27266) (xy 78.267241 -262.293392) (xy 78.312209 -262.306118) (xy 78.358746 -262.310408)
			(xy 78.405283 -262.306118) (xy 78.450251 -262.293392) (xy 78.492134 -262.27266) (xy 78.511146 -262.259064)
			(xy 78.533259 -262.243146) (xy 78.58108 -262.217036) (xy 78.63213 -262.197998) (xy 78.685369 -262.186418)
			(xy 78.739715 -262.182533) (xy 78.79406 -262.186422) (xy 78.847299 -262.198006) (xy 78.898347 -262.217048)
			(xy 78.946166 -262.243162) (xy 78.989781 -262.275815) (xy 79.028306 -262.314343) (xy 79.060955 -262.357961)
			(xy 79.087065 -262.405782) (xy 79.106103 -262.456832) (xy 79.117682 -262.510071) (xy 79.121567 -262.564417)
			(xy 80.400285 -262.564417) (xy 80.40417 -262.510064) (xy 80.415751 -262.456817) (xy 80.434792 -262.405761)
			(xy 80.460905 -262.357934) (xy 80.493558 -262.31431) (xy 80.532088 -262.275777) (xy 80.57571 -262.24312)
			(xy 80.623535 -262.217003) (xy 80.67459 -262.197959) (xy 80.727836 -262.186374) (xy 80.782188 -262.182485)
			(xy 80.836541 -262.186371) (xy 80.889788 -262.197952) (xy 80.940844 -262.216994) (xy 80.988671 -262.243108)
			(xy 81.01076 -262.259064) (xy 81.029772 -262.27266) (xy 81.071655 -262.293392) (xy 81.116623 -262.306118)
			(xy 81.16316 -262.310408) (xy 81.209697 -262.306118) (xy 81.254665 -262.293392) (xy 81.296548 -262.27266)
			(xy 81.31556 -262.259064) (xy 81.337675 -262.243138) (xy 81.385502 -262.217015) (xy 81.43656 -262.197964)
			(xy 81.489809 -262.186375) (xy 81.544166 -262.182482) (xy 81.598524 -262.186365) (xy 81.651775 -262.197945)
			(xy 81.702836 -262.216987) (xy 81.750667 -262.243102) (xy 81.794295 -262.275758) (xy 81.83283 -262.314292)
			(xy 81.865489 -262.357918) (xy 81.891606 -262.405748) (xy 81.91065 -262.456809) (xy 81.922232 -262.510059)
			(xy 81.926118 -262.564417) (xy 81.922228 -262.618774) (xy 81.91064 -262.672024) (xy 81.891592 -262.723082)
			(xy 81.865471 -262.77091) (xy 81.832808 -262.814533) (xy 81.79427 -262.853064) (xy 81.750639 -262.885716)
			(xy 81.702806 -262.911827) (xy 81.651743 -262.930864) (xy 81.59849 -262.94244) (xy 81.544132 -262.946318)
			(xy 81.489776 -262.94242) (xy 81.436528 -262.930826) (xy 81.385471 -262.911771) (xy 81.337647 -262.885643)
			(xy 81.31556 -262.86968) (xy 81.296548 -262.856084) (xy 81.254665 -262.835352) (xy 81.209697 -262.822626)
			(xy 81.16316 -262.818336) (xy 81.116623 -262.822626) (xy 81.071655 -262.835352) (xy 81.029772 -262.856084)
			(xy 81.01076 -262.86968) (xy 80.988699 -262.885674) (xy 80.940875 -262.911792) (xy 80.88982 -262.930838)
			(xy 80.836575 -262.942424) (xy 80.782222 -262.946315) (xy 80.727869 -262.942431) (xy 80.674622 -262.930851)
			(xy 80.623566 -262.911811) (xy 80.575738 -262.885698) (xy 80.532114 -262.853045) (xy 80.493581 -262.814516)
			(xy 80.460923 -262.770895) (xy 80.434806 -262.72307) (xy 80.41576 -262.672015) (xy 80.404175 -262.618769)
			(xy 80.400285 -262.564417) (xy 79.121567 -262.564417) (xy 79.117677 -262.618762) (xy 79.106093 -262.672001)
			(xy 79.087051 -262.723049) (xy 79.060937 -262.770867) (xy 79.028284 -262.814483) (xy 78.989756 -262.853007)
			(xy 78.946137 -262.885656) (xy 78.898317 -262.911766) (xy 78.847267 -262.930803) (xy 78.794027 -262.942382)
			(xy 78.739681 -262.946267) (xy 78.685336 -262.942377) (xy 78.632098 -262.930793) (xy 78.581049 -262.91175)
			(xy 78.533231 -262.885636) (xy 78.511146 -262.86968) (xy 78.492134 -262.856084) (xy 78.450251 -262.835352)
			(xy 78.405283 -262.822626) (xy 78.358746 -262.818336) (xy 78.312209 -262.822626) (xy 78.267241 -262.835352)
			(xy 78.225358 -262.856084) (xy 78.206346 -262.86968) (xy 78.184283 -262.885682) (xy 78.136453 -262.911813)
			(xy 78.08539 -262.930871) (xy 78.032135 -262.942468) (xy 77.977771 -262.946366) (xy 77.923406 -262.942488)
			(xy 77.870146 -262.930911) (xy 77.819077 -262.911872) (xy 77.771236 -262.885758) (xy 77.7276 -262.853101)
			(xy 77.689056 -262.814566) (xy 77.656389 -262.770937) (xy 77.630264 -262.723103) (xy 77.611213 -262.672038)
			(xy 77.599624 -262.618781) (xy 77.595733 -262.564417) (xy 66.688417 -262.564417) (xy 64.47028 -264.782554)
			(xy 64.47028 -266.200128) (xy 64.646302 -266.37615) (xy 64.653167 -266.398685) (xy 64.674046 -266.440908)
			(xy 64.70235 -266.478559) (xy 64.73711 -266.510347) (xy 64.777133 -266.535183) (xy 64.821049 -266.552215)
			(xy 64.867352 -266.560861) (xy 64.890904 -266.561316) (xy 80.69453 -266.561316) (xy 80.965294 -266.290552)
			(xy 83.224878 -266.290552) (xy 83.495642 -266.561316) (xy 84.636864 -266.561316) (xy 84.658937 -266.560852)
			(xy 84.702421 -266.553235) (xy 84.74393 -266.538206) (xy 84.782211 -266.516221) (xy 84.81611 -266.487941)
			(xy 84.844602 -266.454221) (xy 84.866828 -266.416079) (xy 84.882118 -266.374666) (xy 84.886546 -266.353036)
			(xy 84.892046 -266.325643) (xy 84.909992 -266.272733) (xy 84.935461 -266.223006) (xy 84.967909 -266.177523)
			(xy 85.006642 -266.137258) (xy 85.050831 -266.10307) (xy 85.099533 -266.075691) (xy 85.151707 -266.055705)
			(xy 85.206237 -266.04354) (xy 85.261958 -266.039456) (xy 85.317679 -266.04354) (xy 85.372209 -266.055705)
			(xy 85.424383 -266.075691) (xy 85.473085 -266.10307) (xy 85.517274 -266.137258) (xy 85.556007 -266.177523)
			(xy 85.588455 -266.223006) (xy 85.613924 -266.272733) (xy 85.63187 -266.325643) (xy 85.63737 -266.353036)
			(xy 85.641821 -266.374651) (xy 85.657166 -266.416023) (xy 85.679421 -266.454127) (xy 85.707919 -266.487817)
			(xy 85.741804 -266.516083) (xy 85.780059 -266.538076) (xy 85.821536 -266.553137) (xy 85.864989 -266.560812)
			(xy 85.887052 -266.561316) (xy 87.160608 -266.561316) (xy 87.183701 -266.560817) (xy 87.229129 -266.552478)
			(xy 87.272298 -266.53606) (xy 87.311785 -266.512102) (xy 87.346287 -266.481397) (xy 87.374665 -266.444957)
			(xy 87.395983 -266.403985) (xy 87.409537 -266.359832) (xy 87.41488 -266.313956) (xy 87.411836 -266.26787)
			(xy 87.406734 -266.24534) (xy 87.400458 -266.21831) (xy 87.394876 -266.163104) (xy 87.39735 -266.107671)
			(xy 87.407827 -266.05318) (xy 87.426085 -266.000782) (xy 87.451741 -265.951581) (xy 87.484252 -265.906615)
			(xy 87.522934 -265.866832) (xy 87.566969 -265.833071) (xy 87.615431 -265.806044) (xy 87.667296 -265.786321)
			(xy 87.72147 -265.774319) (xy 87.776812 -265.77029) (xy 87.832154 -265.774319) (xy 87.886328 -265.786321)
			(xy 87.938193 -265.806044) (xy 87.986655 -265.833071) (xy 88.03069 -265.866832) (xy 88.069372 -265.906615)
			(xy 88.101883 -265.951581) (xy 88.127539 -266.000782) (xy 88.145797 -266.05318) (xy 88.156274 -266.107671)
			(xy 88.158748 -266.163104) (xy 88.153166 -266.21831) (xy 88.14689 -266.24534) (xy 88.141749 -266.267854)
			(xy 88.138761 -266.313935) (xy 88.144145 -266.359797) (xy 88.157724 -266.403932) (xy 88.17905 -266.444889)
			(xy 88.207423 -266.481322) (xy 88.241909 -266.51203) (xy 88.281374 -266.536006) (xy 88.32452 -266.55246)
			(xy 88.369928 -266.56085) (xy 88.393016 -266.561316) (xy 94.16923 -266.561316) (xy 100.768912 -273.160998)
			(xy 100.81133 -273.20367) (xy 100.81133 -289.7124) (xy 98.569272 -291.954458) (xy 98.569272 -299.466254)
			(xy 98.58502 -299.494956) (xy 98.597933 -299.519297) (xy 98.617393 -299.570845) (xy 98.629232 -299.624657)
			(xy 98.633205 -299.679612) (xy 98.629229 -299.734568) (xy 98.617386 -299.788379) (xy 98.597923 -299.839926)
			(xy 98.58502 -299.864272) (xy 98.569272 -299.892974) (xy 98.569272 -311.512712) (xy 92.338906 -317.742824)
			(xy 92.140786 -317.742824) (xy 92.124134 -317.74332) (xy 92.091965 -317.751944) (xy 92.063124 -317.768601)
			(xy 92.039577 -317.792154) (xy 92.02293 -317.821) (xy 92.014315 -317.853171) (xy 92.013786 -317.869824)
			(xy 92.013786 -317.916052) (xy 92.07246 -317.986664) (xy 92.117926 -317.994792) (xy 92.155045 -318.002086)
			(xy 92.2276 -318.023505) (xy 92.297474 -318.052497) (xy 92.363881 -318.088734) (xy 92.42607 -318.131809)
			(xy 92.483342 -318.181236) (xy 92.535049 -318.236457) (xy 92.580609 -318.296849) (xy 92.619509 -318.361732)
			(xy 92.651309 -318.430374) (xy 92.675651 -318.502002) (xy 92.69226 -318.575806) (xy 92.70095 -318.650956)
			(xy 92.701622 -318.726603) (xy 92.694269 -318.801896) (xy 92.678974 -318.875984) (xy 92.655908 -318.948032)
			(xy 92.625333 -319.017228) (xy 92.587592 -319.082793) (xy 92.543112 -319.143985) (xy 92.492394 -319.200116)
			(xy 92.43601 -319.250552) (xy 92.374595 -319.294725) (xy 92.308843 -319.332137) (xy 92.239495 -319.362366)
			(xy 92.167332 -319.38507) (xy 92.093168 -319.399995) (xy 92.01784 -319.406971) (xy 91.942197 -319.40592)
			(xy 91.867092 -319.396854) (xy 91.830144 -319.388744) (xy 91.814349 -319.385602) (xy 91.782165 -319.386477)
			(xy 91.751222 -319.395371) (xy 91.726271 -319.41008) (xy 93.154506 -319.41008) (xy 93.158522 -319.29381)
			(xy 93.170549 -319.178095) (xy 93.190531 -319.063485) (xy 93.218373 -318.950526) (xy 93.253942 -318.839758)
			(xy 93.297068 -318.731707) (xy 93.347545 -318.626889) (xy 93.405134 -318.525804) (xy 93.46956 -318.428932)
			(xy 93.540515 -318.336736) (xy 93.617662 -318.249655) (xy 93.700633 -318.168104) (xy 93.789033 -318.092472)
			(xy 93.88244 -318.023118) (xy 93.980409 -317.960375) (xy 94.082473 -317.904539) (xy 94.188147 -317.855878)
			(xy 94.296926 -317.814624) (xy 94.408291 -317.780973) (xy 94.521714 -317.755085) (xy 94.636651 -317.737084)
			(xy 94.752557 -317.727055) (xy 94.868879 -317.725047) (xy 94.985062 -317.731069) (xy 95.100553 -317.745092)
			(xy 95.214801 -317.76705) (xy 95.327262 -317.796837) (xy 95.4374 -317.834312) (xy 95.54469 -317.879297)
			(xy 95.648621 -317.931576) (xy 95.748697 -317.990901) (xy 95.844443 -318.056989) (xy 95.9354 -318.129525)
			(xy 96.021136 -318.208164) (xy 96.101243 -318.29253) (xy 96.175339 -318.382222) (xy 96.243069 -318.476812)
			(xy 96.304113 -318.57585) (xy 96.358178 -318.678863) (xy 96.405008 -318.78536) (xy 96.444379 -318.894835)
			(xy 96.476103 -319.006765) (xy 96.500029 -319.120617) (xy 96.516043 -319.235849) (xy 96.52407 -319.351911)
			(xy 96.524572 -319.41008) (xy 96.52407 -319.468249) (xy 96.516043 -319.584311) (xy 96.500029 -319.699543)
			(xy 96.476103 -319.813395) (xy 96.444379 -319.925325) (xy 96.405008 -320.0348) (xy 96.358178 -320.141297)
			(xy 96.304113 -320.24431) (xy 96.243069 -320.343348) (xy 96.175339 -320.437938) (xy 96.101243 -320.52763)
			(xy 96.021136 -320.611996) (xy 95.9354 -320.690635) (xy 95.844443 -320.763171) (xy 95.748697 -320.829259)
			(xy 95.648621 -320.888584) (xy 95.54469 -320.940863) (xy 95.4374 -320.985848) (xy 95.327262 -321.023323)
			(xy 95.214801 -321.05311) (xy 95.100553 -321.075068) (xy 94.985062 -321.089091) (xy 94.868879 -321.095113)
			(xy 94.752557 -321.093105) (xy 94.636651 -321.083076) (xy 94.521714 -321.065075) (xy 94.408291 -321.039187)
			(xy 94.296926 -321.005536) (xy 94.188147 -320.964282) (xy 94.082473 -320.915621) (xy 93.980409 -320.859785)
			(xy 93.88244 -320.797042) (xy 93.789033 -320.727688) (xy 93.700633 -320.652056) (xy 93.617662 -320.570505)
			(xy 93.540515 -320.483424) (xy 93.46956 -320.391228) (xy 93.405134 -320.294356) (xy 93.347545 -320.193271)
			(xy 93.297068 -320.088453) (xy 93.253942 -319.980402) (xy 93.218373 -319.869634) (xy 93.190531 -319.756675)
			(xy 93.170549 -319.642065) (xy 93.158522 -319.52635) (xy 93.154506 -319.41008) (xy 91.726271 -319.41008)
			(xy 91.723487 -319.411721) (xy 91.71178 -319.42278) (xy 91.64955 -319.48501) (xy 91.627233 -319.486284)
			(xy 91.583534 -319.495682) (xy 91.542152 -319.512578) (xy 91.504364 -319.536451) (xy 91.471334 -319.566566)
			(xy 91.44408 -319.601994) (xy 91.423443 -319.641642) (xy 91.410058 -319.684289) (xy 91.404339 -319.728619)
			(xy 91.406462 -319.773267) (xy 91.411044 -319.795144) (xy 91.41867 -319.827695) (xy 91.428502 -319.893828)
			(xy 91.432084 -319.960591) (xy 91.429385 -320.027397) (xy 91.425268 -320.060574) (xy 91.419833 -320.097164)
			(xy 91.402351 -320.169046) (xy 91.377507 -320.238727) (xy 91.345571 -320.305456) (xy 91.306885 -320.368512)
			(xy 91.261869 -320.427216) (xy 91.211006 -320.480935) (xy 91.154847 -320.529088) (xy 91.093996 -320.571157)
			(xy 91.029109 -320.606688) (xy 90.960888 -320.635298) (xy 90.890067 -320.656677) (xy 90.817411 -320.670596)
			(xy 90.743703 -320.676904) (xy 90.669739 -320.675534) (xy 90.596315 -320.666499) (xy 90.560144 -320.658744)
			(xy 90.544349 -320.655602) (xy 90.512165 -320.656477) (xy 90.481222 -320.665371) (xy 90.453487 -320.681721)
			(xy 90.44178 -320.69278) (xy 89.422732 -321.711828) (xy 85.344508 -321.711828) (xy 84.374736 -320.742056)
			(xy 84.36262 -320.730603) (xy 84.333779 -320.713897) (xy 84.301596 -320.705231) (xy 84.268266 -320.705196)
			(xy 84.236065 -320.713796) (xy 84.20719 -320.730442) (xy 84.183612 -320.753999) (xy 84.166939 -320.782859)
			(xy 84.158311 -320.815053) (xy 84.15782 -320.831718) (xy 84.15782 -320.87566) (xy 81.24952 -323.78396)
			(xy 81.24952 -324.979538) (xy 82.79079 -324.979538) (xy 82.794861 -324.923916) (xy 82.806987 -324.869479)
			(xy 82.82691 -324.817388) (xy 82.854206 -324.768753) (xy 82.888292 -324.72461) (xy 82.928441 -324.685901)
			(xy 82.973799 -324.65345) (xy 83.023399 -324.627949) (xy 83.076183 -324.609942) (xy 83.131026 -324.599812)
			(xy 83.18676 -324.597775) (xy 83.242197 -324.603875) (xy 83.296154 -324.617981) (xy 83.347483 -324.639793)
			(xy 83.395089 -324.668847) (xy 83.437957 -324.704522) (xy 83.475174 -324.746059) (xy 83.505947 -324.792572)
			(xy 83.529619 -324.843069) (xy 83.545687 -324.896476) (xy 83.553807 -324.951652) (xy 83.554316 -324.979538)
			(xy 83.553807 -325.007424) (xy 83.545687 -325.0626) (xy 83.529619 -325.116007) (xy 83.505947 -325.166504)
			(xy 83.475174 -325.213017) (xy 83.437957 -325.254554) (xy 83.395089 -325.290229) (xy 83.347483 -325.319283)
			(xy 83.296154 -325.341095) (xy 83.242197 -325.355201) (xy 83.18676 -325.361301) (xy 83.131026 -325.359264)
			(xy 83.076183 -325.349134) (xy 83.023399 -325.331127) (xy 82.973799 -325.305626) (xy 82.928441 -325.273175)
			(xy 82.888292 -325.234466) (xy 82.854206 -325.190323) (xy 82.82691 -325.141688) (xy 82.806987 -325.089597)
			(xy 82.794861 -325.03516) (xy 82.79079 -324.979538) (xy 81.24952 -324.979538) (xy 81.24952 -325.078852)
			(xy 81.250003 -325.101945) (xy 81.258305 -325.147379) (xy 81.27468 -325.190564) (xy 81.29859 -325.230079)
			(xy 81.329247 -325.264622) (xy 81.365642 -325.293057) (xy 81.406576 -325.314447) (xy 81.450701 -325.328088)
			(xy 81.496565 -325.33353) (xy 81.542657 -325.330594) (xy 81.58746 -325.319377) (xy 81.608676 -325.310246)
			(xy 81.633701 -325.298012) (xy 81.686453 -325.280124) (xy 81.741245 -325.270099) (xy 81.796913 -325.268151)
			(xy 81.852272 -325.274321) (xy 81.906145 -325.288478) (xy 81.957385 -325.31032) (xy 82.004904 -325.339384)
			(xy 82.04769 -325.37505) (xy 82.084833 -325.41656) (xy 82.115542 -325.463032) (xy 82.139166 -325.513476)
			(xy 82.155201 -325.56682) (xy 82.163306 -325.621929) (xy 82.163309 -325.677631) (xy 82.15521 -325.732741)
			(xy 82.13918 -325.786086) (xy 82.115562 -325.836533) (xy 82.084857 -325.883008) (xy 82.047719 -325.924522)
			(xy 82.004937 -325.960193) (xy 81.957421 -325.989261) (xy 81.906183 -326.011109) (xy 81.852311 -326.025271)
			(xy 81.796953 -326.031447) (xy 81.741285 -326.029505) (xy 81.686491 -326.019486) (xy 81.633738 -326.001604)
			(xy 81.608676 -325.989442) (xy 81.587447 -325.980342) (xy 81.542644 -325.969131) (xy 81.496553 -325.966199)
			(xy 81.45069 -325.971642) (xy 81.406566 -325.98528) (xy 81.365631 -326.006665) (xy 81.329233 -326.035093)
			(xy 81.298569 -326.069629) (xy 81.27465 -326.109136) (xy 81.26291 -326.140064) (xy 83.341208 -326.140064)
			(xy 83.345279 -326.084442) (xy 83.357405 -326.030005) (xy 83.377328 -325.977914) (xy 83.404624 -325.929279)
			(xy 83.43871 -325.885136) (xy 83.478859 -325.846427) (xy 83.524217 -325.813976) (xy 83.573817 -325.788475)
			(xy 83.626601 -325.770468) (xy 83.681444 -325.760338) (xy 83.737178 -325.758301) (xy 83.792615 -325.764401)
			(xy 83.846572 -325.778507) (xy 83.897901 -325.800319) (xy 83.945507 -325.829373) (xy 83.988375 -325.865048)
			(xy 84.025592 -325.906585) (xy 84.056365 -325.953098) (xy 84.080037 -326.003595) (xy 84.096105 -326.057002)
			(xy 84.104225 -326.112178) (xy 84.104734 -326.140064) (xy 84.104225 -326.16795) (xy 84.096105 -326.223126)
			(xy 84.080037 -326.276533) (xy 84.056365 -326.32703) (xy 84.025592 -326.373543) (xy 83.988375 -326.41508)
			(xy 83.945507 -326.450755) (xy 83.897901 -326.479809) (xy 83.846572 -326.501621) (xy 83.792615 -326.515727)
			(xy 83.737178 -326.521827) (xy 83.681444 -326.51979) (xy 83.626601 -326.50966) (xy 83.573817 -326.491653)
			(xy 83.524217 -326.466152) (xy 83.478859 -326.433701) (xy 83.43871 -326.394992) (xy 83.404624 -326.350849)
			(xy 83.377328 -326.302214) (xy 83.357405 -326.250123) (xy 83.345279 -326.195686) (xy 83.341208 -326.140064)
			(xy 81.26291 -326.140064) (xy 81.25826 -326.152315) (xy 81.249941 -326.197744) (xy 81.24952 -326.220836)
			(xy 81.24952 -327.462134) (xy 82.91271 -327.462134) (xy 82.916781 -327.406512) (xy 82.928907 -327.352075)
			(xy 82.94883 -327.299984) (xy 82.976126 -327.251349) (xy 83.010212 -327.207206) (xy 83.050361 -327.168497)
			(xy 83.095719 -327.136046) (xy 83.145319 -327.110545) (xy 83.198103 -327.092538) (xy 83.252946 -327.082408)
			(xy 83.30868 -327.080371) (xy 83.364117 -327.086471) (xy 83.418074 -327.100577) (xy 83.469403 -327.122389)
			(xy 83.517009 -327.151443) (xy 83.559877 -327.187118) (xy 83.597094 -327.228655) (xy 83.627867 -327.275168)
			(xy 83.651539 -327.325665) (xy 83.667607 -327.379072) (xy 83.675727 -327.434248) (xy 83.676236 -327.462134)
			(xy 83.675727 -327.49002) (xy 83.667607 -327.545196) (xy 83.651539 -327.598603) (xy 83.627867 -327.6491)
			(xy 83.597094 -327.695613) (xy 83.559877 -327.73715) (xy 83.517009 -327.772825) (xy 83.469403 -327.801879)
			(xy 83.418074 -327.823691) (xy 83.364117 -327.837797) (xy 83.30868 -327.843897) (xy 83.252946 -327.84186)
			(xy 83.198103 -327.83173) (xy 83.145319 -327.813723) (xy 83.095719 -327.788222) (xy 83.050361 -327.755771)
			(xy 83.010212 -327.717062) (xy 82.976126 -327.672919) (xy 82.94883 -327.624284) (xy 82.928907 -327.572193)
			(xy 82.916781 -327.517756) (xy 82.91271 -327.462134) (xy 81.24952 -327.462134) (xy 81.24952 -330.01712)
			(xy 80.10652 -331.16012) (xy 86.877404 -331.16012) (xy 86.881424 -330.969469) (xy 86.893478 -330.779156)
			(xy 86.913544 -330.589521) (xy 86.941587 -330.4009) (xy 86.977556 -330.21363) (xy 87.021388 -330.028042)
			(xy 87.073005 -329.844467) (xy 87.132315 -329.663231) (xy 87.199213 -329.484656) (xy 87.273579 -329.309061)
			(xy 87.355281 -329.136756) (xy 87.444175 -328.968049) (xy 87.540101 -328.803239) (xy 87.64289 -328.64262)
			(xy 87.752359 -328.486477) (xy 87.868313 -328.335088) (xy 87.990547 -328.188721) (xy 88.118841 -328.047637)
			(xy 88.252969 -327.912088) (xy 88.392693 -327.782313) (xy 88.537763 -327.658543) (xy 88.687921 -327.541)
			(xy 88.842902 -327.429891) (xy 89.002429 -327.325414) (xy 89.166218 -327.227755) (xy 89.333978 -327.137088)
			(xy 89.505412 -327.053574) (xy 89.680214 -326.977361) (xy 89.858073 -326.908585) (xy 90.038674 -326.847367)
			(xy 90.221694 -326.793818) (xy 90.40681 -326.748032) (xy 90.593691 -326.71009) (xy 90.782006 -326.680061)
			(xy 90.971419 -326.657996) (xy 91.161593 -326.643937) (xy 91.352192 -326.637907) (xy 91.542875 -326.639917)
			(xy 91.733304 -326.649964) (xy 91.92314 -326.66803) (xy 92.112046 -326.694083) (xy 92.299685 -326.728076)
			(xy 92.485725 -326.769949) (xy 92.669834 -326.819628) (xy 92.851685 -326.877024) (xy 93.030955 -326.942035)
			(xy 93.207325 -327.014546) (xy 93.380481 -327.094427) (xy 93.550116 -327.181537) (xy 93.715928 -327.275721)
			(xy 93.877622 -327.376812) (xy 94.03491 -327.484628) (xy 94.187513 -327.59898) (xy 94.335161 -327.719663)
			(xy 94.477589 -327.846464) (xy 94.614545 -327.979155) (xy 94.745786 -328.117503) (xy 94.871078 -328.26126)
			(xy 94.990198 -328.410171) (xy 95.102934 -328.563972) (xy 95.209087 -328.722388) (xy 95.308467 -328.885139)
			(xy 95.400897 -329.051934) (xy 95.486214 -329.222478) (xy 95.564266 -329.396466) (xy 95.634913 -329.573591)
			(xy 95.698031 -329.753536) (xy 95.753507 -329.935982) (xy 95.801242 -330.120605) (xy 95.841152 -330.307075)
			(xy 95.873165 -330.495063) (xy 95.897225 -330.684233) (xy 95.913288 -330.874249) (xy 95.921327 -331.064773)
			(xy 95.92183 -331.16012) (xy 95.921327 -331.255467) (xy 95.913288 -331.445991) (xy 95.897225 -331.636007)
			(xy 95.873165 -331.825177) (xy 95.841152 -332.013165) (xy 95.801242 -332.199635) (xy 95.753507 -332.384258)
			(xy 95.698031 -332.566704) (xy 95.634913 -332.746649) (xy 95.564266 -332.923774) (xy 95.486214 -333.097762)
			(xy 95.400897 -333.268306) (xy 95.308467 -333.435101) (xy 95.209087 -333.597852) (xy 95.102934 -333.756268)
			(xy 94.990198 -333.910069) (xy 94.871078 -334.05898) (xy 94.745786 -334.202737) (xy 94.614545 -334.341085)
			(xy 94.477589 -334.473776) (xy 94.335161 -334.600577) (xy 94.187513 -334.72126) (xy 94.03491 -334.835612)
			(xy 93.877622 -334.943428) (xy 93.715928 -335.044519) (xy 93.550116 -335.138703) (xy 93.380481 -335.225813)
			(xy 93.207325 -335.305694) (xy 93.030955 -335.378205) (xy 92.851685 -335.443216) (xy 92.669834 -335.500612)
			(xy 92.485725 -335.550291) (xy 92.299685 -335.592164) (xy 92.112046 -335.626157) (xy 91.92314 -335.65221)
			(xy 91.733304 -335.670276) (xy 91.542875 -335.680323) (xy 91.352192 -335.682333) (xy 91.161593 -335.676303)
			(xy 90.971419 -335.662244) (xy 90.782006 -335.640179) (xy 90.593691 -335.61015) (xy 90.40681 -335.572208)
			(xy 90.221694 -335.526422) (xy 90.038674 -335.472873) (xy 89.858073 -335.411655) (xy 89.680214 -335.342879)
			(xy 89.505412 -335.266666) (xy 89.333978 -335.183152) (xy 89.166218 -335.092485) (xy 89.002429 -334.994826)
			(xy 88.842902 -334.890349) (xy 88.687921 -334.77924) (xy 88.537763 -334.661697) (xy 88.392693 -334.537927)
			(xy 88.252969 -334.408152) (xy 88.118841 -334.272603) (xy 87.990547 -334.131519) (xy 87.868313 -333.985152)
			(xy 87.752359 -333.833763) (xy 87.64289 -333.67762) (xy 87.540101 -333.517001) (xy 87.444175 -333.352191)
			(xy 87.355281 -333.183484) (xy 87.273579 -333.011179) (xy 87.199213 -332.835584) (xy 87.132315 -332.657009)
			(xy 87.073005 -332.475773) (xy 87.021388 -332.292198) (xy 86.977556 -332.10661) (xy 86.941587 -331.91934)
			(xy 86.913544 -331.730719) (xy 86.893478 -331.541084) (xy 86.881424 -331.350771) (xy 86.877404 -331.16012)
			(xy 80.10652 -331.16012) (xy 70.016878 -341.249762) (xy 72.868035 -341.249762) (xy 72.872042 -341.047012)
			(xy 72.884055 -340.844578) (xy 72.904056 -340.642777) (xy 72.932015 -340.441923) (xy 72.967886 -340.242331)
			(xy 73.011615 -340.044312) (xy 73.063133 -339.848175) (xy 73.122359 -339.654227) (xy 73.189201 -339.462769)
			(xy 73.263555 -339.274102) (xy 73.345304 -339.08852) (xy 73.434322 -338.906312) (xy 73.530468 -338.727763)
			(xy 73.633593 -338.553152) (xy 73.743536 -338.382752) (xy 73.860125 -338.216828) (xy 73.983178 -338.055639)
			(xy 74.112503 -337.899438) (xy 74.247898 -337.748468) (xy 74.389151 -337.602964) (xy 74.536043 -337.463155)
			(xy 74.688343 -337.329258) (xy 74.845814 -337.201483) (xy 75.008211 -337.080028) (xy 75.175278 -336.965084)
			(xy 75.346757 -336.85683) (xy 75.522378 -336.755435) (xy 75.701868 -336.661057) (xy 75.884946 -336.573845)
			(xy 76.071327 -336.493933) (xy 76.26072 -336.421446) (xy 76.452828 -336.356499) (xy 76.647352 -336.299191)
			(xy 76.843988 -336.249614) (xy 77.04243 -336.207843) (xy 77.242367 -336.173945) (xy 77.443486 -336.147973)
			(xy 77.645475 -336.129966) (xy 77.848018 -336.119953) (xy 78.050798 -336.117949) (xy 78.253499 -336.123959)
			(xy 78.455804 -336.137971) (xy 78.657398 -336.159966) (xy 78.857965 -336.189907) (xy 79.057193 -336.227748)
			(xy 79.254771 -336.273431) (xy 79.450389 -336.326884) (xy 79.643743 -336.388023) (xy 79.834531 -336.456754)
			(xy 80.022454 -336.532968) (xy 80.20722 -336.616547) (xy 80.388539 -336.70736) (xy 80.56613 -336.805265)
			(xy 80.739713 -336.91011) (xy 80.909019 -337.021731) (xy 81.073784 -337.139953) (xy 81.233749 -337.264593)
			(xy 81.388665 -337.395454) (xy 81.53829 -337.532334) (xy 81.68239 -337.675018) (xy 81.820742 -337.823284)
			(xy 81.953127 -337.9769) (xy 82.079341 -338.135625) (xy 82.199185 -338.299214) (xy 82.312473 -338.467409)
			(xy 82.419028 -338.639948) (xy 82.518683 -338.816563) (xy 82.611283 -338.996976) (xy 82.696683 -339.180907)
			(xy 82.77475 -339.368068) (xy 82.845362 -339.558168) (xy 82.908408 -339.750908) (xy 82.963791 -339.945989)
			(xy 83.011423 -340.143106) (xy 83.051231 -340.34195) (xy 83.083153 -340.542212) (xy 83.107137 -340.743578)
			(xy 83.123148 -340.945735) (xy 83.131159 -341.148367) (xy 83.13166 -341.249762) (xy 83.131159 -341.351157)
			(xy 83.123148 -341.553789) (xy 83.107137 -341.755946) (xy 83.083153 -341.957312) (xy 83.051231 -342.157574)
			(xy 83.011423 -342.356418) (xy 82.963791 -342.553535) (xy 82.908408 -342.748616) (xy 82.845362 -342.941356)
			(xy 82.77475 -343.131456) (xy 82.696683 -343.318617) (xy 82.611283 -343.502548) (xy 82.518683 -343.682961)
			(xy 82.419028 -343.859576) (xy 82.312473 -344.032115) (xy 82.199185 -344.20031) (xy 82.079341 -344.363899)
			(xy 81.953127 -344.522624) (xy 81.820742 -344.67624) (xy 81.68239 -344.824506) (xy 81.53829 -344.96719)
			(xy 81.388665 -345.10407) (xy 81.233749 -345.234931) (xy 81.073784 -345.359571) (xy 80.909019 -345.477793)
			(xy 80.739713 -345.589414) (xy 80.56613 -345.694259) (xy 80.388539 -345.792164) (xy 80.20722 -345.882977)
			(xy 80.022454 -345.966556) (xy 79.834531 -346.04277) (xy 79.643743 -346.111501) (xy 79.450389 -346.17264)
			(xy 79.254771 -346.226093) (xy 79.057193 -346.271776) (xy 78.857965 -346.309617) (xy 78.657398 -346.339558)
			(xy 78.455804 -346.361553) (xy 78.253499 -346.375565) (xy 78.050798 -346.381575) (xy 77.848018 -346.379571)
			(xy 77.645475 -346.369558) (xy 77.443486 -346.351551) (xy 77.242367 -346.325579) (xy 77.04243 -346.291681)
			(xy 76.843988 -346.24991) (xy 76.647352 -346.200333) (xy 76.452828 -346.143025) (xy 76.26072 -346.078078)
			(xy 76.071327 -346.005591) (xy 75.884946 -345.925679) (xy 75.701868 -345.838467) (xy 75.522378 -345.744089)
			(xy 75.346757 -345.642694) (xy 75.175278 -345.53444) (xy 75.008211 -345.419496) (xy 74.845814 -345.298041)
			(xy 74.688343 -345.170266) (xy 74.536043 -345.036369) (xy 74.389151 -344.89656) (xy 74.247898 -344.751056)
			(xy 74.112503 -344.600086) (xy 73.983178 -344.443885) (xy 73.860125 -344.282696) (xy 73.743536 -344.116772)
			(xy 73.633593 -343.946372) (xy 73.530468 -343.771761) (xy 73.434322 -343.593212) (xy 73.345304 -343.411004)
			(xy 73.263555 -343.225422) (xy 73.189201 -343.036755) (xy 73.122359 -342.845297) (xy 73.063133 -342.651349)
			(xy 73.011615 -342.455212) (xy 72.967886 -342.257193) (xy 72.932015 -342.057601) (xy 72.904056 -341.856747)
			(xy 72.884055 -341.654946) (xy 72.872042 -341.452512) (xy 72.868035 -341.249762) (xy 70.016878 -341.249762)
			(xy 64.39916 -346.86748) (xy 94.786956 -346.86748) (xy 94.791027 -346.811858) (xy 94.803153 -346.757421)
			(xy 94.823076 -346.70533) (xy 94.850372 -346.656695) (xy 94.884458 -346.612552) (xy 94.924607 -346.573843)
			(xy 94.969965 -346.541392) (xy 95.019565 -346.515891) (xy 95.072349 -346.497884) (xy 95.127192 -346.487754)
			(xy 95.182926 -346.485717) (xy 95.238363 -346.491817) (xy 95.29232 -346.505923) (xy 95.343649 -346.527735)
			(xy 95.391255 -346.556789) (xy 95.434123 -346.592464) (xy 95.47134 -346.634001) (xy 95.502113 -346.680514)
			(xy 95.525785 -346.731011) (xy 95.541853 -346.784418) (xy 95.549973 -346.839594) (xy 95.550482 -346.86748)
			(xy 95.549973 -346.895366) (xy 95.541853 -346.950542) (xy 95.525785 -347.003949) (xy 95.502113 -347.054446)
			(xy 95.47134 -347.100959) (xy 95.434123 -347.142496) (xy 95.391255 -347.178171) (xy 95.343649 -347.207225)
			(xy 95.29232 -347.229037) (xy 95.238363 -347.243143) (xy 95.182926 -347.249243) (xy 95.127192 -347.247206)
			(xy 95.072349 -347.237076) (xy 95.019565 -347.219069) (xy 94.969965 -347.193568) (xy 94.924607 -347.161117)
			(xy 94.884458 -347.122408) (xy 94.850372 -347.078265) (xy 94.823076 -347.02963) (xy 94.803153 -346.977539)
			(xy 94.791027 -346.923102) (xy 94.786956 -346.86748) (xy 64.39916 -346.86748) (xy 61.707014 -349.559626)
			(xy 46.044104 -349.559626) (xy 44.797811 -350.805919) (xy 47.574698 -350.805919) (xy 47.574698 -350.724809)
			(xy 47.582648 -350.64409) (xy 47.598471 -350.564539) (xy 47.622016 -350.486923) (xy 47.653055 -350.411987)
			(xy 47.69129 -350.340455) (xy 47.736352 -350.273015) (xy 47.787807 -350.210316) (xy 47.84516 -350.152963)
			(xy 47.907859 -350.101508) (xy 47.975299 -350.056446) (xy 48.046831 -350.018211) (xy 48.121767 -349.987172)
			(xy 48.199383 -349.963627) (xy 48.278934 -349.947804) (xy 48.359653 -349.939854) (xy 48.440763 -349.939854)
			(xy 48.521482 -349.947804) (xy 48.601033 -349.963627) (xy 48.678649 -349.987172) (xy 48.753585 -350.018211)
			(xy 48.825117 -350.056446) (xy 48.892557 -350.101508) (xy 48.955256 -350.152963) (xy 49.012609 -350.210316)
			(xy 49.064064 -350.273015) (xy 49.109126 -350.340455) (xy 49.147361 -350.411987) (xy 49.1784 -350.486923)
			(xy 49.201945 -350.564539) (xy 49.217768 -350.64409) (xy 49.225718 -350.724809) (xy 49.226216 -350.765364)
			(xy 49.225718 -350.805919) (xy 51.074818 -350.805919) (xy 51.074818 -350.724809) (xy 51.082768 -350.64409)
			(xy 51.098591 -350.564539) (xy 51.122136 -350.486923) (xy 51.153175 -350.411987) (xy 51.19141 -350.340455)
			(xy 51.236472 -350.273015) (xy 51.287927 -350.210316) (xy 51.34528 -350.152963) (xy 51.407979 -350.101508)
			(xy 51.475419 -350.056446) (xy 51.546951 -350.018211) (xy 51.621887 -349.987172) (xy 51.699503 -349.963627)
			(xy 51.779054 -349.947804) (xy 51.859773 -349.939854) (xy 51.940883 -349.939854) (xy 52.021602 -349.947804)
			(xy 52.101153 -349.963627) (xy 52.178769 -349.987172) (xy 52.253705 -350.018211) (xy 52.325237 -350.056446)
			(xy 52.392677 -350.101508) (xy 52.455376 -350.152963) (xy 52.512729 -350.210316) (xy 52.564184 -350.273015)
			(xy 52.609246 -350.340455) (xy 52.647481 -350.411987) (xy 52.67852 -350.486923) (xy 52.702065 -350.564539)
			(xy 52.717888 -350.64409) (xy 52.725838 -350.724809) (xy 52.726336 -350.765364) (xy 52.725838 -350.805919)
			(xy 52.717888 -350.886638) (xy 52.702065 -350.966189) (xy 52.67852 -351.043805) (xy 52.647481 -351.118741)
			(xy 52.609246 -351.190273) (xy 52.564184 -351.257713) (xy 52.512729 -351.320412) (xy 52.455376 -351.377765)
			(xy 52.392677 -351.42922) (xy 52.325237 -351.474282) (xy 52.253705 -351.512517) (xy 52.178769 -351.543556)
			(xy 52.101153 -351.567101) (xy 52.021602 -351.582924) (xy 51.940883 -351.590874) (xy 51.859773 -351.590874)
			(xy 51.779054 -351.582924) (xy 51.699503 -351.567101) (xy 51.621887 -351.543556) (xy 51.546951 -351.512517)
			(xy 51.475419 -351.474282) (xy 51.407979 -351.42922) (xy 51.34528 -351.377765) (xy 51.287927 -351.320412)
			(xy 51.236472 -351.257713) (xy 51.19141 -351.190273) (xy 51.153175 -351.118741) (xy 51.122136 -351.043805)
			(xy 51.098591 -350.966189) (xy 51.082768 -350.886638) (xy 51.074818 -350.805919) (xy 49.225718 -350.805919)
			(xy 49.217768 -350.886638) (xy 49.201945 -350.966189) (xy 49.1784 -351.043805) (xy 49.147361 -351.118741)
			(xy 49.109126 -351.190273) (xy 49.064064 -351.257713) (xy 49.012609 -351.320412) (xy 48.955256 -351.377765)
			(xy 48.892557 -351.42922) (xy 48.825117 -351.474282) (xy 48.753585 -351.512517) (xy 48.678649 -351.543556)
			(xy 48.601033 -351.567101) (xy 48.521482 -351.582924) (xy 48.440763 -351.590874) (xy 48.359653 -351.590874)
			(xy 48.278934 -351.582924) (xy 48.199383 -351.567101) (xy 48.121767 -351.543556) (xy 48.046831 -351.512517)
			(xy 47.975299 -351.474282) (xy 47.907859 -351.42922) (xy 47.84516 -351.377765) (xy 47.787807 -351.320412)
			(xy 47.736352 -351.257713) (xy 47.69129 -351.190273) (xy 47.653055 -351.118741) (xy 47.622016 -351.043805)
			(xy 47.598471 -350.966189) (xy 47.582648 -350.886638) (xy 47.574698 -350.805919) (xy 44.797811 -350.805919)
			(xy 44.243244 -351.360486) (xy 44.243244 -352.060002) (xy 44.349416 -352.16592) (xy 95.787972 -352.16592)
		)
		(stroke
			(width 0)
			(type solid)
		)
		(fill yes)
		(layer "In5.Cu")
		(net "GND")
	)
	(gr_poly
		(pts
			(xy 45.119544 -347.765116) (xy 60.53709 -347.765116) (xy 79.153512 -329.148694) (xy 79.153512 -322.915534)
			(xy 80.601312 -321.467734) (xy 80.601312 -316.050422) (xy 90.02522 -306.626514) (xy 90.02522 -298.86656)
			(xy 82.627724 -291.469064) (xy 82.627724 -286.310832) (xy 82.611976 -286.28213) (xy 82.599064 -286.257789)
			(xy 82.579606 -286.206242) (xy 82.567769 -286.15243) (xy 82.563798 -286.097475) (xy 82.567776 -286.042521)
			(xy 82.57962 -285.988711) (xy 82.599085 -285.937166) (xy 82.611976 -285.912814) (xy 82.627724 -285.884112)
			(xy 82.627724 -281.974798) (xy 85.321902 -279.28062) (xy 85.322156 -278.892254) (xy 85.322156 -276.226016)
			(xy 85.321686 -276.209921) (xy 85.313628 -276.178756) (xy 85.298022 -276.150602) (xy 85.275862 -276.127254)
			(xy 85.262466 -276.11832) (xy 85.230084 -276.097443) (xy 85.169565 -276.049754) (xy 85.114551 -275.995806)
			(xy 85.065688 -275.936232) (xy 85.023545 -275.871727) (xy 84.988617 -275.803048) (xy 84.961313 -275.730998)
			(xy 84.941952 -275.656419) (xy 84.93076 -275.580186) (xy 84.927868 -275.503189) (xy 84.933311 -275.426331)
			(xy 84.939632 -275.388324) (xy 84.945326 -275.358569) (xy 84.961095 -275.30007) (xy 84.971128 -275.271484)
			(xy 84.983886 -275.237789) (xy 85.015262 -275.172926) (xy 85.053031 -275.111564) (xy 85.096807 -275.054333)
			(xy 85.146141 -275.001818) (xy 85.200529 -274.954557) (xy 85.2297 -274.93341) (xy 85.261482 -274.911634)
			(xy 85.328875 -274.874292) (xy 85.399907 -274.844448) (xy 85.473747 -274.82245) (xy 85.54953 -274.808556)
			(xy 85.626371 -274.802928) (xy 85.70337 -274.805633) (xy 85.779627 -274.816639) (xy 85.854249 -274.835817)
			(xy 85.926363 -274.862942) (xy 85.995125 -274.897697) (xy 86.059732 -274.939676) (xy 86.119426 -274.988387)
			(xy 86.17351 -275.043261) (xy 86.221351 -275.103655) (xy 86.262388 -275.168864) (xy 86.296143 -275.238123)
			(xy 86.32222 -275.310622) (xy 86.331806 -275.347938) (xy 86.341712 -275.388832) (xy 86.383368 -275.42363)
			(xy 86.395948 -275.433564) (xy 86.424867 -275.447368) (xy 86.456315 -275.453526) (xy 86.488304 -275.451649)
			(xy 86.518816 -275.441856) (xy 86.545923 -275.424765) (xy 86.567913 -275.401456) (xy 86.583397 -275.3734)
			(xy 86.591398 -275.34237) (xy 86.591902 -275.326348) (xy 86.591902 -275.31822) (xy 86.592156 -275.274024)
			(xy 86.592156 -274.956016) (xy 86.591686 -274.939921) (xy 86.583628 -274.908756) (xy 86.568022 -274.880602)
			(xy 86.545862 -274.857254) (xy 86.532466 -274.84832) (xy 86.500084 -274.827443) (xy 86.439565 -274.779754)
			(xy 86.384551 -274.725806) (xy 86.335688 -274.666232) (xy 86.293545 -274.601727) (xy 86.258617 -274.533048)
			(xy 86.231313 -274.460998) (xy 86.211952 -274.386419) (xy 86.20076 -274.310186) (xy 86.197868 -274.233189)
			(xy 86.203311 -274.156331) (xy 86.209632 -274.118324) (xy 86.215326 -274.088569) (xy 86.231095 -274.03007)
			(xy 86.241128 -274.001484) (xy 86.253886 -273.967789) (xy 86.285262 -273.902926) (xy 86.323031 -273.841564)
			(xy 86.366807 -273.784333) (xy 86.416141 -273.731818) (xy 86.470529 -273.684557) (xy 86.4997 -273.66341)
			(xy 86.530646 -273.64216) (xy 86.596196 -273.605565) (xy 86.665232 -273.57607) (xy 86.736989 -273.554005)
			(xy 86.81067 -273.539613) (xy 86.885456 -273.533056) (xy 86.960517 -273.534405) (xy 87.035019 -273.543647)
			(xy 87.108135 -273.560677) (xy 87.179052 -273.585307) (xy 87.246984 -273.617264) (xy 87.311175 -273.656192)
			(xy 87.370914 -273.701659) (xy 87.425535 -273.753161) (xy 87.474434 -273.810125) (xy 87.517066 -273.871918)
			(xy 87.552959 -273.937855) (xy 87.581713 -274.007203) (xy 87.603009 -274.079192) (xy 87.610188 -274.116038)
			(xy 87.61347 -274.131397) (xy 87.626494 -274.159966) (xy 87.646106 -274.184486) (xy 87.671117 -274.203468)
			(xy 87.700008 -274.215762) (xy 87.731027 -274.220622) (xy 87.762294 -274.217753) (xy 87.791911 -274.207329)
			(xy 87.818082 -274.189983) (xy 87.83922 -274.166766) (xy 87.854043 -274.139087) (xy 87.861651 -274.108624)
			(xy 87.862156 -274.092924) (xy 87.862156 -273.686016) (xy 87.861686 -273.669921) (xy 87.853628 -273.638756)
			(xy 87.838022 -273.610602) (xy 87.815862 -273.587254) (xy 87.802466 -273.57832) (xy 87.770921 -273.558012)
			(xy 87.711858 -273.511746) (xy 87.65799 -273.459522) (xy 87.609917 -273.40192) (xy 87.56817 -273.33958)
			(xy 87.533214 -273.273194) (xy 87.505437 -273.203498) (xy 87.485147 -273.131267) (xy 87.472569 -273.057302)
			(xy 87.467843 -272.982424) (xy 87.471021 -272.907464) (xy 87.482069 -272.833255) (xy 87.500863 -272.76062)
			(xy 87.527195 -272.690366) (xy 87.560772 -272.623272) (xy 87.601223 -272.560083) (xy 87.648097 -272.501501)
			(xy 87.700874 -272.448175) (xy 87.758969 -272.400699) (xy 87.821737 -272.359598) (xy 87.88848 -272.32533)
			(xy 87.958459 -272.298274) (xy 88.030896 -272.278731) (xy 88.104987 -272.266917) (xy 88.17991 -272.262965)
			(xy 88.254833 -272.266917) (xy 88.328924 -272.278731) (xy 88.401361 -272.298274) (xy 88.47134 -272.32533)
			(xy 88.538083 -272.359598) (xy 88.600851 -272.400699) (xy 88.658946 -272.448175) (xy 88.711723 -272.501501)
			(xy 88.758597 -272.560083) (xy 88.799048 -272.623272) (xy 88.832625 -272.690366) (xy 88.858957 -272.76062)
			(xy 88.877751 -272.833255) (xy 88.888799 -272.907464) (xy 88.891665 -272.97507) (xy 90.007697 -272.97507)
			(xy 90.011732 -272.899366) (xy 90.023791 -272.824521) (xy 90.043737 -272.75138) (xy 90.071344 -272.680775)
			(xy 90.1063 -272.613504) (xy 90.148208 -272.550329) (xy 90.196594 -272.491967) (xy 90.25091 -272.439079)
			(xy 90.310539 -272.392264) (xy 90.374807 -272.352052) (xy 90.442984 -272.3189) (xy 90.5143 -272.293182)
			(xy 90.587945 -272.27519) (xy 90.663085 -272.265128) (xy 90.738869 -272.263109) (xy 90.814439 -272.269158)
			(xy 90.888937 -272.283205) (xy 90.96152 -272.305091) (xy 91.031366 -272.334568) (xy 91.097683 -272.371303)
			(xy 91.159719 -272.414878) (xy 91.216772 -272.4648) (xy 91.268196 -272.520504) (xy 91.313407 -272.581359)
			(xy 91.351894 -272.646674) (xy 91.38322 -272.71571) (xy 91.40703 -272.787685) (xy 91.423055 -272.861783)
			(xy 91.431114 -272.937164) (xy 91.431618 -272.97507) (xy 91.431114 -273.012976) (xy 91.423055 -273.088357)
			(xy 91.40703 -273.162455) (xy 91.38322 -273.23443) (xy 91.351894 -273.303466) (xy 91.313407 -273.368781)
			(xy 91.268196 -273.429636) (xy 91.216772 -273.48534) (xy 91.159719 -273.535262) (xy 91.097683 -273.578837)
			(xy 91.031366 -273.615572) (xy 90.96152 -273.645049) (xy 90.888937 -273.666935) (xy 90.814439 -273.680982)
			(xy 90.738869 -273.687031) (xy 90.663085 -273.685012) (xy 90.587945 -273.67495) (xy 90.5143 -273.656958)
			(xy 90.442984 -273.63124) (xy 90.374807 -273.598088) (xy 90.310539 -273.557876) (xy 90.25091 -273.511061)
			(xy 90.196594 -273.458173) (xy 90.148208 -273.399811) (xy 90.1063 -273.336636) (xy 90.071344 -273.269365)
			(xy 90.043737 -273.19876) (xy 90.023791 -273.125619) (xy 90.011732 -273.050774) (xy 90.007697 -272.97507)
			(xy 88.891665 -272.97507) (xy 88.891977 -272.982424) (xy 88.887251 -273.057302) (xy 88.874673 -273.131267)
			(xy 88.854383 -273.203498) (xy 88.826606 -273.273194) (xy 88.79165 -273.33958) (xy 88.749903 -273.40192)
			(xy 88.70183 -273.459522) (xy 88.647962 -273.511746) (xy 88.588899 -273.558012) (xy 88.557354 -273.57832)
			(xy 88.54396 -273.587253) (xy 88.521812 -273.610607) (xy 88.506216 -273.638761) (xy 88.498163 -273.669923)
			(xy 88.497664 -273.686016) (xy 88.497664 -274.120864) (xy 88.53932 -274.16252) (xy 88.551438 -274.173959)
			(xy 88.580277 -274.190635) (xy 88.612452 -274.199267) (xy 88.645766 -274.199267) (xy 88.677941 -274.190635)
			(xy 88.70678 -274.173959) (xy 88.718898 -274.16252) (xy 88.745568 -274.13585) (xy 88.753442 -274.098766)
			(xy 88.762076 -274.060249) (xy 88.786751 -273.985264) (xy 88.819573 -273.913472) (xy 88.86014 -273.845753)
			(xy 88.907953 -273.782941) (xy 88.962424 -273.725807) (xy 89.022885 -273.675053) (xy 89.055448 -273.652742)
			(xy 89.087942 -273.631719) (xy 89.156638 -273.596065) (xy 89.228797 -273.568073) (xy 89.303566 -273.548074)
			(xy 89.380063 -273.536303) (xy 89.457385 -273.532901) (xy 89.534621 -273.537906) (xy 89.610858 -273.551259)
			(xy 89.685196 -273.572804) (xy 89.756758 -273.602286) (xy 89.824701 -273.639357) (xy 89.88822 -273.683579)
			(xy 89.946568 -273.734431) (xy 89.999056 -273.791312) (xy 90.022426 -273.82216) (xy 90.034364 -273.838924)
			(xy 90.055691 -273.870483) (xy 90.092233 -273.937319) (xy 90.121428 -274.007675) (xy 90.142943 -274.080746)
			(xy 90.156532 -274.155698) (xy 90.162038 -274.231671) (xy 90.161574 -274.24507) (xy 91.277697 -274.24507)
			(xy 91.281732 -274.169366) (xy 91.293791 -274.094521) (xy 91.313737 -274.02138) (xy 91.341344 -273.950775)
			(xy 91.3763 -273.883504) (xy 91.418208 -273.820329) (xy 91.466594 -273.761967) (xy 91.52091 -273.709079)
			(xy 91.580539 -273.662264) (xy 91.644807 -273.622052) (xy 91.712984 -273.5889) (xy 91.7843 -273.563182)
			(xy 91.857945 -273.54519) (xy 91.933085 -273.535128) (xy 92.008869 -273.533109) (xy 92.084439 -273.539158)
			(xy 92.158937 -273.553205) (xy 92.23152 -273.575091) (xy 92.301366 -273.604568) (xy 92.367683 -273.641303)
			(xy 92.429719 -273.684878) (xy 92.486772 -273.7348) (xy 92.538196 -273.790504) (xy 92.583407 -273.851359)
			(xy 92.621894 -273.916674) (xy 92.65322 -273.98571) (xy 92.67703 -274.057685) (xy 92.693055 -274.131783)
			(xy 92.701114 -274.207164) (xy 92.701618 -274.24507) (xy 92.701114 -274.282976) (xy 92.693055 -274.358357)
			(xy 92.67703 -274.432455) (xy 92.65322 -274.50443) (xy 92.621894 -274.573466) (xy 92.583407 -274.638781)
			(xy 92.538196 -274.699636) (xy 92.486772 -274.75534) (xy 92.429719 -274.805262) (xy 92.367683 -274.848837)
			(xy 92.301366 -274.885572) (xy 92.23152 -274.915049) (xy 92.158937 -274.936935) (xy 92.084439 -274.950982)
			(xy 92.008869 -274.957031) (xy 91.933085 -274.955012) (xy 91.857945 -274.94495) (xy 91.7843 -274.926958)
			(xy 91.712984 -274.90124) (xy 91.644807 -274.868088) (xy 91.580539 -274.827876) (xy 91.52091 -274.781061)
			(xy 91.466594 -274.728173) (xy 91.418208 -274.669811) (xy 91.3763 -274.606636) (xy 91.341344 -274.539365)
			(xy 91.313737 -274.46876) (xy 91.293791 -274.395619) (xy 91.281732 -274.320774) (xy 91.277697 -274.24507)
			(xy 90.161574 -274.24507) (xy 90.1594 -274.307799) (xy 90.148647 -274.383209) (xy 90.129902 -274.457039)
			(xy 90.10338 -274.528446) (xy 90.069384 -274.596612) (xy 90.028303 -274.660758) (xy 89.980606 -274.720149)
			(xy 89.92684 -274.774108) (xy 89.867619 -274.822016) (xy 89.80362 -274.863326) (xy 89.735576 -274.897565)
			(xy 89.664264 -274.924342) (xy 89.590501 -274.94335) (xy 89.51513 -274.954372) (xy 89.477088 -274.95627)
			(xy 89.46084 -274.957344) (xy 89.429662 -274.966704) (xy 89.401872 -274.983657) (xy 89.379283 -275.007095)
			(xy 89.363368 -275.035492) (xy 89.355164 -275.066993) (xy 89.35466 -275.08327) (xy 89.35466 -275.51507)
			(xy 90.007697 -275.51507) (xy 90.011732 -275.439366) (xy 90.023791 -275.364521) (xy 90.043737 -275.29138)
			(xy 90.071344 -275.220775) (xy 90.1063 -275.153504) (xy 90.148208 -275.090329) (xy 90.196594 -275.031967)
			(xy 90.25091 -274.979079) (xy 90.310539 -274.932264) (xy 90.374807 -274.892052) (xy 90.442984 -274.8589)
			(xy 90.5143 -274.833182) (xy 90.587945 -274.81519) (xy 90.663085 -274.805128) (xy 90.738869 -274.803109)
			(xy 90.814439 -274.809158) (xy 90.888937 -274.823205) (xy 90.96152 -274.845091) (xy 91.031366 -274.874568)
			(xy 91.097683 -274.911303) (xy 91.159719 -274.954878) (xy 91.165664 -274.96008) (xy 93.154506 -274.96008)
			(xy 93.158522 -274.84381) (xy 93.170549 -274.728095) (xy 93.190531 -274.613485) (xy 93.218373 -274.500526)
			(xy 93.253942 -274.389758) (xy 93.297068 -274.281707) (xy 93.347545 -274.176889) (xy 93.405134 -274.075804)
			(xy 93.46956 -273.978932) (xy 93.540515 -273.886736) (xy 93.617662 -273.799655) (xy 93.700633 -273.718104)
			(xy 93.789033 -273.642472) (xy 93.88244 -273.573118) (xy 93.980409 -273.510375) (xy 94.082473 -273.454539)
			(xy 94.188147 -273.405878) (xy 94.296926 -273.364624) (xy 94.408291 -273.330973) (xy 94.521714 -273.305085)
			(xy 94.636651 -273.287084) (xy 94.752557 -273.277055) (xy 94.868879 -273.275047) (xy 94.985062 -273.281069)
			(xy 95.100553 -273.295092) (xy 95.214801 -273.31705) (xy 95.327262 -273.346837) (xy 95.4374 -273.384312)
			(xy 95.54469 -273.429297) (xy 95.648621 -273.481576) (xy 95.748697 -273.540901) (xy 95.844443 -273.606989)
			(xy 95.9354 -273.679525) (xy 96.021136 -273.758164) (xy 96.101243 -273.84253) (xy 96.175339 -273.932222)
			(xy 96.243069 -274.026812) (xy 96.304113 -274.12585) (xy 96.358178 -274.228863) (xy 96.405008 -274.33536)
			(xy 96.444379 -274.444835) (xy 96.476103 -274.556765) (xy 96.500029 -274.670617) (xy 96.516043 -274.785849)
			(xy 96.52407 -274.901911) (xy 96.524572 -274.96008) (xy 96.52407 -275.018249) (xy 96.516043 -275.134311)
			(xy 96.500029 -275.249543) (xy 96.476103 -275.363395) (xy 96.444379 -275.475325) (xy 96.405008 -275.5848)
			(xy 96.358178 -275.691297) (xy 96.304113 -275.79431) (xy 96.243069 -275.893348) (xy 96.175339 -275.987938)
			(xy 96.101243 -276.07763) (xy 96.021136 -276.161996) (xy 95.9354 -276.240635) (xy 95.844443 -276.313171)
			(xy 95.748697 -276.379259) (xy 95.648621 -276.438584) (xy 95.54469 -276.490863) (xy 95.4374 -276.535848)
			(xy 95.327262 -276.573323) (xy 95.214801 -276.60311) (xy 95.100553 -276.625068) (xy 94.985062 -276.639091)
			(xy 94.868879 -276.645113) (xy 94.752557 -276.643105) (xy 94.636651 -276.633076) (xy 94.521714 -276.615075)
			(xy 94.408291 -276.589187) (xy 94.296926 -276.555536) (xy 94.188147 -276.514282) (xy 94.082473 -276.465621)
			(xy 93.980409 -276.409785) (xy 93.88244 -276.347042) (xy 93.789033 -276.277688) (xy 93.700633 -276.202056)
			(xy 93.617662 -276.120505) (xy 93.540515 -276.033424) (xy 93.46956 -275.941228) (xy 93.405134 -275.844356)
			(xy 93.347545 -275.743271) (xy 93.297068 -275.638453) (xy 93.253942 -275.530402) (xy 93.218373 -275.419634)
			(xy 93.190531 -275.306675) (xy 93.170549 -275.192065) (xy 93.158522 -275.07635) (xy 93.154506 -274.96008)
			(xy 91.165664 -274.96008) (xy 91.216772 -275.0048) (xy 91.268196 -275.060504) (xy 91.313407 -275.121359)
			(xy 91.351894 -275.186674) (xy 91.38322 -275.25571) (xy 91.40703 -275.327685) (xy 91.423055 -275.401783)
			(xy 91.431114 -275.477164) (xy 91.431618 -275.51507) (xy 91.431114 -275.552976) (xy 91.423055 -275.628357)
			(xy 91.40703 -275.702455) (xy 91.38322 -275.77443) (xy 91.351894 -275.843466) (xy 91.313407 -275.908781)
			(xy 91.268196 -275.969636) (xy 91.216772 -276.02534) (xy 91.159719 -276.075262) (xy 91.097683 -276.118837)
			(xy 91.031366 -276.155572) (xy 90.96152 -276.185049) (xy 90.888937 -276.206935) (xy 90.814439 -276.220982)
			(xy 90.738869 -276.227031) (xy 90.663085 -276.225012) (xy 90.587945 -276.21495) (xy 90.5143 -276.196958)
			(xy 90.442984 -276.17124) (xy 90.374807 -276.138088) (xy 90.310539 -276.097876) (xy 90.25091 -276.051061)
			(xy 90.196594 -275.998173) (xy 90.148208 -275.939811) (xy 90.1063 -275.876636) (xy 90.071344 -275.809365)
			(xy 90.043737 -275.73876) (xy 90.023791 -275.665619) (xy 90.011732 -275.590774) (xy 90.007697 -275.51507)
			(xy 89.35466 -275.51507) (xy 89.35466 -279.622504) (xy 88.372442 -280.604976) (xy 88.248998 -280.72842)
			(xy 87.776812 -281.200606) (xy 87.767922 -281.232102) (xy 87.75984 -281.258471) (xy 87.737139 -281.308732)
			(xy 87.70744 -281.355203) (xy 87.671362 -281.396915) (xy 87.629656 -281.433) (xy 87.583191 -281.462707)
			(xy 87.532933 -281.485417) (xy 87.506556 -281.493468) (xy 87.47506 -281.502358) (xy 85.504528 -283.47289)
			(xy 85.504528 -286.709866) (xy 86.877404 -286.709866) (xy 86.881424 -286.519215) (xy 86.893478 -286.328902)
			(xy 86.913544 -286.139267) (xy 86.941587 -285.950646) (xy 86.977556 -285.763376) (xy 87.021388 -285.577788)
			(xy 87.073005 -285.394213) (xy 87.132315 -285.212977) (xy 87.199213 -285.034402) (xy 87.273579 -284.858807)
			(xy 87.355281 -284.686502) (xy 87.444175 -284.517795) (xy 87.540101 -284.352985) (xy 87.64289 -284.192366)
			(xy 87.752359 -284.036223) (xy 87.868313 -283.884834) (xy 87.990547 -283.738467) (xy 88.118841 -283.597383)
			(xy 88.252969 -283.461834) (xy 88.392693 -283.332059) (xy 88.537763 -283.208289) (xy 88.687921 -283.090746)
			(xy 88.842902 -282.979637) (xy 89.002429 -282.87516) (xy 89.166218 -282.777501) (xy 89.333978 -282.686834)
			(xy 89.505412 -282.60332) (xy 89.680214 -282.527107) (xy 89.858073 -282.458331) (xy 90.038674 -282.397113)
			(xy 90.221694 -282.343564) (xy 90.40681 -282.297778) (xy 90.593691 -282.259836) (xy 90.782006 -282.229807)
			(xy 90.971419 -282.207742) (xy 91.161593 -282.193683) (xy 91.352192 -282.187653) (xy 91.542875 -282.189663)
			(xy 91.733304 -282.19971) (xy 91.92314 -282.217776) (xy 92.112046 -282.243829) (xy 92.299685 -282.277822)
			(xy 92.485725 -282.319695) (xy 92.669834 -282.369374) (xy 92.851685 -282.42677) (xy 93.030955 -282.491781)
			(xy 93.207325 -282.564292) (xy 93.380481 -282.644173) (xy 93.550116 -282.731283) (xy 93.715928 -282.825467)
			(xy 93.877622 -282.926558) (xy 94.03491 -283.034374) (xy 94.187513 -283.148726) (xy 94.335161 -283.269409)
			(xy 94.477589 -283.39621) (xy 94.614545 -283.528901) (xy 94.745786 -283.667249) (xy 94.871078 -283.811006)
			(xy 94.990198 -283.959917) (xy 95.102934 -284.113718) (xy 95.209087 -284.272134) (xy 95.308467 -284.434885)
			(xy 95.400897 -284.60168) (xy 95.486214 -284.772224) (xy 95.564266 -284.946212) (xy 95.634913 -285.123337)
			(xy 95.698031 -285.303282) (xy 95.753507 -285.485728) (xy 95.801242 -285.670351) (xy 95.841152 -285.856821)
			(xy 95.873165 -286.044809) (xy 95.897225 -286.233979) (xy 95.913288 -286.423995) (xy 95.921327 -286.614519)
			(xy 95.92183 -286.709866) (xy 95.921327 -286.805213) (xy 95.913288 -286.995737) (xy 95.897225 -287.185753)
			(xy 95.873165 -287.374923) (xy 95.841152 -287.562911) (xy 95.801242 -287.749381) (xy 95.753507 -287.934004)
			(xy 95.698031 -288.11645) (xy 95.634913 -288.296395) (xy 95.564266 -288.47352) (xy 95.486214 -288.647508)
			(xy 95.400897 -288.818052) (xy 95.308467 -288.984847) (xy 95.209087 -289.147598) (xy 95.102934 -289.306014)
			(xy 94.990198 -289.459815) (xy 94.871078 -289.608726) (xy 94.745786 -289.752483) (xy 94.614545 -289.890831)
			(xy 94.477589 -290.023522) (xy 94.335161 -290.150323) (xy 94.187513 -290.271006) (xy 94.03491 -290.385358)
			(xy 93.877622 -290.493174) (xy 93.715928 -290.594265) (xy 93.550116 -290.688449) (xy 93.380481 -290.775559)
			(xy 93.207325 -290.85544) (xy 93.030955 -290.927951) (xy 92.851685 -290.992962) (xy 92.669834 -291.050358)
			(xy 92.485725 -291.100037) (xy 92.299685 -291.14191) (xy 92.112046 -291.175903) (xy 91.92314 -291.201956)
			(xy 91.733304 -291.220022) (xy 91.542875 -291.230069) (xy 91.352192 -291.232079) (xy 91.161593 -291.226049)
			(xy 90.971419 -291.21199) (xy 90.782006 -291.189925) (xy 90.593691 -291.159896) (xy 90.40681 -291.121954)
			(xy 90.221694 -291.076168) (xy 90.038674 -291.022619) (xy 89.858073 -290.961401) (xy 89.680214 -290.892625)
			(xy 89.505412 -290.816412) (xy 89.333978 -290.732898) (xy 89.166218 -290.642231) (xy 89.002429 -290.544572)
			(xy 88.842902 -290.440095) (xy 88.687921 -290.328986) (xy 88.537763 -290.211443) (xy 88.392693 -290.087673)
			(xy 88.252969 -289.957898) (xy 88.118841 -289.822349) (xy 87.990547 -289.681265) (xy 87.868313 -289.534898)
			(xy 87.752359 -289.383509) (xy 87.64289 -289.227366) (xy 87.540101 -289.066747) (xy 87.444175 -288.901937)
			(xy 87.355281 -288.73323) (xy 87.273579 -288.560925) (xy 87.199213 -288.38533) (xy 87.132315 -288.206755)
			(xy 87.073005 -288.025519) (xy 87.021388 -287.841944) (xy 86.977556 -287.656356) (xy 86.941587 -287.469086)
			(xy 86.913544 -287.280465) (xy 86.893478 -287.09083) (xy 86.881424 -286.900517) (xy 86.877404 -286.709866)
			(xy 85.504528 -286.709866) (xy 85.504528 -291.027358) (xy 92.371672 -297.894502) (xy 92.371672 -306.725574)
			(xy 84.15782 -314.939426) (xy 84.15782 -315.996828) (xy 84.158367 -316.013473) (xy 84.166989 -316.045627)
			(xy 84.18364 -316.074454) (xy 84.207184 -316.097989) (xy 84.236018 -316.114629) (xy 84.268175 -316.12324)
			(xy 84.28482 -316.123828) (xy 84.585048 -316.123828) (xy 94.049088 -306.659788) (xy 94.049088 -306.21351)
			(xy 94.033086 -306.184808) (xy 94.020168 -306.160467) (xy 94.000699 -306.108918) (xy 93.98885 -306.055103)
			(xy 93.984869 -306.000144) (xy 93.988838 -305.945183) (xy 94.000674 -305.891366) (xy 94.020131 -305.839812)
			(xy 94.033086 -305.815492) (xy 94.049088 -305.78679) (xy 94.049088 -292.77945) (xy 98.481896 -288.346388)
			(xy 98.481896 -274.320254) (xy 94.354396 -270.1925) (xy 71.981314 -270.1925) (xy 70.815454 -269.02664)
			(xy 36.604194 -269.02664) (xy 36.581722 -269.028544) (xy 36.537922 -269.039273) (xy 36.4967 -269.057555)
			(xy 36.459347 -269.082819) (xy 36.427032 -269.114273) (xy 36.40077 -269.150931) (xy 36.381381 -269.191645)
			(xy 36.369474 -269.235139) (xy 36.365422 -269.280051) (xy 36.369351 -269.324974) (xy 36.381139 -269.368501)
			(xy 36.390326 -269.389098) (xy 36.408215 -269.428191) (xy 36.437609 -269.508988) (xy 36.459504 -269.59213)
			(xy 36.473718 -269.676925) (xy 36.480132 -269.762663) (xy 36.478693 -269.848628) (xy 36.469412 -269.934103)
			(xy 36.452367 -270.018374) (xy 36.4277 -270.100737) (xy 36.395617 -270.180505) (xy 36.356387 -270.25701)
			(xy 36.310337 -270.329615) (xy 36.25785 -270.397713) (xy 36.199367 -270.460735) (xy 36.135374 -270.518156)
			(xy 36.066407 -270.569494) (xy 35.993041 -270.614323) (xy 35.91589 -270.652267) (xy 35.835596 -270.68301)
			(xy 35.752832 -270.706294) (xy 35.668287 -270.721926) (xy 35.582669 -270.729774) (xy 35.496691 -270.729774)
			(xy 35.411073 -270.721926) (xy 35.326528 -270.706294) (xy 35.243764 -270.68301) (xy 35.16347 -270.652267)
			(xy 35.086319 -270.614323) (xy 35.012953 -270.569494) (xy 34.943986 -270.518156) (xy 34.879993 -270.460735)
			(xy 34.82151 -270.397713) (xy 34.769023 -270.329615) (xy 34.722973 -270.25701) (xy 34.683743 -270.180505)
			(xy 34.65166 -270.100737) (xy 34.626993 -270.018374) (xy 34.609948 -269.934103) (xy 34.600667 -269.848628)
			(xy 34.599228 -269.762663) (xy 34.605642 -269.676925) (xy 34.619856 -269.59213) (xy 34.641751 -269.508988)
			(xy 34.671145 -269.428191) (xy 34.689034 -269.389098) (xy 34.698235 -269.368507) (xy 34.710025 -269.32498)
			(xy 34.713956 -269.280055) (xy 34.709904 -269.235142) (xy 34.697996 -269.191647) (xy 34.678605 -269.150932)
			(xy 34.65234 -269.114275) (xy 34.620022 -269.082823) (xy 34.582666 -269.057562) (xy 34.54144 -269.039284)
			(xy 34.497638 -269.028561) (xy 34.475166 -269.02664) (xy 31.524194 -269.02664) (xy 31.501722 -269.028544)
			(xy 31.457922 -269.039273) (xy 31.4167 -269.057555) (xy 31.379347 -269.082819) (xy 31.347032 -269.114273)
			(xy 31.32077 -269.150931) (xy 31.301381 -269.191645) (xy 31.289474 -269.235139) (xy 31.285422 -269.280051)
			(xy 31.289351 -269.324974) (xy 31.301139 -269.368501) (xy 31.310326 -269.389098) (xy 31.328215 -269.428191)
			(xy 31.357609 -269.508988) (xy 31.379504 -269.59213) (xy 31.393718 -269.676925) (xy 31.400132 -269.762663)
			(xy 31.398693 -269.848628) (xy 31.389412 -269.934103) (xy 31.372367 -270.018374) (xy 31.3477 -270.100737)
			(xy 31.315617 -270.180505) (xy 31.276387 -270.25701) (xy 31.230337 -270.329615) (xy 31.17785 -270.397713)
			(xy 31.119367 -270.460735) (xy 31.055374 -270.518156) (xy 30.986407 -270.569494) (xy 30.913041 -270.614323)
			(xy 30.83589 -270.652267) (xy 30.755596 -270.68301) (xy 30.672832 -270.706294) (xy 30.588287 -270.721926)
			(xy 30.502669 -270.729774) (xy 30.416691 -270.729774) (xy 30.331073 -270.721926) (xy 30.246528 -270.706294)
			(xy 30.163764 -270.68301) (xy 30.08347 -270.652267) (xy 30.006319 -270.614323) (xy 29.932953 -270.569494)
			(xy 29.863986 -270.518156) (xy 29.799993 -270.460735) (xy 29.74151 -270.397713) (xy 29.689023 -270.329615)
			(xy 29.642973 -270.25701) (xy 29.603743 -270.180505) (xy 29.57166 -270.100737) (xy 29.546993 -270.018374)
			(xy 29.529948 -269.934103) (xy 29.520667 -269.848628) (xy 29.519228 -269.762663) (xy 29.525642 -269.676925)
			(xy 29.539856 -269.59213) (xy 29.561751 -269.508988) (xy 29.591145 -269.428191) (xy 29.609034 -269.389098)
			(xy 29.618235 -269.368507) (xy 29.630025 -269.32498) (xy 29.633956 -269.280055) (xy 29.629904 -269.235142)
			(xy 29.617996 -269.191647) (xy 29.598605 -269.150932) (xy 29.57234 -269.114275) (xy 29.540022 -269.082823)
			(xy 29.502666 -269.057562) (xy 29.46144 -269.039284) (xy 29.417638 -269.028561) (xy 29.395166 -269.02664)
			(xy 21.6408 -269.02664) (xy 21.617584 -269.028647) (xy 21.572406 -269.040036) (xy 21.530057 -269.059464)
			(xy 21.491956 -269.086281) (xy 21.459376 -269.11959) (xy 21.433409 -269.158275) (xy 21.414923 -269.201043)
			(xy 21.404536 -269.246463) (xy 21.403056 -269.269718) (xy 21.401338 -269.297429) (xy 21.390888 -269.351955)
			(xy 21.372647 -269.404392) (xy 21.347 -269.453632) (xy 21.314489 -269.498636) (xy 21.2758 -269.538454)
			(xy 21.23175 -269.572246) (xy 21.183268 -269.599298) (xy 21.131377 -269.61904) (xy 21.077174 -269.631054)
			(xy 21.021802 -269.635087) (xy 20.96643 -269.631054) (xy 20.912227 -269.61904) (xy 20.860336 -269.599298)
			(xy 20.811854 -269.572246) (xy 20.767804 -269.538454) (xy 20.729115 -269.498636) (xy 20.696604 -269.453632)
			(xy 20.670957 -269.404392) (xy 20.652716 -269.351955) (xy 20.642266 -269.297429) (xy 20.640548 -269.269718)
			(xy 20.639048 -269.246468) (xy 20.628649 -269.201057) (xy 20.610158 -269.158298) (xy 20.584191 -269.119621)
			(xy 20.551616 -269.086317) (xy 20.513523 -269.0595) (xy 20.471184 -269.040066) (xy 20.426015 -269.028665)
			(xy 20.402804 -269.02664) (xy 19.090132 -269.02664) (xy 19.075124 -269.028271) (xy 19.046446 -269.037673)
			(xy 19.020774 -269.053541) (xy 19.009868 -269.063978) (xy 15.733014 -272.340832) (xy 26.850592 -272.340832)
			(xy 26.854663 -272.28521) (xy 26.866789 -272.230773) (xy 26.886712 -272.178682) (xy 26.914008 -272.130047)
			(xy 26.948094 -272.085904) (xy 26.988243 -272.047195) (xy 27.033601 -272.014744) (xy 27.083201 -271.989243)
			(xy 27.135985 -271.971236) (xy 27.190828 -271.961106) (xy 27.246562 -271.959069) (xy 27.301999 -271.965169)
			(xy 27.355956 -271.979275) (xy 27.407285 -272.001087) (xy 27.454891 -272.030141) (xy 27.497759 -272.065816)
			(xy 27.534976 -272.107353) (xy 27.565749 -272.153866) (xy 27.589421 -272.204363) (xy 27.605489 -272.25777)
			(xy 27.613609 -272.312946) (xy 27.614118 -272.340832) (xy 27.613609 -272.368718) (xy 27.612926 -272.37336)
			(xy 29.519874 -272.37336) (xy 29.519874 -272.28646) (xy 29.527892 -272.199931) (xy 29.54386 -272.114511)
			(xy 29.567641 -272.030929) (xy 29.599033 -271.949897) (xy 29.637767 -271.872108) (xy 29.683514 -271.798224)
			(xy 29.735883 -271.728877) (xy 29.794427 -271.664657) (xy 29.858647 -271.606113) (xy 29.927994 -271.553744)
			(xy 30.001878 -271.507997) (xy 30.079667 -271.469263) (xy 30.160699 -271.437871) (xy 30.244281 -271.41409)
			(xy 30.329701 -271.398122) (xy 30.41623 -271.390104) (xy 30.50313 -271.390104) (xy 30.589659 -271.398122)
			(xy 30.675079 -271.41409) (xy 30.758661 -271.437871) (xy 30.839693 -271.469263) (xy 30.917482 -271.507997)
			(xy 30.991366 -271.553744) (xy 31.060713 -271.606113) (xy 31.124933 -271.664657) (xy 31.183477 -271.728877)
			(xy 31.235846 -271.798224) (xy 31.281593 -271.872108) (xy 31.320327 -271.949897) (xy 31.351719 -272.030929)
			(xy 31.3755 -272.114511) (xy 31.391468 -272.199931) (xy 31.399486 -272.28646) (xy 31.399988 -272.32991)
			(xy 31.399486 -272.37336) (xy 34.599874 -272.37336) (xy 34.599874 -272.28646) (xy 34.607892 -272.199931)
			(xy 34.62386 -272.114511) (xy 34.647641 -272.030929) (xy 34.679033 -271.949897) (xy 34.717767 -271.872108)
			(xy 34.763514 -271.798224) (xy 34.815883 -271.728877) (xy 34.874427 -271.664657) (xy 34.938647 -271.606113)
			(xy 35.007994 -271.553744) (xy 35.081878 -271.507997) (xy 35.159667 -271.469263) (xy 35.240699 -271.437871)
			(xy 35.324281 -271.41409) (xy 35.409701 -271.398122) (xy 35.49623 -271.390104) (xy 35.58313 -271.390104)
			(xy 35.669659 -271.398122) (xy 35.755079 -271.41409) (xy 35.838661 -271.437871) (xy 35.919693 -271.469263)
			(xy 35.997482 -271.507997) (xy 36.071366 -271.553744) (xy 36.140713 -271.606113) (xy 36.204933 -271.664657)
			(xy 36.263477 -271.728877) (xy 36.315846 -271.798224) (xy 36.361593 -271.872108) (xy 36.400327 -271.949897)
			(xy 36.431719 -272.030929) (xy 36.4555 -272.114511) (xy 36.471468 -272.199931) (xy 36.479486 -272.28646)
			(xy 36.479988 -272.32991) (xy 36.479486 -272.37336) (xy 36.471468 -272.459889) (xy 36.4555 -272.545309)
			(xy 36.431719 -272.628891) (xy 36.400327 -272.709923) (xy 36.361593 -272.787712) (xy 36.315846 -272.861596)
			(xy 36.263477 -272.930943) (xy 36.204933 -272.995163) (xy 36.140713 -273.053707) (xy 36.071366 -273.106076)
			(xy 35.997482 -273.151823) (xy 35.919693 -273.190557) (xy 35.838661 -273.221949) (xy 35.755079 -273.24573)
			(xy 35.669659 -273.261698) (xy 35.58313 -273.269716) (xy 35.49623 -273.269716) (xy 35.409701 -273.261698)
			(xy 35.324281 -273.24573) (xy 35.240699 -273.221949) (xy 35.159667 -273.190557) (xy 35.081878 -273.151823)
			(xy 35.007994 -273.106076) (xy 34.938647 -273.053707) (xy 34.874427 -272.995163) (xy 34.815883 -272.930943)
			(xy 34.763514 -272.861596) (xy 34.717767 -272.787712) (xy 34.679033 -272.709923) (xy 34.647641 -272.628891)
			(xy 34.62386 -272.545309) (xy 34.607892 -272.459889) (xy 34.599874 -272.37336) (xy 31.399486 -272.37336)
			(xy 31.391468 -272.459889) (xy 31.3755 -272.545309) (xy 31.351719 -272.628891) (xy 31.320327 -272.709923)
			(xy 31.281593 -272.787712) (xy 31.235846 -272.861596) (xy 31.183477 -272.930943) (xy 31.124933 -272.995163)
			(xy 31.060713 -273.053707) (xy 30.991366 -273.106076) (xy 30.917482 -273.151823) (xy 30.839693 -273.190557)
			(xy 30.758661 -273.221949) (xy 30.675079 -273.24573) (xy 30.589659 -273.261698) (xy 30.50313 -273.269716)
			(xy 30.41623 -273.269716) (xy 30.329701 -273.261698) (xy 30.244281 -273.24573) (xy 30.160699 -273.221949)
			(xy 30.079667 -273.190557) (xy 30.001878 -273.151823) (xy 29.927994 -273.106076) (xy 29.858647 -273.053707)
			(xy 29.794427 -272.995163) (xy 29.735883 -272.930943) (xy 29.683514 -272.861596) (xy 29.637767 -272.787712)
			(xy 29.599033 -272.709923) (xy 29.567641 -272.628891) (xy 29.54386 -272.545309) (xy 29.527892 -272.459889)
			(xy 29.519874 -272.37336) (xy 27.612926 -272.37336) (xy 27.605489 -272.423894) (xy 27.589421 -272.477301)
			(xy 27.565749 -272.527798) (xy 27.534976 -272.574311) (xy 27.497759 -272.615848) (xy 27.454891 -272.651523)
			(xy 27.407285 -272.680577) (xy 27.355956 -272.702389) (xy 27.301999 -272.716495) (xy 27.246562 -272.722595)
			(xy 27.190828 -272.720558) (xy 27.135985 -272.710428) (xy 27.083201 -272.692421) (xy 27.033601 -272.66692)
			(xy 26.988243 -272.634469) (xy 26.948094 -272.59576) (xy 26.914008 -272.551617) (xy 26.886712 -272.502982)
			(xy 26.866789 -272.450891) (xy 26.854663 -272.396454) (xy 26.850592 -272.340832) (xy 15.733014 -272.340832)
			(xy 14.463776 -273.61007) (xy 39.818564 -273.61007) (xy 39.819058 -273.552661) (xy 39.826902 -273.438113)
			(xy 39.842544 -273.324366) (xy 39.865911 -273.211952) (xy 39.896896 -273.101394) (xy 39.935352 -272.993209)
			(xy 39.981101 -272.8879) (xy 40.03393 -272.785958) (xy 40.093592 -272.687859) (xy 40.159809 -272.59406)
			(xy 40.232272 -272.504998) (xy 40.310645 -272.421089) (xy 40.39456 -272.342723) (xy 40.483627 -272.270266)
			(xy 40.577431 -272.204056) (xy 40.675535 -272.144402) (xy 40.777481 -272.091581) (xy 40.882793 -272.045839)
			(xy 40.990981 -272.007391) (xy 41.101541 -271.976415) (xy 41.213957 -271.953056) (xy 41.327705 -271.937423)
			(xy 41.442254 -271.929588) (xy 41.557072 -271.929588) (xy 41.671621 -271.937423) (xy 41.785369 -271.953056)
			(xy 41.897785 -271.976415) (xy 42.008345 -272.007391) (xy 42.116533 -272.045839) (xy 42.221845 -272.091581)
			(xy 42.323791 -272.144402) (xy 42.421895 -272.204056) (xy 42.501239 -272.26006) (xy 63.647577 -272.26006)
			(xy 63.651612 -272.184356) (xy 63.663671 -272.109511) (xy 63.683617 -272.03637) (xy 63.711224 -271.965765)
			(xy 63.74618 -271.898494) (xy 63.788088 -271.835319) (xy 63.836474 -271.776957) (xy 63.89079 -271.724069)
			(xy 63.950419 -271.677254) (xy 64.014687 -271.637042) (xy 64.082864 -271.60389) (xy 64.15418 -271.578172)
			(xy 64.227825 -271.56018) (xy 64.302965 -271.550118) (xy 64.378749 -271.548099) (xy 64.454319 -271.554148)
			(xy 64.528817 -271.568195) (xy 64.6014 -271.590081) (xy 64.671246 -271.619558) (xy 64.737563 -271.656293)
			(xy 64.799599 -271.699868) (xy 64.856652 -271.74979) (xy 64.908076 -271.805494) (xy 64.953287 -271.866349)
			(xy 64.991774 -271.931664) (xy 65.0231 -272.0007) (xy 65.04691 -272.072675) (xy 65.062935 -272.146773)
			(xy 65.070994 -272.222154) (xy 65.071498 -272.26006) (xy 66.187577 -272.26006) (xy 66.191612 -272.184356)
			(xy 66.203671 -272.109511) (xy 66.223617 -272.03637) (xy 66.251224 -271.965765) (xy 66.28618 -271.898494)
			(xy 66.328088 -271.835319) (xy 66.376474 -271.776957) (xy 66.43079 -271.724069) (xy 66.490419 -271.677254)
			(xy 66.554687 -271.637042) (xy 66.622864 -271.60389) (xy 66.69418 -271.578172) (xy 66.767825 -271.56018)
			(xy 66.842965 -271.550118) (xy 66.918749 -271.548099) (xy 66.994319 -271.554148) (xy 67.068817 -271.568195)
			(xy 67.1414 -271.590081) (xy 67.211246 -271.619558) (xy 67.277563 -271.656293) (xy 67.339599 -271.699868)
			(xy 67.396652 -271.74979) (xy 67.448076 -271.805494) (xy 67.493287 -271.866349) (xy 67.531774 -271.931664)
			(xy 67.5631 -272.0007) (xy 67.58691 -272.072675) (xy 67.602935 -272.146773) (xy 67.610994 -272.222154)
			(xy 67.611498 -272.26006) (xy 68.727577 -272.26006) (xy 68.731612 -272.184356) (xy 68.743671 -272.109511)
			(xy 68.763617 -272.03637) (xy 68.791224 -271.965765) (xy 68.82618 -271.898494) (xy 68.868088 -271.835319)
			(xy 68.916474 -271.776957) (xy 68.97079 -271.724069) (xy 69.030419 -271.677254) (xy 69.094687 -271.637042)
			(xy 69.162864 -271.60389) (xy 69.23418 -271.578172) (xy 69.307825 -271.56018) (xy 69.382965 -271.550118)
			(xy 69.458749 -271.548099) (xy 69.534319 -271.554148) (xy 69.608817 -271.568195) (xy 69.6814 -271.590081)
			(xy 69.751246 -271.619558) (xy 69.817563 -271.656293) (xy 69.879599 -271.699868) (xy 69.936652 -271.74979)
			(xy 69.988076 -271.805494) (xy 70.033287 -271.866349) (xy 70.071774 -271.931664) (xy 70.1031 -272.0007)
			(xy 70.12691 -272.072675) (xy 70.142935 -272.146773) (xy 70.150994 -272.222154) (xy 70.151498 -272.26006)
			(xy 71.267577 -272.26006) (xy 71.271612 -272.184356) (xy 71.283671 -272.109511) (xy 71.303617 -272.03637)
			(xy 71.331224 -271.965765) (xy 71.36618 -271.898494) (xy 71.408088 -271.835319) (xy 71.456474 -271.776957)
			(xy 71.51079 -271.724069) (xy 71.570419 -271.677254) (xy 71.634687 -271.637042) (xy 71.702864 -271.60389)
			(xy 71.77418 -271.578172) (xy 71.847825 -271.56018) (xy 71.922965 -271.550118) (xy 71.998749 -271.548099)
			(xy 72.074319 -271.554148) (xy 72.148817 -271.568195) (xy 72.2214 -271.590081) (xy 72.291246 -271.619558)
			(xy 72.357563 -271.656293) (xy 72.419599 -271.699868) (xy 72.476652 -271.74979) (xy 72.528076 -271.805494)
			(xy 72.573287 -271.866349) (xy 72.611774 -271.931664) (xy 72.6431 -272.0007) (xy 72.66691 -272.072675)
			(xy 72.682935 -272.146773) (xy 72.690994 -272.222154) (xy 72.691498 -272.26006) (xy 73.807577 -272.26006)
			(xy 73.811612 -272.184356) (xy 73.823671 -272.109511) (xy 73.843617 -272.03637) (xy 73.871224 -271.965765)
			(xy 73.90618 -271.898494) (xy 73.948088 -271.835319) (xy 73.996474 -271.776957) (xy 74.05079 -271.724069)
			(xy 74.110419 -271.677254) (xy 74.174687 -271.637042) (xy 74.242864 -271.60389) (xy 74.31418 -271.578172)
			(xy 74.387825 -271.56018) (xy 74.462965 -271.550118) (xy 74.538749 -271.548099) (xy 74.614319 -271.554148)
			(xy 74.688817 -271.568195) (xy 74.7614 -271.590081) (xy 74.831246 -271.619558) (xy 74.897563 -271.656293)
			(xy 74.959599 -271.699868) (xy 75.016652 -271.74979) (xy 75.068076 -271.805494) (xy 75.113287 -271.866349)
			(xy 75.151774 -271.931664) (xy 75.1831 -272.0007) (xy 75.20691 -272.072675) (xy 75.222935 -272.146773)
			(xy 75.230994 -272.222154) (xy 75.231498 -272.26006) (xy 76.347577 -272.26006) (xy 76.351612 -272.184356)
			(xy 76.363671 -272.109511) (xy 76.383617 -272.03637) (xy 76.411224 -271.965765) (xy 76.44618 -271.898494)
			(xy 76.488088 -271.835319) (xy 76.536474 -271.776957) (xy 76.59079 -271.724069) (xy 76.650419 -271.677254)
			(xy 76.714687 -271.637042) (xy 76.782864 -271.60389) (xy 76.85418 -271.578172) (xy 76.927825 -271.56018)
			(xy 77.002965 -271.550118) (xy 77.078749 -271.548099) (xy 77.154319 -271.554148) (xy 77.228817 -271.568195)
			(xy 77.3014 -271.590081) (xy 77.371246 -271.619558) (xy 77.437563 -271.656293) (xy 77.499599 -271.699868)
			(xy 77.556652 -271.74979) (xy 77.608076 -271.805494) (xy 77.653287 -271.866349) (xy 77.691774 -271.931664)
			(xy 77.7231 -272.0007) (xy 77.74691 -272.072675) (xy 77.762935 -272.146773) (xy 77.770994 -272.222154)
			(xy 77.771498 -272.26006) (xy 78.887577 -272.26006) (xy 78.891612 -272.184356) (xy 78.903671 -272.109511)
			(xy 78.923617 -272.03637) (xy 78.951224 -271.965765) (xy 78.98618 -271.898494) (xy 79.028088 -271.835319)
			(xy 79.076474 -271.776957) (xy 79.13079 -271.724069) (xy 79.190419 -271.677254) (xy 79.254687 -271.637042)
			(xy 79.322864 -271.60389) (xy 79.39418 -271.578172) (xy 79.467825 -271.56018) (xy 79.542965 -271.550118)
			(xy 79.618749 -271.548099) (xy 79.694319 -271.554148) (xy 79.768817 -271.568195) (xy 79.8414 -271.590081)
			(xy 79.911246 -271.619558) (xy 79.977563 -271.656293) (xy 80.039599 -271.699868) (xy 80.096652 -271.74979)
			(xy 80.148076 -271.805494) (xy 80.193287 -271.866349) (xy 80.231774 -271.931664) (xy 80.2631 -272.0007)
			(xy 80.28691 -272.072675) (xy 80.302935 -272.146773) (xy 80.310994 -272.222154) (xy 80.311498 -272.26006)
			(xy 81.427577 -272.26006) (xy 81.431612 -272.184356) (xy 81.443671 -272.109511) (xy 81.463617 -272.03637)
			(xy 81.491224 -271.965765) (xy 81.52618 -271.898494) (xy 81.568088 -271.835319) (xy 81.616474 -271.776957)
			(xy 81.67079 -271.724069) (xy 81.730419 -271.677254) (xy 81.794687 -271.637042) (xy 81.862864 -271.60389)
			(xy 81.93418 -271.578172) (xy 82.007825 -271.56018) (xy 82.082965 -271.550118) (xy 82.158749 -271.548099)
			(xy 82.234319 -271.554148) (xy 82.308817 -271.568195) (xy 82.3814 -271.590081) (xy 82.451246 -271.619558)
			(xy 82.517563 -271.656293) (xy 82.579599 -271.699868) (xy 82.585544 -271.70507) (xy 86.197697 -271.70507)
			(xy 86.201732 -271.629366) (xy 86.213791 -271.554521) (xy 86.233737 -271.48138) (xy 86.261344 -271.410775)
			(xy 86.2963 -271.343504) (xy 86.338208 -271.280329) (xy 86.386594 -271.221967) (xy 86.44091 -271.169079)
			(xy 86.500539 -271.122264) (xy 86.564807 -271.082052) (xy 86.632984 -271.0489) (xy 86.7043 -271.023182)
			(xy 86.777945 -271.00519) (xy 86.853085 -270.995128) (xy 86.928869 -270.993109) (xy 87.004439 -270.999158)
			(xy 87.078937 -271.013205) (xy 87.15152 -271.035091) (xy 87.221366 -271.064568) (xy 87.287683 -271.101303)
			(xy 87.349719 -271.144878) (xy 87.406772 -271.1948) (xy 87.458196 -271.250504) (xy 87.503407 -271.311359)
			(xy 87.541894 -271.376674) (xy 87.57322 -271.44571) (xy 87.59703 -271.517685) (xy 87.613055 -271.591783)
			(xy 87.621114 -271.667164) (xy 87.621618 -271.70507) (xy 88.737697 -271.70507) (xy 88.741732 -271.629366)
			(xy 88.753791 -271.554521) (xy 88.773737 -271.48138) (xy 88.801344 -271.410775) (xy 88.8363 -271.343504)
			(xy 88.878208 -271.280329) (xy 88.926594 -271.221967) (xy 88.98091 -271.169079) (xy 89.040539 -271.122264)
			(xy 89.104807 -271.082052) (xy 89.172984 -271.0489) (xy 89.2443 -271.023182) (xy 89.317945 -271.00519)
			(xy 89.393085 -270.995128) (xy 89.468869 -270.993109) (xy 89.544439 -270.999158) (xy 89.618937 -271.013205)
			(xy 89.69152 -271.035091) (xy 89.761366 -271.064568) (xy 89.827683 -271.101303) (xy 89.889719 -271.144878)
			(xy 89.946772 -271.1948) (xy 89.998196 -271.250504) (xy 90.043407 -271.311359) (xy 90.081894 -271.376674)
			(xy 90.11322 -271.44571) (xy 90.13703 -271.517685) (xy 90.153055 -271.591783) (xy 90.161114 -271.667164)
			(xy 90.161618 -271.70507) (xy 91.277697 -271.70507) (xy 91.281732 -271.629366) (xy 91.293791 -271.554521)
			(xy 91.313737 -271.48138) (xy 91.341344 -271.410775) (xy 91.3763 -271.343504) (xy 91.418208 -271.280329)
			(xy 91.466594 -271.221967) (xy 91.52091 -271.169079) (xy 91.580539 -271.122264) (xy 91.644807 -271.082052)
			(xy 91.712984 -271.0489) (xy 91.7843 -271.023182) (xy 91.857945 -271.00519) (xy 91.933085 -270.995128)
			(xy 92.008869 -270.993109) (xy 92.084439 -270.999158) (xy 92.158937 -271.013205) (xy 92.23152 -271.035091)
			(xy 92.301366 -271.064568) (xy 92.367683 -271.101303) (xy 92.429719 -271.144878) (xy 92.486772 -271.1948)
			(xy 92.538196 -271.250504) (xy 92.583407 -271.311359) (xy 92.621894 -271.376674) (xy 92.65322 -271.44571)
			(xy 92.67703 -271.517685) (xy 92.693055 -271.591783) (xy 92.701114 -271.667164) (xy 92.701618 -271.70507)
			(xy 92.701114 -271.742976) (xy 92.693055 -271.818357) (xy 92.67703 -271.892455) (xy 92.65322 -271.96443)
			(xy 92.621894 -272.033466) (xy 92.583407 -272.098781) (xy 92.538196 -272.159636) (xy 92.486772 -272.21534)
			(xy 92.429719 -272.265262) (xy 92.367683 -272.308837) (xy 92.301366 -272.345572) (xy 92.23152 -272.375049)
			(xy 92.158937 -272.396935) (xy 92.084439 -272.410982) (xy 92.008869 -272.417031) (xy 91.933085 -272.415012)
			(xy 91.857945 -272.40495) (xy 91.7843 -272.386958) (xy 91.712984 -272.36124) (xy 91.644807 -272.328088)
			(xy 91.580539 -272.287876) (xy 91.52091 -272.241061) (xy 91.466594 -272.188173) (xy 91.418208 -272.129811)
			(xy 91.3763 -272.066636) (xy 91.341344 -271.999365) (xy 91.313737 -271.92876) (xy 91.293791 -271.855619)
			(xy 91.281732 -271.780774) (xy 91.277697 -271.70507) (xy 90.161618 -271.70507) (xy 90.161114 -271.742976)
			(xy 90.153055 -271.818357) (xy 90.13703 -271.892455) (xy 90.11322 -271.96443) (xy 90.081894 -272.033466)
			(xy 90.043407 -272.098781) (xy 89.998196 -272.159636) (xy 89.946772 -272.21534) (xy 89.889719 -272.265262)
			(xy 89.827683 -272.308837) (xy 89.761366 -272.345572) (xy 89.69152 -272.375049) (xy 89.618937 -272.396935)
			(xy 89.544439 -272.410982) (xy 89.468869 -272.417031) (xy 89.393085 -272.415012) (xy 89.317945 -272.40495)
			(xy 89.2443 -272.386958) (xy 89.172984 -272.36124) (xy 89.104807 -272.328088) (xy 89.040539 -272.287876)
			(xy 88.98091 -272.241061) (xy 88.926594 -272.188173) (xy 88.878208 -272.129811) (xy 88.8363 -272.066636)
			(xy 88.801344 -271.999365) (xy 88.773737 -271.92876) (xy 88.753791 -271.855619) (xy 88.741732 -271.780774)
			(xy 88.737697 -271.70507) (xy 87.621618 -271.70507) (xy 87.621114 -271.742976) (xy 87.613055 -271.818357)
			(xy 87.59703 -271.892455) (xy 87.57322 -271.96443) (xy 87.541894 -272.033466) (xy 87.503407 -272.098781)
			(xy 87.458196 -272.159636) (xy 87.406772 -272.21534) (xy 87.349719 -272.265262) (xy 87.287683 -272.308837)
			(xy 87.221366 -272.345572) (xy 87.15152 -272.375049) (xy 87.078937 -272.396935) (xy 87.004439 -272.410982)
			(xy 86.928869 -272.417031) (xy 86.853085 -272.415012) (xy 86.777945 -272.40495) (xy 86.7043 -272.386958)
			(xy 86.632984 -272.36124) (xy 86.564807 -272.328088) (xy 86.500539 -272.287876) (xy 86.44091 -272.241061)
			(xy 86.386594 -272.188173) (xy 86.338208 -272.129811) (xy 86.2963 -272.066636) (xy 86.261344 -271.999365)
			(xy 86.233737 -271.92876) (xy 86.213791 -271.855619) (xy 86.201732 -271.780774) (xy 86.197697 -271.70507)
			(xy 82.585544 -271.70507) (xy 82.636652 -271.74979) (xy 82.688076 -271.805494) (xy 82.733287 -271.866349)
			(xy 82.771774 -271.931664) (xy 82.8031 -272.0007) (xy 82.82691 -272.072675) (xy 82.842935 -272.146773)
			(xy 82.850994 -272.222154) (xy 82.851498 -272.26006) (xy 82.850994 -272.297966) (xy 82.842935 -272.373347)
			(xy 82.82691 -272.447445) (xy 82.8031 -272.51942) (xy 82.771774 -272.588456) (xy 82.733287 -272.653771)
			(xy 82.688076 -272.714626) (xy 82.636652 -272.77033) (xy 82.579599 -272.820252) (xy 82.517563 -272.863827)
			(xy 82.451246 -272.900562) (xy 82.3814 -272.930039) (xy 82.308817 -272.951925) (xy 82.234319 -272.965972)
			(xy 82.158749 -272.972021) (xy 82.082965 -272.970002) (xy 82.007825 -272.95994) (xy 81.93418 -272.941948)
			(xy 81.862864 -272.91623) (xy 81.794687 -272.883078) (xy 81.730419 -272.842866) (xy 81.67079 -272.796051)
			(xy 81.616474 -272.743163) (xy 81.568088 -272.684801) (xy 81.52618 -272.621626) (xy 81.491224 -272.554355)
			(xy 81.463617 -272.48375) (xy 81.443671 -272.410609) (xy 81.431612 -272.335764) (xy 81.427577 -272.26006)
			(xy 80.311498 -272.26006) (xy 80.310994 -272.297966) (xy 80.302935 -272.373347) (xy 80.28691 -272.447445)
			(xy 80.2631 -272.51942) (xy 80.231774 -272.588456) (xy 80.193287 -272.653771) (xy 80.148076 -272.714626)
			(xy 80.096652 -272.77033) (xy 80.039599 -272.820252) (xy 79.977563 -272.863827) (xy 79.911246 -272.900562)
			(xy 79.8414 -272.930039) (xy 79.768817 -272.951925) (xy 79.694319 -272.965972) (xy 79.618749 -272.972021)
			(xy 79.542965 -272.970002) (xy 79.467825 -272.95994) (xy 79.39418 -272.941948) (xy 79.322864 -272.91623)
			(xy 79.254687 -272.883078) (xy 79.190419 -272.842866) (xy 79.13079 -272.796051) (xy 79.076474 -272.743163)
			(xy 79.028088 -272.684801) (xy 78.98618 -272.621626) (xy 78.951224 -272.554355) (xy 78.923617 -272.48375)
			(xy 78.903671 -272.410609) (xy 78.891612 -272.335764) (xy 78.887577 -272.26006) (xy 77.771498 -272.26006)
			(xy 77.770994 -272.297966) (xy 77.762935 -272.373347) (xy 77.74691 -272.447445) (xy 77.7231 -272.51942)
			(xy 77.691774 -272.588456) (xy 77.653287 -272.653771) (xy 77.608076 -272.714626) (xy 77.556652 -272.77033)
			(xy 77.499599 -272.820252) (xy 77.437563 -272.863827) (xy 77.371246 -272.900562) (xy 77.3014 -272.930039)
			(xy 77.228817 -272.951925) (xy 77.154319 -272.965972) (xy 77.078749 -272.972021) (xy 77.002965 -272.970002)
			(xy 76.927825 -272.95994) (xy 76.85418 -272.941948) (xy 76.782864 -272.91623) (xy 76.714687 -272.883078)
			(xy 76.650419 -272.842866) (xy 76.59079 -272.796051) (xy 76.536474 -272.743163) (xy 76.488088 -272.684801)
			(xy 76.44618 -272.621626) (xy 76.411224 -272.554355) (xy 76.383617 -272.48375) (xy 76.363671 -272.410609)
			(xy 76.351612 -272.335764) (xy 76.347577 -272.26006) (xy 75.231498 -272.26006) (xy 75.230994 -272.297966)
			(xy 75.222935 -272.373347) (xy 75.20691 -272.447445) (xy 75.1831 -272.51942) (xy 75.151774 -272.588456)
			(xy 75.113287 -272.653771) (xy 75.068076 -272.714626) (xy 75.016652 -272.77033) (xy 74.959599 -272.820252)
			(xy 74.897563 -272.863827) (xy 74.831246 -272.900562) (xy 74.7614 -272.930039) (xy 74.688817 -272.951925)
			(xy 74.614319 -272.965972) (xy 74.538749 -272.972021) (xy 74.462965 -272.970002) (xy 74.387825 -272.95994)
			(xy 74.31418 -272.941948) (xy 74.242864 -272.91623) (xy 74.174687 -272.883078) (xy 74.110419 -272.842866)
			(xy 74.05079 -272.796051) (xy 73.996474 -272.743163) (xy 73.948088 -272.684801) (xy 73.90618 -272.621626)
			(xy 73.871224 -272.554355) (xy 73.843617 -272.48375) (xy 73.823671 -272.410609) (xy 73.811612 -272.335764)
			(xy 73.807577 -272.26006) (xy 72.691498 -272.26006) (xy 72.690994 -272.297966) (xy 72.682935 -272.373347)
			(xy 72.66691 -272.447445) (xy 72.6431 -272.51942) (xy 72.611774 -272.588456) (xy 72.573287 -272.653771)
			(xy 72.528076 -272.714626) (xy 72.476652 -272.77033) (xy 72.419599 -272.820252) (xy 72.357563 -272.863827)
			(xy 72.291246 -272.900562) (xy 72.2214 -272.930039) (xy 72.148817 -272.951925) (xy 72.074319 -272.965972)
			(xy 71.998749 -272.972021) (xy 71.922965 -272.970002) (xy 71.847825 -272.95994) (xy 71.77418 -272.941948)
			(xy 71.702864 -272.91623) (xy 71.634687 -272.883078) (xy 71.570419 -272.842866) (xy 71.51079 -272.796051)
			(xy 71.456474 -272.743163) (xy 71.408088 -272.684801) (xy 71.36618 -272.621626) (xy 71.331224 -272.554355)
			(xy 71.303617 -272.48375) (xy 71.283671 -272.410609) (xy 71.271612 -272.335764) (xy 71.267577 -272.26006)
			(xy 70.151498 -272.26006) (xy 70.150994 -272.297966) (xy 70.142935 -272.373347) (xy 70.12691 -272.447445)
			(xy 70.1031 -272.51942) (xy 70.071774 -272.588456) (xy 70.033287 -272.653771) (xy 69.988076 -272.714626)
			(xy 69.936652 -272.77033) (xy 69.879599 -272.820252) (xy 69.817563 -272.863827) (xy 69.751246 -272.900562)
			(xy 69.6814 -272.930039) (xy 69.608817 -272.951925) (xy 69.534319 -272.965972) (xy 69.458749 -272.972021)
			(xy 69.382965 -272.970002) (xy 69.307825 -272.95994) (xy 69.23418 -272.941948) (xy 69.162864 -272.91623)
			(xy 69.094687 -272.883078) (xy 69.030419 -272.842866) (xy 68.97079 -272.796051) (xy 68.916474 -272.743163)
			(xy 68.868088 -272.684801) (xy 68.82618 -272.621626) (xy 68.791224 -272.554355) (xy 68.763617 -272.48375)
			(xy 68.743671 -272.410609) (xy 68.731612 -272.335764) (xy 68.727577 -272.26006) (xy 67.611498 -272.26006)
			(xy 67.610994 -272.297966) (xy 67.602935 -272.373347) (xy 67.58691 -272.447445) (xy 67.5631 -272.51942)
			(xy 67.531774 -272.588456) (xy 67.493287 -272.653771) (xy 67.448076 -272.714626) (xy 67.396652 -272.77033)
			(xy 67.339599 -272.820252) (xy 67.277563 -272.863827) (xy 67.211246 -272.900562) (xy 67.1414 -272.930039)
			(xy 67.068817 -272.951925) (xy 66.994319 -272.965972) (xy 66.918749 -272.972021) (xy 66.842965 -272.970002)
			(xy 66.767825 -272.95994) (xy 66.69418 -272.941948) (xy 66.622864 -272.91623) (xy 66.554687 -272.883078)
			(xy 66.490419 -272.842866) (xy 66.43079 -272.796051) (xy 66.376474 -272.743163) (xy 66.328088 -272.684801)
			(xy 66.28618 -272.621626) (xy 66.251224 -272.554355) (xy 66.223617 -272.48375) (xy 66.203671 -272.410609)
			(xy 66.191612 -272.335764) (xy 66.187577 -272.26006) (xy 65.071498 -272.26006) (xy 65.070994 -272.297966)
			(xy 65.062935 -272.373347) (xy 65.04691 -272.447445) (xy 65.0231 -272.51942) (xy 64.991774 -272.588456)
			(xy 64.953287 -272.653771) (xy 64.908076 -272.714626) (xy 64.856652 -272.77033) (xy 64.799599 -272.820252)
			(xy 64.737563 -272.863827) (xy 64.671246 -272.900562) (xy 64.6014 -272.930039) (xy 64.528817 -272.951925)
			(xy 64.454319 -272.965972) (xy 64.378749 -272.972021) (xy 64.302965 -272.970002) (xy 64.227825 -272.95994)
			(xy 64.15418 -272.941948) (xy 64.082864 -272.91623) (xy 64.014687 -272.883078) (xy 63.950419 -272.842866)
			(xy 63.89079 -272.796051) (xy 63.836474 -272.743163) (xy 63.788088 -272.684801) (xy 63.74618 -272.621626)
			(xy 63.711224 -272.554355) (xy 63.683617 -272.48375) (xy 63.663671 -272.410609) (xy 63.651612 -272.335764)
			(xy 63.647577 -272.26006) (xy 42.501239 -272.26006) (xy 42.515699 -272.270266) (xy 42.604766 -272.342723)
			(xy 42.688681 -272.421089) (xy 42.767054 -272.504998) (xy 42.839517 -272.59406) (xy 42.905734 -272.687859)
			(xy 42.965396 -272.785958) (xy 43.018225 -272.8879) (xy 43.056094 -272.97507) (xy 84.927697 -272.97507)
			(xy 84.931732 -272.899366) (xy 84.943791 -272.824521) (xy 84.963737 -272.75138) (xy 84.991344 -272.680775)
			(xy 85.0263 -272.613504) (xy 85.068208 -272.550329) (xy 85.116594 -272.491967) (xy 85.17091 -272.439079)
			(xy 85.230539 -272.392264) (xy 85.294807 -272.352052) (xy 85.362984 -272.3189) (xy 85.4343 -272.293182)
			(xy 85.507945 -272.27519) (xy 85.583085 -272.265128) (xy 85.658869 -272.263109) (xy 85.734439 -272.269158)
			(xy 85.808937 -272.283205) (xy 85.88152 -272.305091) (xy 85.951366 -272.334568) (xy 86.017683 -272.371303)
			(xy 86.079719 -272.414878) (xy 86.136772 -272.4648) (xy 86.188196 -272.520504) (xy 86.233407 -272.581359)
			(xy 86.271894 -272.646674) (xy 86.30322 -272.71571) (xy 86.32703 -272.787685) (xy 86.343055 -272.861783)
			(xy 86.351114 -272.937164) (xy 86.351618 -272.97507) (xy 86.351114 -273.012976) (xy 86.343055 -273.088357)
			(xy 86.32703 -273.162455) (xy 86.30322 -273.23443) (xy 86.271894 -273.303466) (xy 86.233407 -273.368781)
			(xy 86.188196 -273.429636) (xy 86.136772 -273.48534) (xy 86.079719 -273.535262) (xy 86.017683 -273.578837)
			(xy 85.951366 -273.615572) (xy 85.88152 -273.645049) (xy 85.808937 -273.666935) (xy 85.734439 -273.680982)
			(xy 85.658869 -273.687031) (xy 85.583085 -273.685012) (xy 85.507945 -273.67495) (xy 85.4343 -273.656958)
			(xy 85.362984 -273.63124) (xy 85.294807 -273.598088) (xy 85.230539 -273.557876) (xy 85.17091 -273.511061)
			(xy 85.116594 -273.458173) (xy 85.068208 -273.399811) (xy 85.0263 -273.336636) (xy 84.991344 -273.269365)
			(xy 84.963737 -273.19876) (xy 84.943791 -273.125619) (xy 84.931732 -273.050774) (xy 84.927697 -272.97507)
			(xy 43.056094 -272.97507) (xy 43.063974 -272.993209) (xy 43.10243 -273.101394) (xy 43.133415 -273.211952)
			(xy 43.156782 -273.324366) (xy 43.172424 -273.438113) (xy 43.180268 -273.552661) (xy 43.180762 -273.61007)
			(xy 43.180576 -273.643253) (xy 43.177909 -273.709567) (xy 43.175428 -273.742658) (xy 43.170272 -273.800942)
			(xy 43.152948 -273.916671) (xy 43.127616 -274.030914) (xy 43.094401 -274.143119) (xy 43.053462 -274.252742)
			(xy 43.004999 -274.359253) (xy 42.949245 -274.462135) (xy 42.886471 -274.560891) (xy 42.816981 -274.655042)
			(xy 42.741111 -274.744132) (xy 42.659229 -274.827729) (xy 42.571732 -274.90543) (xy 42.500813 -274.96008)
			(xy 63.647577 -274.96008) (xy 63.651612 -274.884376) (xy 63.663671 -274.809531) (xy 63.683617 -274.73639)
			(xy 63.711224 -274.665785) (xy 63.74618 -274.598514) (xy 63.788088 -274.535339) (xy 63.836474 -274.476977)
			(xy 63.89079 -274.424089) (xy 63.950419 -274.377274) (xy 64.014687 -274.337062) (xy 64.082864 -274.30391)
			(xy 64.15418 -274.278192) (xy 64.227825 -274.2602) (xy 64.302965 -274.250138) (xy 64.378749 -274.248119)
			(xy 64.454319 -274.254168) (xy 64.528817 -274.268215) (xy 64.6014 -274.290101) (xy 64.671246 -274.319578)
			(xy 64.737563 -274.356313) (xy 64.799599 -274.399888) (xy 64.856652 -274.44981) (xy 64.908076 -274.505514)
			(xy 64.953287 -274.566369) (xy 64.991774 -274.631684) (xy 65.0231 -274.70072) (xy 65.04691 -274.772695)
			(xy 65.062935 -274.846793) (xy 65.070994 -274.922174) (xy 65.071498 -274.96008) (xy 66.187577 -274.96008)
			(xy 66.191612 -274.884376) (xy 66.203671 -274.809531) (xy 66.223617 -274.73639) (xy 66.251224 -274.665785)
			(xy 66.28618 -274.598514) (xy 66.328088 -274.535339) (xy 66.376474 -274.476977) (xy 66.43079 -274.424089)
			(xy 66.490419 -274.377274) (xy 66.554687 -274.337062) (xy 66.622864 -274.30391) (xy 66.69418 -274.278192)
			(xy 66.767825 -274.2602) (xy 66.842965 -274.250138) (xy 66.918749 -274.248119) (xy 66.994319 -274.254168)
			(xy 67.068817 -274.268215) (xy 67.1414 -274.290101) (xy 67.211246 -274.319578) (xy 67.277563 -274.356313)
			(xy 67.339599 -274.399888) (xy 67.396652 -274.44981) (xy 67.448076 -274.505514) (xy 67.493287 -274.566369)
			(xy 67.531774 -274.631684) (xy 67.5631 -274.70072) (xy 67.58691 -274.772695) (xy 67.602935 -274.846793)
			(xy 67.610994 -274.922174) (xy 67.611498 -274.96008) (xy 68.727577 -274.96008) (xy 68.731612 -274.884376)
			(xy 68.743671 -274.809531) (xy 68.763617 -274.73639) (xy 68.791224 -274.665785) (xy 68.82618 -274.598514)
			(xy 68.868088 -274.535339) (xy 68.916474 -274.476977) (xy 68.97079 -274.424089) (xy 69.030419 -274.377274)
			(xy 69.094687 -274.337062) (xy 69.162864 -274.30391) (xy 69.23418 -274.278192) (xy 69.307825 -274.2602)
			(xy 69.382965 -274.250138) (xy 69.458749 -274.248119) (xy 69.534319 -274.254168) (xy 69.608817 -274.268215)
			(xy 69.6814 -274.290101) (xy 69.751246 -274.319578) (xy 69.817563 -274.356313) (xy 69.879599 -274.399888)
			(xy 69.936652 -274.44981) (xy 69.988076 -274.505514) (xy 70.033287 -274.566369) (xy 70.071774 -274.631684)
			(xy 70.1031 -274.70072) (xy 70.12691 -274.772695) (xy 70.142935 -274.846793) (xy 70.150994 -274.922174)
			(xy 70.151498 -274.96008) (xy 71.267577 -274.96008) (xy 71.271612 -274.884376) (xy 71.283671 -274.809531)
			(xy 71.303617 -274.73639) (xy 71.331224 -274.665785) (xy 71.36618 -274.598514) (xy 71.408088 -274.535339)
			(xy 71.456474 -274.476977) (xy 71.51079 -274.424089) (xy 71.570419 -274.377274) (xy 71.634687 -274.337062)
			(xy 71.702864 -274.30391) (xy 71.77418 -274.278192) (xy 71.847825 -274.2602) (xy 71.922965 -274.250138)
			(xy 71.998749 -274.248119) (xy 72.074319 -274.254168) (xy 72.148817 -274.268215) (xy 72.2214 -274.290101)
			(xy 72.291246 -274.319578) (xy 72.357563 -274.356313) (xy 72.419599 -274.399888) (xy 72.476652 -274.44981)
			(xy 72.528076 -274.505514) (xy 72.573287 -274.566369) (xy 72.611774 -274.631684) (xy 72.6431 -274.70072)
			(xy 72.66691 -274.772695) (xy 72.682935 -274.846793) (xy 72.690994 -274.922174) (xy 72.691498 -274.96008)
			(xy 73.807577 -274.96008) (xy 73.811612 -274.884376) (xy 73.823671 -274.809531) (xy 73.843617 -274.73639)
			(xy 73.871224 -274.665785) (xy 73.90618 -274.598514) (xy 73.948088 -274.535339) (xy 73.996474 -274.476977)
			(xy 74.05079 -274.424089) (xy 74.110419 -274.377274) (xy 74.174687 -274.337062) (xy 74.242864 -274.30391)
			(xy 74.31418 -274.278192) (xy 74.387825 -274.2602) (xy 74.462965 -274.250138) (xy 74.538749 -274.248119)
			(xy 74.614319 -274.254168) (xy 74.688817 -274.268215) (xy 74.7614 -274.290101) (xy 74.831246 -274.319578)
			(xy 74.897563 -274.356313) (xy 74.959599 -274.399888) (xy 75.016652 -274.44981) (xy 75.068076 -274.505514)
			(xy 75.113287 -274.566369) (xy 75.151774 -274.631684) (xy 75.1831 -274.70072) (xy 75.20691 -274.772695)
			(xy 75.222935 -274.846793) (xy 75.230994 -274.922174) (xy 75.231498 -274.96008) (xy 76.347577 -274.96008)
			(xy 76.351612 -274.884376) (xy 76.363671 -274.809531) (xy 76.383617 -274.73639) (xy 76.411224 -274.665785)
			(xy 76.44618 -274.598514) (xy 76.488088 -274.535339) (xy 76.536474 -274.476977) (xy 76.59079 -274.424089)
			(xy 76.650419 -274.377274) (xy 76.714687 -274.337062) (xy 76.782864 -274.30391) (xy 76.85418 -274.278192)
			(xy 76.927825 -274.2602) (xy 77.002965 -274.250138) (xy 77.078749 -274.248119) (xy 77.154319 -274.254168)
			(xy 77.228817 -274.268215) (xy 77.3014 -274.290101) (xy 77.371246 -274.319578) (xy 77.437563 -274.356313)
			(xy 77.499599 -274.399888) (xy 77.556652 -274.44981) (xy 77.608076 -274.505514) (xy 77.653287 -274.566369)
			(xy 77.691774 -274.631684) (xy 77.7231 -274.70072) (xy 77.74691 -274.772695) (xy 77.762935 -274.846793)
			(xy 77.770994 -274.922174) (xy 77.771498 -274.96008) (xy 78.887577 -274.96008) (xy 78.891612 -274.884376)
			(xy 78.903671 -274.809531) (xy 78.923617 -274.73639) (xy 78.951224 -274.665785) (xy 78.98618 -274.598514)
			(xy 79.028088 -274.535339) (xy 79.076474 -274.476977) (xy 79.13079 -274.424089) (xy 79.190419 -274.377274)
			(xy 79.254687 -274.337062) (xy 79.322864 -274.30391) (xy 79.39418 -274.278192) (xy 79.467825 -274.2602)
			(xy 79.542965 -274.250138) (xy 79.618749 -274.248119) (xy 79.694319 -274.254168) (xy 79.768817 -274.268215)
			(xy 79.8414 -274.290101) (xy 79.911246 -274.319578) (xy 79.977563 -274.356313) (xy 80.039599 -274.399888)
			(xy 80.096652 -274.44981) (xy 80.148076 -274.505514) (xy 80.193287 -274.566369) (xy 80.231774 -274.631684)
			(xy 80.2631 -274.70072) (xy 80.28691 -274.772695) (xy 80.302935 -274.846793) (xy 80.310994 -274.922174)
			(xy 80.311498 -274.96008) (xy 81.427577 -274.96008) (xy 81.431612 -274.884376) (xy 81.443671 -274.809531)
			(xy 81.463617 -274.73639) (xy 81.491224 -274.665785) (xy 81.52618 -274.598514) (xy 81.568088 -274.535339)
			(xy 81.616474 -274.476977) (xy 81.67079 -274.424089) (xy 81.730419 -274.377274) (xy 81.794687 -274.337062)
			(xy 81.862864 -274.30391) (xy 81.93418 -274.278192) (xy 82.007825 -274.2602) (xy 82.082965 -274.250138)
			(xy 82.158749 -274.248119) (xy 82.234319 -274.254168) (xy 82.308817 -274.268215) (xy 82.3814 -274.290101)
			(xy 82.451246 -274.319578) (xy 82.517563 -274.356313) (xy 82.579599 -274.399888) (xy 82.636652 -274.44981)
			(xy 82.688076 -274.505514) (xy 82.733287 -274.566369) (xy 82.771774 -274.631684) (xy 82.8031 -274.70072)
			(xy 82.82691 -274.772695) (xy 82.842935 -274.846793) (xy 82.850994 -274.922174) (xy 82.851498 -274.96008)
			(xy 82.850994 -274.997986) (xy 82.842935 -275.073367) (xy 82.82691 -275.147465) (xy 82.8031 -275.21944)
			(xy 82.771774 -275.288476) (xy 82.733287 -275.353791) (xy 82.688076 -275.414646) (xy 82.636652 -275.47035)
			(xy 82.579599 -275.520272) (xy 82.517563 -275.563847) (xy 82.451246 -275.600582) (xy 82.3814 -275.630059)
			(xy 82.308817 -275.651945) (xy 82.234319 -275.665992) (xy 82.158749 -275.672041) (xy 82.082965 -275.670022)
			(xy 82.007825 -275.65996) (xy 81.93418 -275.641968) (xy 81.862864 -275.61625) (xy 81.794687 -275.583098)
			(xy 81.730419 -275.542886) (xy 81.67079 -275.496071) (xy 81.616474 -275.443183) (xy 81.568088 -275.384821)
			(xy 81.52618 -275.321646) (xy 81.491224 -275.254375) (xy 81.463617 -275.18377) (xy 81.443671 -275.110629)
			(xy 81.431612 -275.035784) (xy 81.427577 -274.96008) (xy 80.311498 -274.96008) (xy 80.310994 -274.997986)
			(xy 80.302935 -275.073367) (xy 80.28691 -275.147465) (xy 80.2631 -275.21944) (xy 80.231774 -275.288476)
			(xy 80.193287 -275.353791) (xy 80.148076 -275.414646) (xy 80.096652 -275.47035) (xy 80.039599 -275.520272)
			(xy 79.977563 -275.563847) (xy 79.911246 -275.600582) (xy 79.8414 -275.630059) (xy 79.768817 -275.651945)
			(xy 79.694319 -275.665992) (xy 79.618749 -275.672041) (xy 79.542965 -275.670022) (xy 79.467825 -275.65996)
			(xy 79.39418 -275.641968) (xy 79.322864 -275.61625) (xy 79.254687 -275.583098) (xy 79.190419 -275.542886)
			(xy 79.13079 -275.496071) (xy 79.076474 -275.443183) (xy 79.028088 -275.384821) (xy 78.98618 -275.321646)
			(xy 78.951224 -275.254375) (xy 78.923617 -275.18377) (xy 78.903671 -275.110629) (xy 78.891612 -275.035784)
			(xy 78.887577 -274.96008) (xy 77.771498 -274.96008) (xy 77.770994 -274.997986) (xy 77.762935 -275.073367)
			(xy 77.74691 -275.147465) (xy 77.7231 -275.21944) (xy 77.691774 -275.288476) (xy 77.653287 -275.353791)
			(xy 77.608076 -275.414646) (xy 77.556652 -275.47035) (xy 77.499599 -275.520272) (xy 77.437563 -275.563847)
			(xy 77.371246 -275.600582) (xy 77.3014 -275.630059) (xy 77.228817 -275.651945) (xy 77.154319 -275.665992)
			(xy 77.078749 -275.672041) (xy 77.002965 -275.670022) (xy 76.927825 -275.65996) (xy 76.85418 -275.641968)
			(xy 76.782864 -275.61625) (xy 76.714687 -275.583098) (xy 76.650419 -275.542886) (xy 76.59079 -275.496071)
			(xy 76.536474 -275.443183) (xy 76.488088 -275.384821) (xy 76.44618 -275.321646) (xy 76.411224 -275.254375)
			(xy 76.383617 -275.18377) (xy 76.363671 -275.110629) (xy 76.351612 -275.035784) (xy 76.347577 -274.96008)
			(xy 75.231498 -274.96008) (xy 75.230994 -274.997986) (xy 75.222935 -275.073367) (xy 75.20691 -275.147465)
			(xy 75.1831 -275.21944) (xy 75.151774 -275.288476) (xy 75.113287 -275.353791) (xy 75.068076 -275.414646)
			(xy 75.016652 -275.47035) (xy 74.959599 -275.520272) (xy 74.897563 -275.563847) (xy 74.831246 -275.600582)
			(xy 74.7614 -275.630059) (xy 74.688817 -275.651945) (xy 74.614319 -275.665992) (xy 74.538749 -275.672041)
			(xy 74.462965 -275.670022) (xy 74.387825 -275.65996) (xy 74.31418 -275.641968) (xy 74.242864 -275.61625)
			(xy 74.174687 -275.583098) (xy 74.110419 -275.542886) (xy 74.05079 -275.496071) (xy 73.996474 -275.443183)
			(xy 73.948088 -275.384821) (xy 73.90618 -275.321646) (xy 73.871224 -275.254375) (xy 73.843617 -275.18377)
			(xy 73.823671 -275.110629) (xy 73.811612 -275.035784) (xy 73.807577 -274.96008) (xy 72.691498 -274.96008)
			(xy 72.690994 -274.997986) (xy 72.682935 -275.073367) (xy 72.66691 -275.147465) (xy 72.6431 -275.21944)
			(xy 72.611774 -275.288476) (xy 72.573287 -275.353791) (xy 72.528076 -275.414646) (xy 72.476652 -275.47035)
			(xy 72.419599 -275.520272) (xy 72.357563 -275.563847) (xy 72.291246 -275.600582) (xy 72.2214 -275.630059)
			(xy 72.148817 -275.651945) (xy 72.074319 -275.665992) (xy 71.998749 -275.672041) (xy 71.922965 -275.670022)
			(xy 71.847825 -275.65996) (xy 71.77418 -275.641968) (xy 71.702864 -275.61625) (xy 71.634687 -275.583098)
			(xy 71.570419 -275.542886) (xy 71.51079 -275.496071) (xy 71.456474 -275.443183) (xy 71.408088 -275.384821)
			(xy 71.36618 -275.321646) (xy 71.331224 -275.254375) (xy 71.303617 -275.18377) (xy 71.283671 -275.110629)
			(xy 71.271612 -275.035784) (xy 71.267577 -274.96008) (xy 70.151498 -274.96008) (xy 70.150994 -274.997986)
			(xy 70.142935 -275.073367) (xy 70.12691 -275.147465) (xy 70.1031 -275.21944) (xy 70.071774 -275.288476)
			(xy 70.033287 -275.353791) (xy 69.988076 -275.414646) (xy 69.936652 -275.47035) (xy 69.879599 -275.520272)
			(xy 69.817563 -275.563847) (xy 69.751246 -275.600582) (xy 69.6814 -275.630059) (xy 69.608817 -275.651945)
			(xy 69.534319 -275.665992) (xy 69.458749 -275.672041) (xy 69.382965 -275.670022) (xy 69.307825 -275.65996)
			(xy 69.23418 -275.641968) (xy 69.162864 -275.61625) (xy 69.094687 -275.583098) (xy 69.030419 -275.542886)
			(xy 68.97079 -275.496071) (xy 68.916474 -275.443183) (xy 68.868088 -275.384821) (xy 68.82618 -275.321646)
			(xy 68.791224 -275.254375) (xy 68.763617 -275.18377) (xy 68.743671 -275.110629) (xy 68.731612 -275.035784)
			(xy 68.727577 -274.96008) (xy 67.611498 -274.96008) (xy 67.610994 -274.997986) (xy 67.602935 -275.073367)
			(xy 67.58691 -275.147465) (xy 67.5631 -275.21944) (xy 67.531774 -275.288476) (xy 67.493287 -275.353791)
			(xy 67.448076 -275.414646) (xy 67.396652 -275.47035) (xy 67.339599 -275.520272) (xy 67.277563 -275.563847)
			(xy 67.211246 -275.600582) (xy 67.1414 -275.630059) (xy 67.068817 -275.651945) (xy 66.994319 -275.665992)
			(xy 66.918749 -275.672041) (xy 66.842965 -275.670022) (xy 66.767825 -275.65996) (xy 66.69418 -275.641968)
			(xy 66.622864 -275.61625) (xy 66.554687 -275.583098) (xy 66.490419 -275.542886) (xy 66.43079 -275.496071)
			(xy 66.376474 -275.443183) (xy 66.328088 -275.384821) (xy 66.28618 -275.321646) (xy 66.251224 -275.254375)
			(xy 66.223617 -275.18377) (xy 66.203671 -275.110629) (xy 66.191612 -275.035784) (xy 66.187577 -274.96008)
			(xy 65.071498 -274.96008) (xy 65.070994 -274.997986) (xy 65.062935 -275.073367) (xy 65.04691 -275.147465)
			(xy 65.0231 -275.21944) (xy 64.991774 -275.288476) (xy 64.953287 -275.353791) (xy 64.908076 -275.414646)
			(xy 64.856652 -275.47035) (xy 64.799599 -275.520272) (xy 64.737563 -275.563847) (xy 64.671246 -275.600582)
			(xy 64.6014 -275.630059) (xy 64.528817 -275.651945) (xy 64.454319 -275.665992) (xy 64.378749 -275.672041)
			(xy 64.302965 -275.670022) (xy 64.227825 -275.65996) (xy 64.15418 -275.641968) (xy 64.082864 -275.61625)
			(xy 64.014687 -275.583098) (xy 63.950419 -275.542886) (xy 63.89079 -275.496071) (xy 63.836474 -275.443183)
			(xy 63.788088 -275.384821) (xy 63.74618 -275.321646) (xy 63.711224 -275.254375) (xy 63.683617 -275.18377)
			(xy 63.663671 -275.110629) (xy 63.651612 -275.035784) (xy 63.647577 -274.96008) (xy 42.500813 -274.96008)
			(xy 42.479042 -274.976857) (xy 42.381609 -275.041665) (xy 42.279905 -275.09954) (xy 42.174422 -275.150202)
			(xy 42.065671 -275.193404) (xy 41.954179 -275.228939) (xy 41.840485 -275.256634) (xy 41.725141 -275.276354)
			(xy 41.608704 -275.288005) (xy 41.491739 -275.29153) (xy 41.374812 -275.286912) (xy 41.258489 -275.274173)
			(xy 41.143334 -275.253375) (xy 41.029905 -275.224618) (xy 40.91875 -275.188042) (xy 40.810407 -275.143825)
			(xy 40.705403 -275.092179) (xy 40.604244 -275.033356) (xy 40.507421 -274.96764) (xy 40.415403 -274.895349)
			(xy 40.328636 -274.816834) (xy 40.247539 -274.732474) (xy 40.172506 -274.642679) (xy 40.103899 -274.547883)
			(xy 40.042051 -274.448544) (xy 39.987262 -274.345145) (xy 39.939796 -274.238186) (xy 39.899884 -274.128185)
			(xy 39.86772 -274.015674) (xy 39.843457 -273.901199) (xy 39.827215 -273.785313) (xy 39.819072 -273.668579)
			(xy 39.818564 -273.61007) (xy 14.463776 -273.61007) (xy 13.267322 -274.806524) (xy 24.075407 -274.806524)
			(xy 24.075407 -274.743296) (xy 24.08366 -274.68061) (xy 24.100024 -274.619537) (xy 24.12422 -274.561123)
			(xy 24.155833 -274.506366) (xy 24.194323 -274.456205) (xy 24.239032 -274.411496) (xy 24.289193 -274.373006)
			(xy 24.343949 -274.341392) (xy 24.402363 -274.317195) (xy 24.463436 -274.30083) (xy 24.526122 -274.292577)
			(xy 24.557736 -274.29206) (xy 25.874218 -274.29206) (xy 26.431494 -274.849082) (xy 26.44828 -274.865083)
			(xy 26.48647 -274.891379) (xy 26.528796 -274.910309) (xy 26.573855 -274.921245) (xy 26.620151 -274.923825)
			(xy 26.666146 -274.917961) (xy 26.710314 -274.903849) (xy 26.751188 -274.881958) (xy 26.787411 -274.853014)
			(xy 26.817782 -274.817977) (xy 26.841291 -274.778012) (xy 26.857159 -274.734444) (xy 26.861516 -274.711668)
			(xy 26.866629 -274.684281) (xy 26.883757 -274.63127) (xy 26.908414 -274.581313) (xy 26.940075 -274.535474)
			(xy 26.978067 -274.494728) (xy 27.021582 -274.459942) (xy 27.069694 -274.431855) (xy 27.12138 -274.411066)
			(xy 27.175541 -274.398016) (xy 27.231023 -274.392983) (xy 27.286647 -274.396073) (xy 27.341231 -274.407222)
			(xy 27.393612 -274.426192) (xy 27.442676 -274.45258) (xy 27.487381 -274.485824) (xy 27.526774 -274.525217)
			(xy 27.560018 -274.569921) (xy 27.586406 -274.618985) (xy 27.605377 -274.671366) (xy 27.616526 -274.725949)
			(xy 27.619618 -274.781574) (xy 27.614585 -274.837056) (xy 27.601535 -274.891217) (xy 27.580746 -274.942903)
			(xy 27.55266 -274.991015) (xy 27.517874 -275.03453) (xy 27.477129 -275.072523) (xy 27.43129 -275.104185)
			(xy 27.381334 -275.128842) (xy 27.328322 -275.14597) (xy 27.300936 -275.151088) (xy 27.278148 -275.155399)
			(xy 27.234572 -275.171269) (xy 27.194599 -275.194783) (xy 27.159556 -275.225159) (xy 27.130606 -275.261389)
			(xy 27.108711 -275.302271) (xy 27.094597 -275.346446) (xy 27.088733 -275.39245) (xy 27.091313 -275.438754)
			(xy 27.102252 -275.483821) (xy 27.121186 -275.526155) (xy 27.147488 -275.564351) (xy 27.163522 -275.58111)
			(xy 27.235404 -275.652992) (xy 29.38907 -275.652992) (xy 29.412516 -275.652483) (xy 29.458608 -275.643852)
			(xy 29.502334 -275.626913) (xy 29.542212 -275.602241) (xy 29.576888 -275.570674) (xy 29.605187 -275.533282)
			(xy 29.626147 -275.491334) (xy 29.639057 -275.446254) (xy 29.643481 -275.39957) (xy 29.639266 -275.352867)
			(xy 29.626558 -275.307729) (xy 29.616654 -275.28647) (xy 29.597882 -275.247353) (xy 29.566773 -275.16635)
			(xy 29.54326 -275.082826) (xy 29.527541 -274.997491) (xy 29.519752 -274.911071) (xy 29.519957 -274.824301)
			(xy 29.528156 -274.737918) (xy 29.544278 -274.652658) (xy 29.568186 -274.569247) (xy 29.599678 -274.488392)
			(xy 29.638485 -274.410783) (xy 29.684276 -274.337079) (xy 29.736664 -274.267908) (xy 29.795201 -274.203857)
			(xy 29.85939 -274.145471) (xy 29.928686 -274.093248) (xy 30.002498 -274.04763) (xy 30.080199 -274.009007)
			(xy 30.161127 -273.977707) (xy 30.244595 -273.953996) (xy 30.329893 -273.938076) (xy 30.416295 -273.930082)
			(xy 30.503065 -273.930082) (xy 30.589467 -273.938076) (xy 30.674765 -273.953996) (xy 30.758233 -273.977707)
			(xy 30.839161 -274.009007) (xy 30.916862 -274.04763) (xy 30.990674 -274.093248) (xy 31.05997 -274.145471)
			(xy 31.124159 -274.203857) (xy 31.182696 -274.267908) (xy 31.235084 -274.337079) (xy 31.280875 -274.410783)
			(xy 31.319682 -274.488392) (xy 31.351174 -274.569247) (xy 31.375082 -274.652658) (xy 31.391204 -274.737918)
			(xy 31.399403 -274.824301) (xy 31.399608 -274.911071) (xy 31.399402 -274.91336) (xy 34.599874 -274.91336)
			(xy 34.599874 -274.82646) (xy 34.607892 -274.739931) (xy 34.62386 -274.654511) (xy 34.647641 -274.570929)
			(xy 34.679033 -274.489897) (xy 34.717767 -274.412108) (xy 34.763514 -274.338224) (xy 34.815883 -274.268877)
			(xy 34.874427 -274.204657) (xy 34.938647 -274.146113) (xy 35.007994 -274.093744) (xy 35.081878 -274.047997)
			(xy 35.159667 -274.009263) (xy 35.240699 -273.977871) (xy 35.324281 -273.95409) (xy 35.409701 -273.938122)
			(xy 35.49623 -273.930104) (xy 35.58313 -273.930104) (xy 35.669659 -273.938122) (xy 35.755079 -273.95409)
			(xy 35.838661 -273.977871) (xy 35.919693 -274.009263) (xy 35.997482 -274.047997) (xy 36.071366 -274.093744)
			(xy 36.140713 -274.146113) (xy 36.204933 -274.204657) (xy 36.263477 -274.268877) (xy 36.315846 -274.338224)
			(xy 36.361593 -274.412108) (xy 36.400327 -274.489897) (xy 36.431719 -274.570929) (xy 36.4555 -274.654511)
			(xy 36.471468 -274.739931) (xy 36.479486 -274.82646) (xy 36.479988 -274.86991) (xy 36.479486 -274.91336)
			(xy 36.471468 -274.999889) (xy 36.4555 -275.085309) (xy 36.431719 -275.168891) (xy 36.400327 -275.249923)
			(xy 36.361593 -275.327712) (xy 36.315846 -275.401596) (xy 36.263477 -275.470943) (xy 36.204933 -275.535163)
			(xy 36.140713 -275.593707) (xy 36.071366 -275.646076) (xy 35.997482 -275.691823) (xy 35.919693 -275.730557)
			(xy 35.838661 -275.761949) (xy 35.755079 -275.78573) (xy 35.669659 -275.801698) (xy 35.58313 -275.809716)
			(xy 35.49623 -275.809716) (xy 35.409701 -275.801698) (xy 35.324281 -275.78573) (xy 35.240699 -275.761949)
			(xy 35.159667 -275.730557) (xy 35.081878 -275.691823) (xy 35.007994 -275.646076) (xy 34.938647 -275.593707)
			(xy 34.874427 -275.535163) (xy 34.815883 -275.470943) (xy 34.763514 -275.401596) (xy 34.717767 -275.327712)
			(xy 34.679033 -275.249923) (xy 34.647641 -275.168891) (xy 34.62386 -275.085309) (xy 34.607892 -274.999889)
			(xy 34.599874 -274.91336) (xy 31.399402 -274.91336) (xy 31.391819 -274.997491) (xy 31.3761 -275.082826)
			(xy 31.352587 -275.16635) (xy 31.321478 -275.247353) (xy 31.302706 -275.28647) (xy 31.292744 -275.307709)
			(xy 31.280002 -275.352854) (xy 31.275764 -275.39957) (xy 31.280175 -275.446271) (xy 31.293083 -275.491368)
			(xy 31.314051 -275.533329) (xy 31.342366 -275.570728) (xy 31.377065 -275.602293) (xy 31.416969 -275.626952)
			(xy 31.460722 -275.643866) (xy 31.506836 -275.652461) (xy 31.53029 -275.652992) (xy 31.771082 -275.652992)
			(xy 33.0835 -276.96541) (xy 33.0835 -277.45336) (xy 34.599874 -277.45336) (xy 34.599874 -277.36646)
			(xy 34.607892 -277.279931) (xy 34.62386 -277.194511) (xy 34.647641 -277.110929) (xy 34.679033 -277.029897)
			(xy 34.717767 -276.952108) (xy 34.763514 -276.878224) (xy 34.815883 -276.808877) (xy 34.874427 -276.744657)
			(xy 34.938647 -276.686113) (xy 35.007994 -276.633744) (xy 35.081878 -276.587997) (xy 35.159667 -276.549263)
			(xy 35.240699 -276.517871) (xy 35.324281 -276.49409) (xy 35.409701 -276.478122) (xy 35.49623 -276.470104)
			(xy 35.58313 -276.470104) (xy 35.669659 -276.478122) (xy 35.755079 -276.49409) (xy 35.838661 -276.517871)
			(xy 35.919693 -276.549263) (xy 35.997482 -276.587997) (xy 36.071366 -276.633744) (xy 36.140713 -276.686113)
			(xy 36.204933 -276.744657) (xy 36.263477 -276.808877) (xy 36.315846 -276.878224) (xy 36.361593 -276.952108)
			(xy 36.400327 -277.029897) (xy 36.431719 -277.110929) (xy 36.4555 -277.194511) (xy 36.471468 -277.279931)
			(xy 36.479486 -277.36646) (xy 36.479988 -277.40991) (xy 36.479486 -277.45336) (xy 36.471468 -277.539889)
			(xy 36.4555 -277.625309) (xy 36.431719 -277.708891) (xy 36.400327 -277.789923) (xy 36.361593 -277.867712)
			(xy 36.315846 -277.941596) (xy 36.263477 -278.010943) (xy 36.204933 -278.075163) (xy 36.140713 -278.133707)
			(xy 36.071366 -278.186076) (xy 35.997482 -278.231823) (xy 35.919693 -278.270557) (xy 35.838661 -278.301949)
			(xy 35.755079 -278.32573) (xy 35.669659 -278.341698) (xy 35.58313 -278.349716) (xy 35.49623 -278.349716)
			(xy 35.409701 -278.341698) (xy 35.324281 -278.32573) (xy 35.240699 -278.301949) (xy 35.159667 -278.270557)
			(xy 35.081878 -278.231823) (xy 35.007994 -278.186076) (xy 34.938647 -278.133707) (xy 34.874427 -278.075163)
			(xy 34.815883 -278.010943) (xy 34.763514 -277.941596) (xy 34.717767 -277.867712) (xy 34.679033 -277.789923)
			(xy 34.647641 -277.708891) (xy 34.62386 -277.625309) (xy 34.607892 -277.539889) (xy 34.599874 -277.45336)
			(xy 33.0835 -277.45336) (xy 33.0835 -279.99336) (xy 34.599874 -279.99336) (xy 34.599874 -279.90646)
			(xy 34.607892 -279.819931) (xy 34.62386 -279.734511) (xy 34.647641 -279.650929) (xy 34.679033 -279.569897)
			(xy 34.717767 -279.492108) (xy 34.763514 -279.418224) (xy 34.815883 -279.348877) (xy 34.874427 -279.284657)
			(xy 34.938647 -279.226113) (xy 35.007994 -279.173744) (xy 35.081878 -279.127997) (xy 35.159667 -279.089263)
			(xy 35.240699 -279.057871) (xy 35.324281 -279.03409) (xy 35.409701 -279.018122) (xy 35.49623 -279.010104)
			(xy 35.58313 -279.010104) (xy 35.669659 -279.018122) (xy 35.755079 -279.03409) (xy 35.838661 -279.057871)
			(xy 35.919693 -279.089263) (xy 35.997482 -279.127997) (xy 36.071366 -279.173744) (xy 36.140713 -279.226113)
			(xy 36.204933 -279.284657) (xy 36.263477 -279.348877) (xy 36.315846 -279.418224) (xy 36.361593 -279.492108)
			(xy 36.400327 -279.569897) (xy 36.431719 -279.650929) (xy 36.434833 -279.661874) (xy 39.458898 -279.661874)
			(xy 39.462969 -279.606252) (xy 39.475095 -279.551815) (xy 39.495018 -279.499724) (xy 39.522314 -279.451089)
			(xy 39.5564 -279.406946) (xy 39.596549 -279.368237) (xy 39.641907 -279.335786) (xy 39.691507 -279.310285)
			(xy 39.744291 -279.292278) (xy 39.799134 -279.282148) (xy 39.854868 -279.280111) (xy 39.910305 -279.286211)
			(xy 39.964262 -279.300317) (xy 40.015591 -279.322129) (xy 40.063197 -279.351183) (xy 40.106065 -279.386858)
			(xy 40.143282 -279.428395) (xy 40.174055 -279.474908) (xy 40.197727 -279.525405) (xy 40.213795 -279.578812)
			(xy 40.221915 -279.633988) (xy 40.222424 -279.661874) (xy 40.221915 -279.68976) (xy 40.213795 -279.744936)
			(xy 40.197727 -279.798343) (xy 40.174055 -279.84884) (xy 40.143282 -279.895353) (xy 40.106065 -279.93689)
			(xy 40.063197 -279.972565) (xy 40.015591 -280.001619) (xy 39.964262 -280.023431) (xy 39.910305 -280.037537)
			(xy 39.854868 -280.043637) (xy 39.799134 -280.0416) (xy 39.744291 -280.03147) (xy 39.691507 -280.013463)
			(xy 39.641907 -279.987962) (xy 39.596549 -279.955511) (xy 39.5564 -279.916802) (xy 39.522314 -279.872659)
			(xy 39.495018 -279.824024) (xy 39.475095 -279.771933) (xy 39.462969 -279.717496) (xy 39.458898 -279.661874)
			(xy 36.434833 -279.661874) (xy 36.4555 -279.734511) (xy 36.471468 -279.819931) (xy 36.479486 -279.90646)
			(xy 36.479988 -279.94991) (xy 36.479486 -279.99336) (xy 36.471468 -280.079889) (xy 36.4555 -280.165309)
			(xy 36.431719 -280.248891) (xy 36.400327 -280.329923) (xy 36.361593 -280.407712) (xy 36.315846 -280.481596)
			(xy 36.263477 -280.550943) (xy 36.204933 -280.615163) (xy 36.140713 -280.673707) (xy 36.071366 -280.726076)
			(xy 35.997482 -280.771823) (xy 35.919693 -280.810557) (xy 35.838661 -280.841949) (xy 35.755079 -280.86573)
			(xy 35.669659 -280.881698) (xy 35.58313 -280.889716) (xy 35.49623 -280.889716) (xy 35.409701 -280.881698)
			(xy 35.324281 -280.86573) (xy 35.240699 -280.841949) (xy 35.159667 -280.810557) (xy 35.081878 -280.771823)
			(xy 35.007994 -280.726076) (xy 34.938647 -280.673707) (xy 34.874427 -280.615163) (xy 34.815883 -280.550943)
			(xy 34.763514 -280.481596) (xy 34.717767 -280.407712) (xy 34.679033 -280.329923) (xy 34.647641 -280.248891)
			(xy 34.62386 -280.165309) (xy 34.607892 -280.079889) (xy 34.599874 -279.99336) (xy 33.0835 -279.99336)
			(xy 33.0835 -281.89047) (xy 33.726315 -282.53336) (xy 34.599874 -282.53336) (xy 34.599874 -282.44646)
			(xy 34.607892 -282.359931) (xy 34.62386 -282.274511) (xy 34.647641 -282.190929) (xy 34.679033 -282.109897)
			(xy 34.717767 -282.032108) (xy 34.763514 -281.958224) (xy 34.815883 -281.888877) (xy 34.874427 -281.824657)
			(xy 34.938647 -281.766113) (xy 35.007994 -281.713744) (xy 35.081878 -281.667997) (xy 35.159667 -281.629263)
			(xy 35.240699 -281.597871) (xy 35.324281 -281.57409) (xy 35.409701 -281.558122) (xy 35.49623 -281.550104)
			(xy 35.58313 -281.550104) (xy 35.669659 -281.558122) (xy 35.755079 -281.57409) (xy 35.838661 -281.597871)
			(xy 35.919693 -281.629263) (xy 35.997482 -281.667997) (xy 36.071366 -281.713744) (xy 36.140713 -281.766113)
			(xy 36.204933 -281.824657) (xy 36.263477 -281.888877) (xy 36.315846 -281.958224) (xy 36.361593 -282.032108)
			(xy 36.400327 -282.109897) (xy 36.431719 -282.190929) (xy 36.4555 -282.274511) (xy 36.471468 -282.359931)
			(xy 36.479486 -282.44646) (xy 36.479988 -282.48991) (xy 36.479486 -282.53336) (xy 36.471468 -282.619889)
			(xy 36.4555 -282.705309) (xy 36.431719 -282.788891) (xy 36.400327 -282.869923) (xy 36.361593 -282.947712)
			(xy 36.315846 -283.021596) (xy 36.263477 -283.090943) (xy 36.204933 -283.155163) (xy 36.140713 -283.213707)
			(xy 36.071366 -283.266076) (xy 35.997482 -283.311823) (xy 35.919693 -283.350557) (xy 35.838661 -283.381949)
			(xy 35.755079 -283.40573) (xy 35.669659 -283.421698) (xy 35.58313 -283.429716) (xy 35.49623 -283.429716)
			(xy 35.409701 -283.421698) (xy 35.324281 -283.40573) (xy 35.240699 -283.381949) (xy 35.159667 -283.350557)
			(xy 35.081878 -283.311823) (xy 35.007994 -283.266076) (xy 34.938647 -283.213707) (xy 34.874427 -283.155163)
			(xy 34.815883 -283.090943) (xy 34.763514 -283.021596) (xy 34.717767 -282.947712) (xy 34.679033 -282.869923)
			(xy 34.647641 -282.788891) (xy 34.62386 -282.705309) (xy 34.607892 -282.619889) (xy 34.599874 -282.53336)
			(xy 33.726315 -282.53336) (xy 35.261804 -284.069028) (xy 35.272928 -284.079564) (xy 35.299121 -284.095447)
			(xy 35.328345 -284.104629) (xy 35.358915 -284.106581) (xy 35.374072 -284.104334) (xy 35.416795 -284.097168)
			(xy 35.503116 -284.089817) (xy 35.589747 -284.090437) (xy 35.675954 -284.099024) (xy 35.761006 -284.115505)
			(xy 35.844181 -284.139739) (xy 35.924774 -284.171522) (xy 36.002102 -284.210583) (xy 36.075508 -284.256593)
			(xy 36.144372 -284.309159) (xy 36.208107 -284.367838) (xy 36.266175 -284.43213) (xy 36.318083 -284.501492)
			(xy 36.36339 -284.575334) (xy 36.401712 -284.653031) (xy 36.432724 -284.733923) (xy 36.456164 -284.817326)
			(xy 36.471833 -284.902531) (xy 36.479597 -284.988816) (xy 36.479392 -285.075449) (xy 36.471217 -285.161696)
			(xy 36.455304 -285.245979) (xy 47.75199 -285.245979) (xy 47.75199 -285.164869) (xy 47.75994 -285.08415)
			(xy 47.775763 -285.004599) (xy 47.799308 -284.926983) (xy 47.830347 -284.852047) (xy 47.868582 -284.780515)
			(xy 47.913644 -284.713075) (xy 47.965099 -284.650376) (xy 48.022452 -284.593023) (xy 48.085151 -284.541568)
			(xy 48.152591 -284.496506) (xy 48.224123 -284.458271) (xy 48.299059 -284.427232) (xy 48.376675 -284.403687)
			(xy 48.456226 -284.387864) (xy 48.536945 -284.379914) (xy 48.618055 -284.379914) (xy 48.698774 -284.387864)
			(xy 48.778325 -284.403687) (xy 48.855941 -284.427232) (xy 48.930877 -284.458271) (xy 49.002409 -284.496506)
			(xy 49.069849 -284.541568) (xy 49.132548 -284.593023) (xy 49.189901 -284.650376) (xy 49.241356 -284.713075)
			(xy 49.286418 -284.780515) (xy 49.324653 -284.852047) (xy 49.355692 -284.926983) (xy 49.379237 -285.004599)
			(xy 49.39506 -285.08415) (xy 49.40301 -285.164869) (xy 49.403508 -285.205424) (xy 49.40301 -285.245979)
			(xy 51.25211 -285.245979) (xy 51.25211 -285.164869) (xy 51.26006 -285.08415) (xy 51.275883 -285.004599)
			(xy 51.299428 -284.926983) (xy 51.330467 -284.852047) (xy 51.368702 -284.780515) (xy 51.413764 -284.713075)
			(xy 51.465219 -284.650376) (xy 51.522572 -284.593023) (xy 51.585271 -284.541568) (xy 51.652711 -284.496506)
			(xy 51.724243 -284.458271) (xy 51.799179 -284.427232) (xy 51.876795 -284.403687) (xy 51.956346 -284.387864)
			(xy 52.037065 -284.379914) (xy 52.118175 -284.379914) (xy 52.198894 -284.387864) (xy 52.278445 -284.403687)
			(xy 52.356061 -284.427232) (xy 52.430997 -284.458271) (xy 52.502529 -284.496506) (xy 52.569969 -284.541568)
			(xy 52.632668 -284.593023) (xy 52.690021 -284.650376) (xy 52.741476 -284.713075) (xy 52.786538 -284.780515)
			(xy 52.824773 -284.852047) (xy 52.855812 -284.926983) (xy 52.879357 -285.004599) (xy 52.89518 -285.08415)
			(xy 52.90313 -285.164869) (xy 52.903628 -285.205424) (xy 52.90313 -285.245979) (xy 52.89518 -285.326698)
			(xy 52.879357 -285.406249) (xy 52.855812 -285.483865) (xy 52.824773 -285.558801) (xy 52.786538 -285.630333)
			(xy 52.741476 -285.697773) (xy 52.71946 -285.7246) (xy 58.726192 -285.7246) (xy 58.730079 -285.670247)
			(xy 58.741663 -285.617001) (xy 58.760706 -285.565945) (xy 58.786822 -285.518119) (xy 58.819479 -285.474496)
			(xy 58.858012 -285.435966) (xy 58.901636 -285.403312) (xy 58.949463 -285.377198) (xy 59.00052 -285.358157)
			(xy 59.053767 -285.346577) (xy 59.10812 -285.342692) (xy 59.162473 -285.346582) (xy 59.215719 -285.358169)
			(xy 59.266774 -285.377215) (xy 59.314598 -285.403333) (xy 59.336686 -285.419292) (xy 59.355698 -285.432888)
			(xy 59.397581 -285.45362) (xy 59.442549 -285.466346) (xy 59.489086 -285.470636) (xy 59.535623 -285.466346)
			(xy 59.580591 -285.45362) (xy 59.622474 -285.432888) (xy 59.641486 -285.419292) (xy 59.663574 -285.403331)
			(xy 59.711401 -285.377208) (xy 59.762458 -285.358158) (xy 59.815708 -285.346568) (xy 59.870064 -285.342675)
			(xy 59.924421 -285.346558) (xy 59.977672 -285.358137) (xy 60.028734 -285.377178) (xy 60.076565 -285.403292)
			(xy 60.120193 -285.435948) (xy 60.158729 -285.47448) (xy 60.191389 -285.518105) (xy 60.217507 -285.565934)
			(xy 60.236552 -285.616993) (xy 60.248137 -285.670243) (xy 60.252025 -285.7246) (xy 61.258109 -285.7246)
			(xy 61.261996 -285.670251) (xy 61.273578 -285.617008) (xy 61.29262 -285.565956) (xy 61.318733 -285.518133)
			(xy 61.351387 -285.474513) (xy 61.389916 -285.435984) (xy 61.433536 -285.403331) (xy 61.481359 -285.377218)
			(xy 61.532412 -285.358177) (xy 61.585655 -285.346595) (xy 61.640004 -285.342709) (xy 61.694353 -285.346596)
			(xy 61.747596 -285.358179) (xy 61.798648 -285.377222) (xy 61.846471 -285.403336) (xy 61.868558 -285.419292)
			(xy 61.88757 -285.432888) (xy 61.929453 -285.45362) (xy 61.974421 -285.466346) (xy 62.020958 -285.470636)
			(xy 62.067495 -285.466346) (xy 62.112463 -285.45362) (xy 62.154346 -285.432888) (xy 62.173358 -285.419292)
			(xy 62.195447 -285.403328) (xy 62.243276 -285.377201) (xy 62.294336 -285.358147) (xy 62.347588 -285.346554)
			(xy 62.401948 -285.342658) (xy 62.456309 -285.346539) (xy 62.509565 -285.358118) (xy 62.56063 -285.377158)
			(xy 62.608465 -285.403272) (xy 62.652097 -285.435929) (xy 62.690637 -285.474464) (xy 62.7233 -285.518091)
			(xy 62.749421 -285.565923) (xy 62.768468 -285.616986) (xy 62.780053 -285.670239) (xy 62.781323 -285.687986)
			(xy 63.482113 -285.687986) (xy 63.486003 -285.633636) (xy 63.497588 -285.580393) (xy 63.516632 -285.529341)
			(xy 63.542748 -285.481519) (xy 63.575404 -285.437901) (xy 63.613936 -285.399374) (xy 63.657558 -285.366723)
			(xy 63.705383 -285.340612) (xy 63.756438 -285.321574) (xy 63.809682 -285.309996) (xy 63.864032 -285.306113)
			(xy 63.918382 -285.310005) (xy 63.971624 -285.321593) (xy 64.022675 -285.340639) (xy 64.070496 -285.366758)
			(xy 64.092582 -285.382716) (xy 64.111594 -285.396312) (xy 64.153477 -285.417044) (xy 64.198445 -285.42977)
			(xy 64.244982 -285.43406) (xy 64.291519 -285.42977) (xy 64.336487 -285.417044) (xy 64.37837 -285.396312)
			(xy 64.397382 -285.382716) (xy 64.419448 -285.366722) (xy 64.467276 -285.340595) (xy 64.518336 -285.321542)
			(xy 64.571588 -285.309949) (xy 64.625947 -285.306053) (xy 64.680308 -285.309934) (xy 64.733563 -285.321512)
			(xy 64.784628 -285.340552) (xy 64.832463 -285.366665) (xy 64.876095 -285.399321) (xy 64.914635 -285.437854)
			(xy 64.947299 -285.48148) (xy 64.97342 -285.529311) (xy 64.992469 -285.580373) (xy 65.004056 -285.633626)
			(xy 65.00535 -285.651699) (xy 65.77816 -285.651699) (xy 65.782048 -285.597338) (xy 65.793634 -285.544085)
			(xy 65.812681 -285.493022) (xy 65.838802 -285.445191) (xy 65.871465 -285.401564) (xy 65.910005 -285.36303)
			(xy 65.953636 -285.330373) (xy 66.001472 -285.304259) (xy 66.052537 -285.285219) (xy 66.105792 -285.273641)
			(xy 66.160153 -285.26976) (xy 66.214513 -285.273656) (xy 66.267765 -285.285249) (xy 66.318825 -285.304303)
			(xy 66.366653 -285.33043) (xy 66.388742 -285.346394) (xy 66.407754 -285.35999) (xy 66.449637 -285.380722)
			(xy 66.494605 -285.393448) (xy 66.541142 -285.397738) (xy 66.587679 -285.393448) (xy 66.632647 -285.380722)
			(xy 66.67453 -285.35999) (xy 66.693542 -285.346394) (xy 66.715627 -285.330435) (xy 66.76345 -285.304321)
			(xy 66.814502 -285.285278) (xy 66.867745 -285.273695) (xy 66.922095 -285.269807) (xy 66.976444 -285.273693)
			(xy 67.029687 -285.285275) (xy 67.08074 -285.304316) (xy 67.128564 -285.330429) (xy 67.172184 -285.363082)
			(xy 67.210713 -285.401611) (xy 67.243367 -285.445231) (xy 67.269481 -285.493054) (xy 67.288523 -285.544106)
			(xy 67.300106 -285.597349) (xy 67.30141 -285.61558) (xy 68.15259 -285.61558) (xy 68.156481 -285.561224)
			(xy 68.168069 -285.507976) (xy 68.187117 -285.456919) (xy 68.213237 -285.409092) (xy 68.245899 -285.365471)
			(xy 68.284437 -285.326942) (xy 68.328067 -285.29429) (xy 68.375899 -285.26818) (xy 68.42696 -285.249144)
			(xy 68.480211 -285.237569) (xy 68.534568 -285.23369) (xy 68.588923 -285.237588) (xy 68.64217 -285.249182)
			(xy 68.693224 -285.268236) (xy 68.741047 -285.294363) (xy 68.763134 -285.310326) (xy 68.782146 -285.323922)
			(xy 68.824029 -285.344654) (xy 68.868997 -285.35738) (xy 68.915534 -285.36167) (xy 68.962071 -285.35738)
			(xy 69.007039 -285.344654) (xy 69.048922 -285.323922) (xy 69.067934 -285.310326) (xy 69.089989 -285.294323)
			(xy 69.137815 -285.268203) (xy 69.18887 -285.249156) (xy 69.242117 -285.237568) (xy 69.296471 -285.233677)
			(xy 69.350825 -285.23756) (xy 69.404074 -285.249139) (xy 69.455132 -285.268179) (xy 69.502962 -285.294292)
			(xy 69.546588 -285.326945) (xy 69.585122 -285.365475) (xy 69.617782 -285.409097) (xy 69.6439 -285.456923)
			(xy 69.662947 -285.507979) (xy 69.674533 -285.561226) (xy 69.678423 -285.61558) (xy 69.674539 -285.669934)
			(xy 69.662958 -285.723182) (xy 69.643917 -285.77424) (xy 69.617804 -285.822069) (xy 69.585149 -285.865694)
			(xy 69.546618 -285.904228) (xy 69.502996 -285.936886) (xy 69.45517 -285.963004) (xy 69.404113 -285.982049)
			(xy 69.350866 -285.993634) (xy 69.296512 -285.997523) (xy 69.242157 -285.993637) (xy 69.188909 -285.982056)
			(xy 69.137852 -285.963014) (xy 69.090024 -285.936899) (xy 69.067934 -285.920942) (xy 69.048922 -285.907346)
			(xy 69.007039 -285.886614) (xy 68.962071 -285.873888) (xy 68.915534 -285.869598) (xy 68.868997 -285.873888)
			(xy 68.824029 -285.886614) (xy 68.782146 -285.907346) (xy 68.763134 -285.920942) (xy 68.741013 -285.936859)
			(xy 68.693187 -285.962981) (xy 68.642131 -285.98203) (xy 68.588882 -285.993618) (xy 68.534527 -285.99751)
			(xy 68.480171 -285.993626) (xy 68.426921 -285.982045) (xy 68.375862 -285.963003) (xy 68.328032 -285.936888)
			(xy 68.284406 -285.904232) (xy 68.245873 -285.865699) (xy 68.213215 -285.822073) (xy 68.1871 -285.774244)
			(xy 68.168057 -285.723185) (xy 68.156475 -285.669935) (xy 68.15259 -285.61558) (xy 67.30141 -285.61558)
			(xy 67.303993 -285.651699) (xy 67.300106 -285.706048) (xy 67.288524 -285.759291) (xy 67.269482 -285.810344)
			(xy 67.243369 -285.858167) (xy 67.210715 -285.901787) (xy 67.172186 -285.940316) (xy 67.128566 -285.97297)
			(xy 67.080742 -285.999083) (xy 67.02969 -286.018124) (xy 66.976446 -286.029706) (xy 66.922097 -286.033593)
			(xy 66.867748 -286.029705) (xy 66.814505 -286.018123) (xy 66.763452 -285.99908) (xy 66.715629 -285.972966)
			(xy 66.693542 -285.95701) (xy 66.67453 -285.943414) (xy 66.632647 -285.922682) (xy 66.587679 -285.909956)
			(xy 66.541142 -285.905666) (xy 66.494605 -285.909956) (xy 66.449637 -285.922682) (xy 66.407754 -285.943414)
			(xy 66.388742 -285.95701) (xy 66.366651 -285.972971) (xy 66.318823 -285.999098) (xy 66.267763 -286.018152)
			(xy 66.214511 -286.029745) (xy 66.160151 -286.03364) (xy 66.10579 -286.029759) (xy 66.052535 -286.01818)
			(xy 66.00147 -285.99914) (xy 65.953634 -285.973026) (xy 65.910003 -285.940369) (xy 65.871464 -285.901835)
			(xy 65.838801 -285.858207) (xy 65.81268 -285.810375) (xy 65.793633 -285.759313) (xy 65.782048 -285.706059)
			(xy 65.77816 -285.651699) (xy 65.00535 -285.651699) (xy 65.007947 -285.687986) (xy 65.00406 -285.742346)
			(xy 64.992477 -285.7956) (xy 64.973432 -285.846663) (xy 64.947314 -285.894495) (xy 64.914654 -285.938124)
			(xy 64.876117 -285.97666) (xy 64.832488 -286.009319) (xy 64.784654 -286.035436) (xy 64.733591 -286.05448)
			(xy 64.680336 -286.066062) (xy 64.625976 -286.069947) (xy 64.571616 -286.066055) (xy 64.518364 -286.054466)
			(xy 64.467302 -286.035417) (xy 64.419472 -286.009293) (xy 64.397382 -285.993332) (xy 64.37837 -285.979736)
			(xy 64.336487 -285.959004) (xy 64.291519 -285.946278) (xy 64.244982 -285.941988) (xy 64.198445 -285.946278)
			(xy 64.153477 -285.959004) (xy 64.111594 -285.979736) (xy 64.092582 -285.993332) (xy 64.070472 -286.009258)
			(xy 64.022649 -286.035373) (xy 63.971596 -286.054416) (xy 63.918353 -286.065999) (xy 63.864003 -286.069887)
			(xy 63.809654 -286.066) (xy 63.75641 -286.054417) (xy 63.705357 -286.035376) (xy 63.657534 -286.009262)
			(xy 63.613914 -285.976608) (xy 63.575385 -285.938078) (xy 63.542732 -285.894457) (xy 63.51662 -285.846633)
			(xy 63.497579 -285.795579) (xy 63.485999 -285.742335) (xy 63.482113 -285.687986) (xy 62.781323 -285.687986)
			(xy 62.783942 -285.7246) (xy 62.780053 -285.778961) (xy 62.768468 -285.832214) (xy 62.749421 -285.883277)
			(xy 62.7233 -285.931109) (xy 62.690637 -285.974736) (xy 62.652097 -286.013271) (xy 62.608465 -286.045928)
			(xy 62.56063 -286.072042) (xy 62.509565 -286.091082) (xy 62.456309 -286.102661) (xy 62.401948 -286.106542)
			(xy 62.347588 -286.102646) (xy 62.294336 -286.091053) (xy 62.243276 -286.071999) (xy 62.195447 -286.045872)
			(xy 62.173358 -286.029908) (xy 62.154346 -286.016312) (xy 62.112463 -285.99558) (xy 62.067495 -285.982854)
			(xy 62.020958 -285.978564) (xy 61.974421 -285.982854) (xy 61.929453 -285.99558) (xy 61.88757 -286.016312)
			(xy 61.868558 -286.029908) (xy 61.846471 -286.045864) (xy 61.798648 -286.071978) (xy 61.747596 -286.091021)
			(xy 61.694353 -286.102604) (xy 61.640004 -286.106491) (xy 61.585655 -286.102605) (xy 61.532412 -286.091023)
			(xy 61.481359 -286.071982) (xy 61.433536 -286.045869) (xy 61.389916 -286.013216) (xy 61.351387 -285.974687)
			(xy 61.318733 -285.931067) (xy 61.29262 -285.883244) (xy 61.273578 -285.832192) (xy 61.261996 -285.778949)
			(xy 61.258109 -285.7246) (xy 60.252025 -285.7246) (xy 60.248137 -285.778957) (xy 60.236552 -285.832207)
			(xy 60.217507 -285.883266) (xy 60.191389 -285.931095) (xy 60.158729 -285.97472) (xy 60.120193 -286.013252)
			(xy 60.076565 -286.045908) (xy 60.028734 -286.072022) (xy 59.977672 -286.091063) (xy 59.924421 -286.102642)
			(xy 59.870064 -286.106525) (xy 59.815708 -286.102632) (xy 59.762458 -286.091042) (xy 59.711401 -286.071992)
			(xy 59.663574 -286.045869) (xy 59.641486 -286.029908) (xy 59.622474 -286.016312) (xy 59.580591 -285.99558)
			(xy 59.535623 -285.982854) (xy 59.489086 -285.978564) (xy 59.442549 -285.982854) (xy 59.397581 -285.99558)
			(xy 59.355698 -286.016312) (xy 59.336686 -286.029908) (xy 59.314598 -286.045867) (xy 59.266774 -286.071985)
			(xy 59.215719 -286.091031) (xy 59.162473 -286.102618) (xy 59.10812 -286.106508) (xy 59.053767 -286.102623)
			(xy 59.00052 -286.091043) (xy 58.949463 -286.072002) (xy 58.901636 -286.045888) (xy 58.858012 -286.013234)
			(xy 58.819479 -285.974704) (xy 58.786822 -285.931081) (xy 58.760706 -285.883255) (xy 58.741663 -285.832199)
			(xy 58.730079 -285.778953) (xy 58.726192 -285.7246) (xy 52.71946 -285.7246) (xy 52.690021 -285.760472)
			(xy 52.632668 -285.817825) (xy 52.569969 -285.86928) (xy 52.502529 -285.914342) (xy 52.430997 -285.952577)
			(xy 52.356061 -285.983616) (xy 52.278445 -286.007161) (xy 52.198894 -286.022984) (xy 52.118175 -286.030934)
			(xy 52.037065 -286.030934) (xy 51.956346 -286.022984) (xy 51.876795 -286.007161) (xy 51.799179 -285.983616)
			(xy 51.724243 -285.952577) (xy 51.652711 -285.914342) (xy 51.585271 -285.86928) (xy 51.522572 -285.817825)
			(xy 51.465219 -285.760472) (xy 51.413764 -285.697773) (xy 51.368702 -285.630333) (xy 51.330467 -285.558801)
			(xy 51.299428 -285.483865) (xy 51.275883 -285.406249) (xy 51.26006 -285.326698) (xy 51.25211 -285.245979)
			(xy 49.40301 -285.245979) (xy 49.39506 -285.326698) (xy 49.379237 -285.406249) (xy 49.355692 -285.483865)
			(xy 49.324653 -285.558801) (xy 49.286418 -285.630333) (xy 49.241356 -285.697773) (xy 49.189901 -285.760472)
			(xy 49.132548 -285.817825) (xy 49.069849 -285.86928) (xy 49.002409 -285.914342) (xy 48.930877 -285.952577)
			(xy 48.855941 -285.983616) (xy 48.778325 -286.007161) (xy 48.698774 -286.022984) (xy 48.618055 -286.030934)
			(xy 48.536945 -286.030934) (xy 48.456226 -286.022984) (xy 48.376675 -286.007161) (xy 48.299059 -285.983616)
			(xy 48.224123 -285.952577) (xy 48.152591 -285.914342) (xy 48.085151 -285.86928) (xy 48.022452 -285.817825)
			(xy 47.965099 -285.760472) (xy 47.913644 -285.697773) (xy 47.868582 -285.630333) (xy 47.830347 -285.558801)
			(xy 47.799308 -285.483865) (xy 47.775763 -285.406249) (xy 47.75994 -285.326698) (xy 47.75199 -285.245979)
			(xy 36.455304 -285.245979) (xy 36.455144 -285.246826) (xy 36.431308 -285.330116) (xy 36.399912 -285.41086)
			(xy 36.361221 -285.488374) (xy 36.315564 -285.562) (xy 36.263327 -285.631114) (xy 36.204955 -285.69513)
			(xy 36.140941 -285.753505) (xy 36.071829 -285.805744) (xy 35.998204 -285.851404) (xy 35.920692 -285.890098)
			(xy 35.839949 -285.921497) (xy 35.75666 -285.945336) (xy 35.671531 -285.961413) (xy 35.585284 -285.96959)
			(xy 35.49865 -285.969799) (xy 35.412365 -285.962038) (xy 35.327159 -285.946372) (xy 35.243756 -285.922935)
			(xy 35.162863 -285.891926) (xy 35.085164 -285.853606) (xy 35.01132 -285.808302) (xy 34.941957 -285.756397)
			(xy 34.877662 -285.698332) (xy 34.818982 -285.634598) (xy 34.766413 -285.565737) (xy 34.720401 -285.492332)
			(xy 34.681336 -285.415006) (xy 34.64955 -285.334414) (xy 34.625313 -285.25124) (xy 34.608829 -285.166189)
			(xy 34.600239 -285.079982) (xy 34.599615 -284.993351) (xy 34.606963 -284.907029) (xy 34.614104 -284.864302)
			(xy 34.616389 -284.849149) (xy 34.61444 -284.818573) (xy 34.605242 -284.789349) (xy 34.589328 -284.763169)
			(xy 34.578798 -284.752034) (xy 32.117284 -282.290774) (xy 32.117284 -277.365714) (xy 31.370778 -276.619208)
			(xy 31.29534 -276.619208) (xy 31.278686 -276.61973) (xy 31.246512 -276.628342) (xy 31.217664 -276.64499)
			(xy 31.19411 -276.668539) (xy 31.177454 -276.697382) (xy 31.168834 -276.729554) (xy 31.16834 -276.746208)
			(xy 31.16834 -276.790404) (xy 31.196026 -276.824948) (xy 31.222839 -276.859516) (xy 31.270661 -276.93278)
			(xy 31.311471 -277.010168) (xy 31.344917 -277.091013) (xy 31.370708 -277.174616) (xy 31.388621 -277.260252)
			(xy 31.398503 -277.347182) (xy 31.400267 -277.434655) (xy 31.393899 -277.521913) (xy 31.379452 -277.608202)
			(xy 31.357053 -277.692776) (xy 31.326895 -277.774904) (xy 31.289238 -277.853875) (xy 31.244409 -277.929007)
			(xy 31.192795 -277.99965) (xy 31.134842 -278.065194) (xy 31.071051 -278.125071) (xy 31.001974 -278.178763)
			(xy 30.928208 -278.225807) (xy 30.850391 -278.265796) (xy 30.769197 -278.298383) (xy 30.685326 -278.323287)
			(xy 30.599505 -278.340293) (xy 30.512475 -278.349254) (xy 30.424989 -278.350092) (xy 30.337803 -278.3428)
			(xy 30.251672 -278.327441) (xy 30.16734 -278.304148) (xy 30.085536 -278.273122) (xy 30.006967 -278.234631)
			(xy 29.932314 -278.189009) (xy 29.862221 -278.136649) (xy 29.797295 -278.078005) (xy 29.738097 -278.013584)
			(xy 29.685139 -277.943943) (xy 29.638879 -277.869683) (xy 29.599716 -277.791447) (xy 29.56799 -277.709912)
			(xy 29.543975 -277.625783) (xy 29.527879 -277.539786) (xy 29.51984 -277.452666) (xy 29.519928 -277.365176)
			(xy 29.528143 -277.278073) (xy 29.544413 -277.192109) (xy 29.568598 -277.108028) (xy 29.600489 -277.026557)
			(xy 29.619702 -276.987254) (xy 29.629893 -276.966033) (xy 29.642957 -276.92081) (xy 29.647468 -276.873953)
			(xy 29.643271 -276.827068) (xy 29.630511 -276.781757) (xy 29.609622 -276.739573) (xy 29.581321 -276.701957)
			(xy 29.546576 -276.670198) (xy 29.506575 -276.645382) (xy 29.462688 -276.628359) (xy 29.416417 -276.61971)
			(xy 29.39288 -276.619208) (xy 26.8351 -276.619208) (xy 25.473914 -275.257768) (xy 24.557736 -275.257768)
			(xy 24.526122 -275.257243) (xy 24.463436 -275.24899) (xy 24.402363 -275.232625) (xy 24.343949 -275.208428)
			(xy 24.289193 -275.176814) (xy 24.239032 -275.138324) (xy 24.194323 -275.093615) (xy 24.155833 -275.043454)
			(xy 24.12422 -274.988697) (xy 24.100024 -274.930283) (xy 24.08366 -274.86921) (xy 24.075407 -274.806524)
			(xy 13.267322 -274.806524) (xy 11.116564 -276.957282) (xy 11.116564 -277.716488) (xy 11.088116 -277.744936)
			(xy 26.885136 -277.744936) (xy 26.889207 -277.689314) (xy 26.901333 -277.634877) (xy 26.921256 -277.582786)
			(xy 26.948552 -277.534151) (xy 26.982638 -277.490008) (xy 27.022787 -277.451299) (xy 27.068145 -277.418848)
			(xy 27.117745 -277.393347) (xy 27.170529 -277.37534) (xy 27.225372 -277.36521) (xy 27.281106 -277.363173)
			(xy 27.336543 -277.369273) (xy 27.3905 -277.383379) (xy 27.441829 -277.405191) (xy 27.489435 -277.434245)
			(xy 27.532303 -277.46992) (xy 27.56952 -277.511457) (xy 27.600293 -277.55797) (xy 27.623965 -277.608467)
			(xy 27.640033 -277.661874) (xy 27.648153 -277.71705) (xy 27.648662 -277.744936) (xy 27.648153 -277.772822)
			(xy 27.640033 -277.827998) (xy 27.623965 -277.881405) (xy 27.600293 -277.931902) (xy 27.56952 -277.978415)
			(xy 27.532303 -278.019952) (xy 27.489435 -278.055627) (xy 27.441829 -278.084681) (xy 27.3905 -278.106493)
			(xy 27.336543 -278.120599) (xy 27.281106 -278.126699) (xy 27.225372 -278.124662) (xy 27.170529 -278.114532)
			(xy 27.117745 -278.096525) (xy 27.068145 -278.071024) (xy 27.022787 -278.038573) (xy 26.982638 -277.999864)
			(xy 26.948552 -277.955721) (xy 26.921256 -277.907086) (xy 26.901333 -277.854995) (xy 26.889207 -277.800558)
			(xy 26.885136 -277.744936) (xy 11.088116 -277.744936) (xy 10.686542 -278.14651) (xy 10.57402 -278.259032)
			(xy 9.679178 -279.15362) (xy 9.283954 -279.15362) (xy 9.261027 -279.155558) (xy 9.216379 -279.166657)
			(xy 9.174456 -279.185605) (xy 9.136624 -279.211785) (xy 9.104119 -279.244344) (xy 9.078001 -279.282218)
			(xy 9.059121 -279.324172) (xy 9.048095 -279.368838) (xy 9.045284 -279.414759) (xy 9.050779 -279.460436)
			(xy 9.057132 -279.48255) (xy 9.066968 -279.516084) (xy 9.0801 -279.584727) (xy 9.085622 -279.654395)
			(xy 9.083469 -279.724249) (xy 9.073665 -279.793445) (xy 9.056329 -279.861148) (xy 9.031671 -279.926541)
			(xy 8.999988 -279.988834) (xy 8.99702 -279.99336) (xy 29.519874 -279.99336) (xy 29.519874 -279.90646)
			(xy 29.527892 -279.819931) (xy 29.54386 -279.734511) (xy 29.567641 -279.650929) (xy 29.599033 -279.569897)
			(xy 29.637767 -279.492108) (xy 29.683514 -279.418224) (xy 29.735883 -279.348877) (xy 29.794427 -279.284657)
			(xy 29.858647 -279.226113) (xy 29.927994 -279.173744) (xy 30.001878 -279.127997) (xy 30.079667 -279.089263)
			(xy 30.160699 -279.057871) (xy 30.244281 -279.03409) (xy 30.329701 -279.018122) (xy 30.41623 -279.010104)
			(xy 30.50313 -279.010104) (xy 30.589659 -279.018122) (xy 30.675079 -279.03409) (xy 30.758661 -279.057871)
			(xy 30.839693 -279.089263) (xy 30.917482 -279.127997) (xy 30.991366 -279.173744) (xy 31.060713 -279.226113)
			(xy 31.124933 -279.284657) (xy 31.183477 -279.348877) (xy 31.235846 -279.418224) (xy 31.281593 -279.492108)
			(xy 31.320327 -279.569897) (xy 31.351719 -279.650929) (xy 31.3755 -279.734511) (xy 31.391468 -279.819931)
			(xy 31.399486 -279.90646) (xy 31.399988 -279.94991) (xy 31.399486 -279.99336) (xy 31.391468 -280.079889)
			(xy 31.3755 -280.165309) (xy 31.351719 -280.248891) (xy 31.320327 -280.329923) (xy 31.281593 -280.407712)
			(xy 31.235846 -280.481596) (xy 31.183477 -280.550943) (xy 31.124933 -280.615163) (xy 31.060713 -280.673707)
			(xy 30.991366 -280.726076) (xy 30.917482 -280.771823) (xy 30.839693 -280.810557) (xy 30.758661 -280.841949)
			(xy 30.675079 -280.86573) (xy 30.589659 -280.881698) (xy 30.50313 -280.889716) (xy 30.41623 -280.889716)
			(xy 30.329701 -280.881698) (xy 30.244281 -280.86573) (xy 30.160699 -280.841949) (xy 30.079667 -280.810557)
			(xy 30.001878 -280.771823) (xy 29.927994 -280.726076) (xy 29.858647 -280.673707) (xy 29.794427 -280.615163)
			(xy 29.735883 -280.550943) (xy 29.683514 -280.481596) (xy 29.637767 -280.407712) (xy 29.599033 -280.329923)
			(xy 29.567641 -280.248891) (xy 29.54386 -280.165309) (xy 29.527892 -280.079889) (xy 29.519874 -279.99336)
			(xy 8.99702 -279.99336) (xy 8.961662 -280.047275) (xy 8.917157 -280.101159) (xy 8.867009 -280.149835)
			(xy 8.839708 -280.171652) (xy 8.821496 -280.186458) (xy 8.790323 -280.221538) (xy 8.766122 -280.261745)
			(xy 8.749716 -280.305714) (xy 8.741665 -280.351948) (xy 8.742241 -280.398873) (xy 8.751425 -280.444895)
			(xy 8.768905 -280.488448) (xy 8.794086 -280.52805) (xy 8.809736 -280.54554) (xy 9.127236 -280.86304)
			(xy 27.247848 -280.86304) (xy 27.251919 -280.807418) (xy 27.264045 -280.752981) (xy 27.283968 -280.70089)
			(xy 27.311264 -280.652255) (xy 27.34535 -280.608112) (xy 27.385499 -280.569403) (xy 27.430857 -280.536952)
			(xy 27.480457 -280.511451) (xy 27.533241 -280.493444) (xy 27.588084 -280.483314) (xy 27.643818 -280.481277)
			(xy 27.699255 -280.487377) (xy 27.753212 -280.501483) (xy 27.804541 -280.523295) (xy 27.852147 -280.552349)
			(xy 27.895015 -280.588024) (xy 27.932232 -280.629561) (xy 27.963005 -280.676074) (xy 27.986677 -280.726571)
			(xy 28.002745 -280.779978) (xy 28.010865 -280.835154) (xy 28.011374 -280.86304) (xy 28.010865 -280.890926)
			(xy 28.002745 -280.946102) (xy 27.986677 -280.999509) (xy 27.963005 -281.050006) (xy 27.932232 -281.096519)
			(xy 27.895015 -281.138056) (xy 27.852147 -281.173731) (xy 27.804541 -281.202785) (xy 27.753212 -281.224597)
			(xy 27.699255 -281.238703) (xy 27.643818 -281.244803) (xy 27.588084 -281.242766) (xy 27.533241 -281.232636)
			(xy 27.480457 -281.214629) (xy 27.430857 -281.189128) (xy 27.385499 -281.156677) (xy 27.34535 -281.117968)
			(xy 27.311264 -281.073825) (xy 27.283968 -281.02519) (xy 27.264045 -280.973099) (xy 27.251919 -280.918662)
			(xy 27.247848 -280.86304) (xy 9.127236 -280.86304) (xy 10.797556 -282.53336) (xy 29.519874 -282.53336)
			(xy 29.519874 -282.44646) (xy 29.527892 -282.359931) (xy 29.54386 -282.274511) (xy 29.567641 -282.190929)
			(xy 29.599033 -282.109897) (xy 29.637767 -282.032108) (xy 29.683514 -281.958224) (xy 29.735883 -281.888877)
			(xy 29.794427 -281.824657) (xy 29.858647 -281.766113) (xy 29.927994 -281.713744) (xy 30.001878 -281.667997)
			(xy 30.079667 -281.629263) (xy 30.160699 -281.597871) (xy 30.244281 -281.57409) (xy 30.329701 -281.558122)
			(xy 30.41623 -281.550104) (xy 30.50313 -281.550104) (xy 30.589659 -281.558122) (xy 30.675079 -281.57409)
			(xy 30.758661 -281.597871) (xy 30.839693 -281.629263) (xy 30.917482 -281.667997) (xy 30.991366 -281.713744)
			(xy 31.060713 -281.766113) (xy 31.124933 -281.824657) (xy 31.183477 -281.888877) (xy 31.235846 -281.958224)
			(xy 31.281593 -282.032108) (xy 31.320327 -282.109897) (xy 31.351719 -282.190929) (xy 31.3755 -282.274511)
			(xy 31.391468 -282.359931) (xy 31.399486 -282.44646) (xy 31.399988 -282.48991) (xy 31.399486 -282.53336)
			(xy 31.391468 -282.619889) (xy 31.3755 -282.705309) (xy 31.351719 -282.788891) (xy 31.320327 -282.869923)
			(xy 31.281593 -282.947712) (xy 31.235846 -283.021596) (xy 31.183477 -283.090943) (xy 31.124933 -283.155163)
			(xy 31.060713 -283.213707) (xy 30.991366 -283.266076) (xy 30.917482 -283.311823) (xy 30.839693 -283.350557)
			(xy 30.758661 -283.381949) (xy 30.675079 -283.40573) (xy 30.589659 -283.421698) (xy 30.50313 -283.429716)
			(xy 30.41623 -283.429716) (xy 30.329701 -283.421698) (xy 30.244281 -283.40573) (xy 30.160699 -283.381949)
			(xy 30.079667 -283.350557) (xy 30.001878 -283.311823) (xy 29.927994 -283.266076) (xy 29.858647 -283.213707)
			(xy 29.794427 -283.155163) (xy 29.735883 -283.090943) (xy 29.683514 -283.021596) (xy 29.637767 -282.947712)
			(xy 29.599033 -282.869923) (xy 29.567641 -282.788891) (xy 29.54386 -282.705309) (xy 29.527892 -282.619889)
			(xy 29.519874 -282.53336) (xy 10.797556 -282.53336) (xy 11.238992 -282.974796) (xy 22.838918 -282.974796)
			(xy 23.292562 -283.42844) (xy 28.193744 -283.42844) (xy 28.197815 -283.372818) (xy 28.209941 -283.318381)
			(xy 28.229864 -283.26629) (xy 28.25716 -283.217655) (xy 28.291246 -283.173512) (xy 28.331395 -283.134803)
			(xy 28.376753 -283.102352) (xy 28.426353 -283.076851) (xy 28.479137 -283.058844) (xy 28.53398 -283.048714)
			(xy 28.589714 -283.046677) (xy 28.645151 -283.052777) (xy 28.699108 -283.066883) (xy 28.750437 -283.088695)
			(xy 28.798043 -283.117749) (xy 28.840911 -283.153424) (xy 28.878128 -283.194961) (xy 28.908901 -283.241474)
			(xy 28.932573 -283.291971) (xy 28.948641 -283.345378) (xy 28.956761 -283.400554) (xy 28.95727 -283.42844)
			(xy 28.956761 -283.456326) (xy 28.948641 -283.511502) (xy 28.932573 -283.564909) (xy 28.908901 -283.615406)
			(xy 28.878128 -283.661919) (xy 28.840911 -283.703456) (xy 28.798043 -283.739131) (xy 28.750437 -283.768185)
			(xy 28.699108 -283.789997) (xy 28.645151 -283.804103) (xy 28.589714 -283.810203) (xy 28.53398 -283.808166)
			(xy 28.479137 -283.798036) (xy 28.426353 -283.780029) (xy 28.376753 -283.754528) (xy 28.331395 -283.722077)
			(xy 28.291246 -283.683368) (xy 28.25716 -283.639225) (xy 28.229864 -283.59059) (xy 28.209941 -283.538499)
			(xy 28.197815 -283.484062) (xy 28.193744 -283.42844) (xy 23.292562 -283.42844) (xy 23.932896 -284.068774)
			(xy 26.32659 -284.068774) (xy 26.330661 -284.013152) (xy 26.342787 -283.958715) (xy 26.36271 -283.906624)
			(xy 26.390006 -283.857989) (xy 26.424092 -283.813846) (xy 26.464241 -283.775137) (xy 26.509599 -283.742686)
			(xy 26.559199 -283.717185) (xy 26.611983 -283.699178) (xy 26.666826 -283.689048) (xy 26.72256 -283.687011)
			(xy 26.777997 -283.693111) (xy 26.831954 -283.707217) (xy 26.883283 -283.729029) (xy 26.930889 -283.758083)
			(xy 26.973757 -283.793758) (xy 27.010974 -283.835295) (xy 27.041747 -283.881808) (xy 27.065419 -283.932305)
			(xy 27.081487 -283.985712) (xy 27.089607 -284.040888) (xy 27.090116 -284.068774) (xy 27.089607 -284.09666)
			(xy 27.081487 -284.151836) (xy 27.065419 -284.205243) (xy 27.041747 -284.25574) (xy 27.010974 -284.302253)
			(xy 26.973757 -284.34379) (xy 26.930889 -284.379465) (xy 26.883283 -284.408519) (xy 26.831954 -284.430331)
			(xy 26.777997 -284.444437) (xy 26.72256 -284.450537) (xy 26.666826 -284.4485) (xy 26.611983 -284.43837)
			(xy 26.559199 -284.420363) (xy 26.509599 -284.394862) (xy 26.464241 -284.362411) (xy 26.424092 -284.323702)
			(xy 26.390006 -284.279559) (xy 26.36271 -284.230924) (xy 26.342787 -284.178833) (xy 26.330661 -284.124396)
			(xy 26.32659 -284.068774) (xy 23.932896 -284.068774) (xy 24.937482 -285.07336) (xy 29.519874 -285.07336)
			(xy 29.519874 -284.98646) (xy 29.527892 -284.899931) (xy 29.54386 -284.814511) (xy 29.567641 -284.730929)
			(xy 29.599033 -284.649897) (xy 29.637767 -284.572108) (xy 29.683514 -284.498224) (xy 29.735883 -284.428877)
			(xy 29.794427 -284.364657) (xy 29.858647 -284.306113) (xy 29.927994 -284.253744) (xy 30.001878 -284.207997)
			(xy 30.079667 -284.169263) (xy 30.160699 -284.137871) (xy 30.244281 -284.11409) (xy 30.329701 -284.098122)
			(xy 30.41623 -284.090104) (xy 30.50313 -284.090104) (xy 30.589659 -284.098122) (xy 30.675079 -284.11409)
			(xy 30.758661 -284.137871) (xy 30.839693 -284.169263) (xy 30.917482 -284.207997) (xy 30.991366 -284.253744)
			(xy 31.060713 -284.306113) (xy 31.124933 -284.364657) (xy 31.183477 -284.428877) (xy 31.235846 -284.498224)
			(xy 31.281593 -284.572108) (xy 31.320327 -284.649897) (xy 31.351719 -284.730929) (xy 31.3755 -284.814511)
			(xy 31.391468 -284.899931) (xy 31.399486 -284.98646) (xy 31.399988 -285.02991) (xy 31.399486 -285.07336)
			(xy 31.391468 -285.159889) (xy 31.3755 -285.245309) (xy 31.351719 -285.328891) (xy 31.320327 -285.409923)
			(xy 31.281593 -285.487712) (xy 31.235846 -285.561596) (xy 31.183477 -285.630943) (xy 31.124933 -285.695163)
			(xy 31.060713 -285.753707) (xy 30.991366 -285.806076) (xy 30.917482 -285.851823) (xy 30.839693 -285.890557)
			(xy 30.758661 -285.921949) (xy 30.675079 -285.94573) (xy 30.589659 -285.961698) (xy 30.50313 -285.969716)
			(xy 30.41623 -285.969716) (xy 30.329701 -285.961698) (xy 30.244281 -285.94573) (xy 30.160699 -285.921949)
			(xy 30.079667 -285.890557) (xy 30.001878 -285.851823) (xy 29.927994 -285.806076) (xy 29.858647 -285.753707)
			(xy 29.794427 -285.695163) (xy 29.735883 -285.630943) (xy 29.683514 -285.561596) (xy 29.637767 -285.487712)
			(xy 29.599033 -285.409923) (xy 29.567641 -285.328891) (xy 29.54386 -285.245309) (xy 29.527892 -285.159889)
			(xy 29.519874 -285.07336) (xy 24.937482 -285.07336) (xy 26.749756 -286.885634) (xy 26.765995 -286.901185)
			(xy 26.80289 -286.926875) (xy 26.843729 -286.945673) (xy 26.887239 -286.956991) (xy 26.932062 -286.960476)
			(xy 26.976798 -286.956019) (xy 27.020052 -286.943759) (xy 27.060474 -286.92408) (xy 27.096802 -286.897595)
			(xy 27.127903 -286.86513) (xy 27.152806 -286.827699) (xy 27.170733 -286.78647) (xy 27.176476 -286.76473)
			(xy 27.182272 -286.737834) (xy 27.200562 -286.685946) (xy 27.226113 -286.637221) (xy 27.258396 -286.592671)
			(xy 27.296741 -286.553217) (xy 27.340355 -286.519679) (xy 27.388332 -286.492751) (xy 27.439679 -286.472991)
			(xy 27.493331 -286.460809) (xy 27.548176 -286.456458) (xy 27.603078 -286.460027) (xy 27.656898 -286.471443)
			(xy 27.708521 -286.490469) (xy 27.756878 -286.51671) (xy 27.800965 -286.549623) (xy 27.839869 -286.588526)
			(xy 27.872783 -286.632612) (xy 27.899026 -286.680967) (xy 27.918054 -286.73259) (xy 27.929471 -286.78641)
			(xy 27.933042 -286.841311) (xy 27.928693 -286.896157) (xy 27.916513 -286.949809) (xy 27.896755 -287.001157)
			(xy 27.869828 -287.049135) (xy 27.836291 -287.092749) (xy 27.796839 -287.131096) (xy 27.752289 -287.16338)
			(xy 27.703566 -287.188933) (xy 27.651678 -287.207224) (xy 27.624786 -287.21304) (xy 27.603021 -287.2187)
			(xy 27.561778 -287.236621) (xy 27.524334 -287.261522) (xy 27.491859 -287.292627) (xy 27.465367 -287.328963)
			(xy 27.445686 -287.369396) (xy 27.433431 -287.412662) (xy 27.428983 -287.457409) (xy 27.432483 -287.502241)
			(xy 27.443821 -287.545756) (xy 27.462643 -287.586596) (xy 27.481302 -287.61336) (xy 29.519874 -287.61336)
			(xy 29.519874 -287.52646) (xy 29.527892 -287.439931) (xy 29.54386 -287.354511) (xy 29.567641 -287.270929)
			(xy 29.599033 -287.189897) (xy 29.637767 -287.112108) (xy 29.683514 -287.038224) (xy 29.735883 -286.968877)
			(xy 29.794427 -286.904657) (xy 29.858647 -286.846113) (xy 29.927994 -286.793744) (xy 30.001878 -286.747997)
			(xy 30.079667 -286.709263) (xy 30.160699 -286.677871) (xy 30.244281 -286.65409) (xy 30.329701 -286.638122)
			(xy 30.41623 -286.630104) (xy 30.50313 -286.630104) (xy 30.589659 -286.638122) (xy 30.675079 -286.65409)
			(xy 30.758661 -286.677871) (xy 30.839693 -286.709263) (xy 30.917482 -286.747997) (xy 30.991366 -286.793744)
			(xy 31.060713 -286.846113) (xy 31.124933 -286.904657) (xy 31.183477 -286.968877) (xy 31.235846 -287.038224)
			(xy 31.281593 -287.112108) (xy 31.320327 -287.189897) (xy 31.351719 -287.270929) (xy 31.3755 -287.354511)
			(xy 31.391468 -287.439931) (xy 31.399486 -287.52646) (xy 31.399988 -287.56991) (xy 31.399486 -287.61336)
			(xy 34.599874 -287.61336) (xy 34.599874 -287.52646) (xy 34.607892 -287.439931) (xy 34.62386 -287.354511)
			(xy 34.647641 -287.270929) (xy 34.679033 -287.189897) (xy 34.717767 -287.112108) (xy 34.763514 -287.038224)
			(xy 34.815883 -286.968877) (xy 34.874427 -286.904657) (xy 34.938647 -286.846113) (xy 35.007994 -286.793744)
			(xy 35.081878 -286.747997) (xy 35.159667 -286.709263) (xy 35.240699 -286.677871) (xy 35.324281 -286.65409)
			(xy 35.409701 -286.638122) (xy 35.49623 -286.630104) (xy 35.58313 -286.630104) (xy 35.669659 -286.638122)
			(xy 35.755079 -286.65409) (xy 35.838661 -286.677871) (xy 35.919693 -286.709263) (xy 35.997482 -286.747997)
			(xy 36.045018 -286.77743) (xy 39.865806 -286.77743) (xy 39.869877 -286.721808) (xy 39.882003 -286.667371)
			(xy 39.901926 -286.61528) (xy 39.929222 -286.566645) (xy 39.963308 -286.522502) (xy 40.003457 -286.483793)
			(xy 40.048815 -286.451342) (xy 40.098415 -286.425841) (xy 40.151199 -286.407834) (xy 40.206042 -286.397704)
			(xy 40.261776 -286.395667) (xy 40.317213 -286.401767) (xy 40.37117 -286.415873) (xy 40.422499 -286.437685)
			(xy 40.470105 -286.466739) (xy 40.512973 -286.502414) (xy 40.55019 -286.543951) (xy 40.580963 -286.590464)
			(xy 40.604635 -286.640961) (xy 40.620703 -286.694368) (xy 40.628823 -286.749544) (xy 40.629332 -286.77743)
			(xy 40.628823 -286.805316) (xy 40.620703 -286.860492) (xy 40.604635 -286.913899) (xy 40.580963 -286.964396)
			(xy 40.55019 -287.010909) (xy 40.512973 -287.052446) (xy 40.470105 -287.088121) (xy 40.422499 -287.117175)
			(xy 40.37117 -287.138987) (xy 40.317213 -287.153093) (xy 40.261776 -287.159193) (xy 40.206042 -287.157156)
			(xy 40.151199 -287.147026) (xy 40.098415 -287.129019) (xy 40.048815 -287.103518) (xy 40.003457 -287.071067)
			(xy 39.963308 -287.032358) (xy 39.929222 -286.988215) (xy 39.901926 -286.93958) (xy 39.882003 -286.887489)
			(xy 39.869877 -286.833052) (xy 39.865806 -286.77743) (xy 36.045018 -286.77743) (xy 36.071366 -286.793744)
			(xy 36.140713 -286.846113) (xy 36.204933 -286.904657) (xy 36.263477 -286.968877) (xy 36.315846 -287.038224)
			(xy 36.361593 -287.112108) (xy 36.400327 -287.189897) (xy 36.431719 -287.270929) (xy 36.4555 -287.354511)
			(xy 36.471468 -287.439931) (xy 36.479486 -287.52646) (xy 36.479988 -287.56991) (xy 36.479486 -287.61336)
			(xy 36.471468 -287.699889) (xy 36.4555 -287.785309) (xy 36.431719 -287.868891) (xy 36.400327 -287.949923)
			(xy 36.361593 -288.027712) (xy 36.315846 -288.101596) (xy 36.263477 -288.170943) (xy 36.204933 -288.235163)
			(xy 36.140713 -288.293707) (xy 36.071366 -288.346076) (xy 35.997482 -288.391823) (xy 35.919693 -288.430557)
			(xy 35.838661 -288.461949) (xy 35.755079 -288.48573) (xy 35.669659 -288.501698) (xy 35.58313 -288.509716)
			(xy 35.49623 -288.509716) (xy 35.409701 -288.501698) (xy 35.324281 -288.48573) (xy 35.240699 -288.461949)
			(xy 35.159667 -288.430557) (xy 35.081878 -288.391823) (xy 35.007994 -288.346076) (xy 34.938647 -288.293707)
			(xy 34.874427 -288.235163) (xy 34.815883 -288.170943) (xy 34.763514 -288.101596) (xy 34.717767 -288.027712)
			(xy 34.679033 -287.949923) (xy 34.647641 -287.868891) (xy 34.62386 -287.785309) (xy 34.607892 -287.699889)
			(xy 34.599874 -287.61336) (xy 31.399486 -287.61336) (xy 31.391468 -287.699889) (xy 31.3755 -287.785309)
			(xy 31.351719 -287.868891) (xy 31.320327 -287.949923) (xy 31.281593 -288.027712) (xy 31.235846 -288.101596)
			(xy 31.183477 -288.170943) (xy 31.124933 -288.235163) (xy 31.060713 -288.293707) (xy 30.991366 -288.346076)
			(xy 30.917482 -288.391823) (xy 30.839693 -288.430557) (xy 30.758661 -288.461949) (xy 30.675079 -288.48573)
			(xy 30.589659 -288.501698) (xy 30.50313 -288.509716) (xy 30.41623 -288.509716) (xy 30.329701 -288.501698)
			(xy 30.244281 -288.48573) (xy 30.160699 -288.461949) (xy 30.079667 -288.430557) (xy 30.001878 -288.391823)
			(xy 29.927994 -288.346076) (xy 29.858647 -288.293707) (xy 29.794427 -288.235163) (xy 29.735883 -288.170943)
			(xy 29.683514 -288.101596) (xy 29.637767 -288.027712) (xy 29.599033 -287.949923) (xy 29.567641 -287.868891)
			(xy 29.54386 -287.785309) (xy 29.527892 -287.699889) (xy 29.519874 -287.61336) (xy 27.481302 -287.61336)
			(xy 27.48836 -287.623484) (xy 27.503882 -287.63976) (xy 28.446476 -288.582354) (xy 40.10101 -288.582354)
			(xy 40.105081 -288.526732) (xy 40.117207 -288.472295) (xy 40.13713 -288.420204) (xy 40.164426 -288.371569)
			(xy 40.198512 -288.327426) (xy 40.238661 -288.288717) (xy 40.284019 -288.256266) (xy 40.333619 -288.230765)
			(xy 40.386403 -288.212758) (xy 40.441246 -288.202628) (xy 40.49698 -288.200591) (xy 40.552417 -288.206691)
			(xy 40.606374 -288.220797) (xy 40.657703 -288.242609) (xy 40.705309 -288.271663) (xy 40.748177 -288.307338)
			(xy 40.785394 -288.348875) (xy 40.816167 -288.395388) (xy 40.81617 -288.395394) (xy 58.7262 -288.395394)
			(xy 58.730088 -288.341042) (xy 58.741672 -288.287797) (xy 58.760716 -288.236743) (xy 58.786832 -288.188918)
			(xy 58.819489 -288.145297) (xy 58.858021 -288.106768) (xy 58.901645 -288.074115) (xy 58.949472 -288.048003)
			(xy 59.000528 -288.028963) (xy 59.053774 -288.017384) (xy 59.108126 -288.0135) (xy 59.162478 -288.017391)
			(xy 59.215722 -288.028978) (xy 59.266776 -288.048025) (xy 59.314599 -288.074143) (xy 59.336686 -288.090102)
			(xy 59.355698 -288.103698) (xy 59.397581 -288.12443) (xy 59.442549 -288.137156) (xy 59.489086 -288.141446)
			(xy 59.535623 -288.137156) (xy 59.580591 -288.12443) (xy 59.622474 -288.103698) (xy 59.641486 -288.090102)
			(xy 59.663565 -288.074127) (xy 59.711392 -288.048003) (xy 59.76245 -288.028952) (xy 59.8157 -288.017361)
			(xy 59.870058 -288.013467) (xy 59.924416 -288.017349) (xy 59.977669 -288.028928) (xy 60.028731 -288.047968)
			(xy 60.076564 -288.074082) (xy 60.120193 -288.106738) (xy 60.158731 -288.14527) (xy 60.191392 -288.188895)
			(xy 60.217512 -288.236725) (xy 60.236558 -288.287785) (xy 60.248144 -288.341036) (xy 60.252033 -288.395394)
			(xy 61.258117 -288.395394) (xy 61.262005 -288.341046) (xy 61.273588 -288.287805) (xy 61.29263 -288.236753)
			(xy 61.318743 -288.188932) (xy 61.351397 -288.145314) (xy 61.389926 -288.106786) (xy 61.433546 -288.074135)
			(xy 61.481368 -288.048023) (xy 61.53242 -288.028983) (xy 61.585662 -288.017402) (xy 61.64001 -288.013517)
			(xy 61.694358 -288.017405) (xy 61.747599 -288.028989) (xy 61.79865 -288.048031) (xy 61.846472 -288.074146)
			(xy 61.868558 -288.090102) (xy 61.88757 -288.103698) (xy 61.929453 -288.12443) (xy 61.974421 -288.137156)
			(xy 62.020958 -288.141446) (xy 62.067495 -288.137156) (xy 62.112463 -288.12443) (xy 62.154346 -288.103698)
			(xy 62.173358 -288.090102) (xy 62.195438 -288.074125) (xy 62.243267 -288.047996) (xy 62.294328 -288.028941)
			(xy 62.347581 -288.017347) (xy 62.401942 -288.01345) (xy 62.456304 -288.01733) (xy 62.509561 -288.028908)
			(xy 62.560628 -288.047948) (xy 62.608465 -288.074062) (xy 62.652098 -288.106719) (xy 62.690639 -288.145254)
			(xy 62.723303 -288.188881) (xy 62.749425 -288.236714) (xy 62.768474 -288.287778) (xy 62.78006 -288.341032)
			(xy 62.78133 -288.35878) (xy 63.482121 -288.35878) (xy 63.486012 -288.304431) (xy 63.497597 -288.25119)
			(xy 63.516642 -288.200139) (xy 63.542758 -288.152318) (xy 63.575414 -288.108701) (xy 63.613946 -288.070176)
			(xy 63.657568 -288.037526) (xy 63.705392 -288.011417) (xy 63.756446 -287.99238) (xy 63.809689 -287.980803)
			(xy 63.864038 -287.976921) (xy 63.918386 -287.980814) (xy 63.971627 -287.992402) (xy 64.022677 -288.011449)
			(xy 64.070497 -288.037568) (xy 64.092582 -288.053526) (xy 64.111594 -288.067122) (xy 64.153477 -288.087854)
			(xy 64.198445 -288.10058) (xy 64.244982 -288.10487) (xy 64.291519 -288.10058) (xy 64.336487 -288.087854)
			(xy 64.37837 -288.067122) (xy 64.397382 -288.053526) (xy 64.419439 -288.037519) (xy 64.467267 -288.011391)
			(xy 64.518328 -287.992336) (xy 64.571581 -287.980742) (xy 64.625941 -287.976845) (xy 64.680303 -287.980725)
			(xy 64.733559 -287.992303) (xy 64.784626 -288.011342) (xy 64.832463 -288.037455) (xy 64.876096 -288.070111)
			(xy 64.914637 -288.108644) (xy 64.947302 -288.152271) (xy 64.973425 -288.200102) (xy 64.992475 -288.251165)
			(xy 65.004063 -288.304419) (xy 65.005357 -288.322493) (xy 65.778168 -288.322493) (xy 65.782057 -288.268134)
			(xy 65.793644 -288.214881) (xy 65.812691 -288.16382) (xy 65.838812 -288.11599) (xy 65.871475 -288.072364)
			(xy 65.910015 -288.033832) (xy 65.953646 -288.001177) (xy 66.001481 -287.975064) (xy 66.052545 -287.956025)
			(xy 66.105799 -287.944448) (xy 66.160159 -287.940568) (xy 66.214518 -287.944465) (xy 66.267769 -287.956058)
			(xy 66.318827 -287.975113) (xy 66.366654 -288.00124) (xy 66.388742 -288.017204) (xy 66.407754 -288.0308)
			(xy 66.449637 -288.051532) (xy 66.494605 -288.064258) (xy 66.541142 -288.068548) (xy 66.587679 -288.064258)
			(xy 66.632647 -288.051532) (xy 66.67453 -288.0308) (xy 66.693542 -288.017204) (xy 66.715618 -288.001231)
			(xy 66.763441 -287.975116) (xy 66.814494 -287.956072) (xy 66.867738 -287.944488) (xy 66.922089 -287.940599)
			(xy 66.976439 -287.944485) (xy 67.029684 -287.956066) (xy 67.080738 -287.975106) (xy 67.128563 -288.001219)
			(xy 67.172185 -288.033872) (xy 67.210716 -288.072401) (xy 67.243371 -288.116021) (xy 67.269486 -288.163845)
			(xy 67.288529 -288.214898) (xy 67.300113 -288.268142) (xy 67.301417 -288.286374) (xy 68.152598 -288.286374)
			(xy 68.15649 -288.232019) (xy 68.168078 -288.178772) (xy 68.187126 -288.127717) (xy 68.213247 -288.079892)
			(xy 68.245909 -288.036271) (xy 68.284447 -287.997744) (xy 68.328076 -287.965093) (xy 68.375908 -287.938985)
			(xy 68.426968 -287.91995) (xy 68.480218 -287.908376) (xy 68.534574 -287.904498) (xy 68.588928 -287.908397)
			(xy 68.642173 -287.919991) (xy 68.693227 -287.939046) (xy 68.741048 -287.965173) (xy 68.763134 -287.981136)
			(xy 68.782146 -287.994732) (xy 68.824029 -288.015464) (xy 68.868997 -288.02819) (xy 68.915534 -288.03248)
			(xy 68.962071 -288.02819) (xy 69.007039 -288.015464) (xy 69.048922 -287.994732) (xy 69.067934 -287.981136)
			(xy 69.08998 -287.96512) (xy 69.137806 -287.938999) (xy 69.188862 -287.91995) (xy 69.24211 -287.908361)
			(xy 69.296465 -287.904469) (xy 69.350821 -287.908351) (xy 69.40407 -287.91993) (xy 69.45513 -287.938969)
			(xy 69.502961 -287.965082) (xy 69.546588 -287.997735) (xy 69.585125 -288.036265) (xy 69.617785 -288.079887)
			(xy 69.643905 -288.127714) (xy 69.662953 -288.178771) (xy 69.67454 -288.232019) (xy 69.678431 -288.286374)
			(xy 69.674548 -288.340729) (xy 69.662967 -288.393979) (xy 69.643927 -288.445038) (xy 69.617814 -288.492868)
			(xy 69.585159 -288.536495) (xy 69.546628 -288.57503) (xy 69.503005 -288.60769) (xy 69.455178 -288.633809)
			(xy 69.404121 -288.652855) (xy 69.350873 -288.664441) (xy 69.296518 -288.668331) (xy 69.242162 -288.664446)
			(xy 69.188913 -288.652865) (xy 69.137854 -288.633823) (xy 69.090025 -288.607709) (xy 69.067934 -288.591752)
			(xy 69.048922 -288.578156) (xy 69.007039 -288.557424) (xy 68.962071 -288.544698) (xy 68.915534 -288.540408)
			(xy 68.868997 -288.544698) (xy 68.824029 -288.557424) (xy 68.782146 -288.578156) (xy 68.763134 -288.591752)
			(xy 68.741004 -288.607655) (xy 68.693179 -288.633776) (xy 68.642123 -288.652824) (xy 68.588875 -288.664411)
			(xy 68.534521 -288.668302) (xy 68.480166 -288.664417) (xy 68.426918 -288.652835) (xy 68.37586 -288.633793)
			(xy 68.328032 -288.607678) (xy 68.284407 -288.575022) (xy 68.245875 -288.536489) (xy 68.213219 -288.492864)
			(xy 68.187104 -288.445035) (xy 68.168063 -288.393977) (xy 68.156482 -288.340728) (xy 68.152598 -288.286374)
			(xy 67.301417 -288.286374) (xy 67.304001 -288.322493) (xy 67.300115 -288.376843) (xy 67.288533 -288.430088)
			(xy 67.269492 -288.481142) (xy 67.243379 -288.528966) (xy 67.210725 -288.572588) (xy 67.172196 -288.611118)
			(xy 67.128575 -288.643773) (xy 67.080751 -288.669888) (xy 67.029698 -288.68893) (xy 66.976454 -288.700513)
			(xy 66.922103 -288.704401) (xy 66.867752 -288.700514) (xy 66.814508 -288.688932) (xy 66.763454 -288.66989)
			(xy 66.71563 -288.643776) (xy 66.693542 -288.62782) (xy 66.67453 -288.614224) (xy 66.632647 -288.593492)
			(xy 66.587679 -288.580766) (xy 66.541142 -288.576476) (xy 66.494605 -288.580766) (xy 66.449637 -288.593492)
			(xy 66.407754 -288.614224) (xy 66.388742 -288.62782) (xy 66.366642 -288.643767) (xy 66.318814 -288.669893)
			(xy 66.267755 -288.688946) (xy 66.214504 -288.700538) (xy 66.160145 -288.704432) (xy 66.105785 -288.70055)
			(xy 66.052531 -288.688971) (xy 66.001467 -288.66993) (xy 65.953634 -288.643816) (xy 65.910004 -288.611159)
			(xy 65.871466 -288.572625) (xy 65.838805 -288.528998) (xy 65.812685 -288.481167) (xy 65.793639 -288.430105)
			(xy 65.782055 -288.376852) (xy 65.778168 -288.322493) (xy 65.005357 -288.322493) (xy 65.007955 -288.35878)
			(xy 65.004069 -288.413141) (xy 64.992486 -288.466396) (xy 64.973442 -288.517461) (xy 64.947324 -288.565295)
			(xy 64.914664 -288.608925) (xy 64.876127 -288.647462) (xy 64.832497 -288.680123) (xy 64.784663 -288.706241)
			(xy 64.733599 -288.725286) (xy 64.680344 -288.736869) (xy 64.625982 -288.740755) (xy 64.571621 -288.736864)
			(xy 64.518367 -288.725276) (xy 64.467305 -288.706226) (xy 64.419473 -288.680103) (xy 64.397382 -288.664142)
			(xy 64.37837 -288.650546) (xy 64.336487 -288.629814) (xy 64.291519 -288.617088) (xy 64.244982 -288.612798)
			(xy 64.198445 -288.617088) (xy 64.153477 -288.629814) (xy 64.111594 -288.650546) (xy 64.092582 -288.664142)
			(xy 64.070462 -288.680055) (xy 64.02264 -288.706168) (xy 63.971588 -288.72521) (xy 63.918346 -288.736792)
			(xy 63.863997 -288.740679) (xy 63.809649 -288.736791) (xy 63.756407 -288.725208) (xy 63.705355 -288.706166)
			(xy 63.657533 -288.680052) (xy 63.613915 -288.647398) (xy 63.575387 -288.608868) (xy 63.542736 -288.565247)
			(xy 63.516625 -288.517424) (xy 63.497585 -288.466371) (xy 63.486006 -288.413128) (xy 63.482121 -288.35878)
			(xy 62.78133 -288.35878) (xy 62.78395 -288.395394) (xy 62.780062 -288.449756) (xy 62.768477 -288.503011)
			(xy 62.74943 -288.554075) (xy 62.72331 -288.601908) (xy 62.690647 -288.645537) (xy 62.652107 -288.684073)
			(xy 62.608475 -288.716731) (xy 62.560639 -288.742847) (xy 62.509573 -288.761888) (xy 62.456316 -288.773468)
			(xy 62.401954 -288.77735) (xy 62.347593 -288.773455) (xy 62.294339 -288.761862) (xy 62.243278 -288.742809)
			(xy 62.195448 -288.716681) (xy 62.173358 -288.700718) (xy 62.154346 -288.687122) (xy 62.112463 -288.66639)
			(xy 62.067495 -288.653664) (xy 62.020958 -288.649374) (xy 61.974421 -288.653664) (xy 61.929453 -288.66639)
			(xy 61.88757 -288.687122) (xy 61.868558 -288.700718) (xy 61.846461 -288.716661) (xy 61.798639 -288.742774)
			(xy 61.747588 -288.761815) (xy 61.694346 -288.773397) (xy 61.639998 -288.777283) (xy 61.58565 -288.773396)
			(xy 61.532409 -288.761814) (xy 61.481357 -288.742772) (xy 61.433535 -288.716659) (xy 61.389917 -288.684006)
			(xy 61.351389 -288.645477) (xy 61.318737 -288.601858) (xy 61.292625 -288.554036) (xy 61.273584 -288.502984)
			(xy 61.262003 -288.449742) (xy 61.258117 -288.395394) (xy 60.252033 -288.395394) (xy 60.248146 -288.449752)
			(xy 60.236562 -288.503003) (xy 60.217517 -288.554064) (xy 60.191399 -288.601894) (xy 60.158739 -288.645521)
			(xy 60.120203 -288.684055) (xy 60.076574 -288.716712) (xy 60.028742 -288.742827) (xy 59.97768 -288.761869)
			(xy 59.924428 -288.773449) (xy 59.87007 -288.777333) (xy 59.815712 -288.773441) (xy 59.762462 -288.761852)
			(xy 59.711403 -288.742802) (xy 59.663575 -288.716679) (xy 59.641486 -288.700718) (xy 59.622474 -288.687122)
			(xy 59.580591 -288.66639) (xy 59.535623 -288.653664) (xy 59.489086 -288.649374) (xy 59.442549 -288.653664)
			(xy 59.397581 -288.66639) (xy 59.355698 -288.687122) (xy 59.336686 -288.700718) (xy 59.314589 -288.716663)
			(xy 59.266765 -288.74278) (xy 59.215711 -288.761825) (xy 59.162466 -288.773411) (xy 59.108114 -288.7773)
			(xy 59.053762 -288.773415) (xy 59.000516 -288.761833) (xy 58.949461 -288.742792) (xy 58.901635 -288.716678)
			(xy 58.858012 -288.684024) (xy 58.819481 -288.645494) (xy 58.786826 -288.601872) (xy 58.760711 -288.554047)
			(xy 58.741669 -288.502991) (xy 58.730086 -288.449746) (xy 58.7262 -288.395394) (xy 40.81617 -288.395394)
			(xy 40.839839 -288.445885) (xy 40.855907 -288.499292) (xy 40.864027 -288.554468) (xy 40.864536 -288.582354)
			(xy 40.864027 -288.61024) (xy 40.855907 -288.665416) (xy 40.839839 -288.718823) (xy 40.816167 -288.76932)
			(xy 40.785394 -288.815833) (xy 40.748177 -288.85737) (xy 40.705309 -288.893045) (xy 40.657703 -288.922099)
			(xy 40.606374 -288.943911) (xy 40.552417 -288.958017) (xy 40.49698 -288.964117) (xy 40.441246 -288.96208)
			(xy 40.386403 -288.95195) (xy 40.333619 -288.933943) (xy 40.284019 -288.908442) (xy 40.238661 -288.875991)
			(xy 40.198512 -288.837282) (xy 40.164426 -288.793139) (xy 40.13713 -288.744504) (xy 40.117207 -288.692413)
			(xy 40.105081 -288.637976) (xy 40.10101 -288.582354) (xy 28.446476 -288.582354) (xy 29.73324 -289.869118)
			(xy 29.73324 -291.063712) (xy 58.726176 -291.063712) (xy 58.730062 -291.009357) (xy 58.741644 -290.956108)
			(xy 58.760687 -290.905049) (xy 58.786802 -290.85722) (xy 58.819459 -290.813595) (xy 58.857992 -290.775062)
			(xy 58.901617 -290.742405) (xy 58.949445 -290.716289) (xy 59.000504 -290.697245) (xy 59.053753 -290.685662)
			(xy 59.108108 -290.681776) (xy 59.162463 -290.685665) (xy 59.215712 -290.69725) (xy 59.266769 -290.716295)
			(xy 59.314597 -290.742413) (xy 59.336686 -290.758372) (xy 59.355698 -290.771968) (xy 59.397581 -290.7927)
			(xy 59.442549 -290.805426) (xy 59.489086 -290.809716) (xy 59.535623 -290.805426) (xy 59.580591 -290.7927)
			(xy 59.622474 -290.771968) (xy 59.641486 -290.758372) (xy 59.663593 -290.742438) (xy 59.711419 -290.716317)
			(xy 59.762475 -290.69727) (xy 59.815722 -290.685682) (xy 59.870076 -290.681791) (xy 59.924431 -290.685675)
			(xy 59.977679 -290.697256) (xy 60.028738 -290.716298) (xy 60.076566 -290.742412) (xy 60.120191 -290.775068)
			(xy 60.158725 -290.8136) (xy 60.191382 -290.857224) (xy 60.217497 -290.905051) (xy 60.23654 -290.956109)
			(xy 60.248123 -291.009357) (xy 60.252009 -291.063712) (xy 61.258093 -291.063712) (xy 61.261978 -291.00936)
			(xy 61.273559 -290.956115) (xy 61.2926 -290.90506) (xy 61.318713 -290.857234) (xy 61.351367 -290.813612)
			(xy 61.389897 -290.77508) (xy 61.433517 -290.742424) (xy 61.481342 -290.716309) (xy 61.532396 -290.697265)
			(xy 61.585641 -290.685681) (xy 61.639992 -290.681793) (xy 61.694344 -290.685679) (xy 61.747589 -290.697261)
			(xy 61.798644 -290.716302) (xy 61.846469 -290.742416) (xy 61.868558 -290.758372) (xy 61.88757 -290.771968)
			(xy 61.929453 -290.7927) (xy 61.974421 -290.805426) (xy 62.020958 -290.809716) (xy 62.067495 -290.805426)
			(xy 62.112463 -290.7927) (xy 62.154346 -290.771968) (xy 62.173358 -290.758372) (xy 62.195466 -290.742435)
			(xy 62.243293 -290.716311) (xy 62.294352 -290.697259) (xy 62.347602 -290.685668) (xy 62.40196 -290.681774)
			(xy 62.456319 -290.685657) (xy 62.509572 -290.697236) (xy 62.560634 -290.716277) (xy 62.608467 -290.742392)
			(xy 62.652096 -290.775049) (xy 62.690633 -290.813583) (xy 62.723293 -290.85721) (xy 62.749411 -290.90504)
			(xy 62.768456 -290.956102) (xy 62.780039 -291.009354) (xy 62.781308 -291.027098) (xy 63.482097 -291.027098)
			(xy 63.485985 -290.972746) (xy 63.497569 -290.9195) (xy 63.516612 -290.868445) (xy 63.542728 -290.82062)
			(xy 63.575384 -290.776999) (xy 63.613916 -290.738469) (xy 63.657539 -290.705816) (xy 63.705366 -290.679703)
			(xy 63.756422 -290.660662) (xy 63.809668 -290.649082) (xy 63.86402 -290.645197) (xy 63.918372 -290.649088)
			(xy 63.971617 -290.660674) (xy 64.022671 -290.67972) (xy 64.070495 -290.705838) (xy 64.092582 -290.721796)
			(xy 64.111594 -290.735392) (xy 64.153477 -290.756124) (xy 64.198445 -290.76885) (xy 64.244982 -290.77314)
			(xy 64.291519 -290.76885) (xy 64.336487 -290.756124) (xy 64.37837 -290.735392) (xy 64.397382 -290.721796)
			(xy 64.419467 -290.705829) (xy 64.467294 -290.679705) (xy 64.518352 -290.660654) (xy 64.571602 -290.649063)
			(xy 64.625959 -290.645169) (xy 64.680318 -290.649052) (xy 64.73357 -290.660631) (xy 64.784632 -290.679671)
			(xy 64.832465 -290.705785) (xy 64.876094 -290.738441) (xy 64.914631 -290.776974) (xy 64.947292 -290.820599)
			(xy 64.973411 -290.868429) (xy 64.992457 -290.919489) (xy 65.004042 -290.97274) (xy 65.005335 -290.990811)
			(xy 65.778144 -290.990811) (xy 65.782031 -290.936448) (xy 65.793615 -290.883192) (xy 65.812662 -290.832127)
			(xy 65.838782 -290.784292) (xy 65.871445 -290.740662) (xy 65.909985 -290.702125) (xy 65.953618 -290.669466)
			(xy 66.001454 -290.643349) (xy 66.052521 -290.624307) (xy 66.105778 -290.612726) (xy 66.160141 -290.608844)
			(xy 66.214503 -290.612738) (xy 66.267758 -290.62433) (xy 66.318821 -290.643383) (xy 66.366652 -290.669511)
			(xy 66.388742 -290.685474) (xy 66.407754 -290.69907) (xy 66.449637 -290.719802) (xy 66.494605 -290.732528)
			(xy 66.541142 -290.736818) (xy 66.587679 -290.732528) (xy 66.632647 -290.719802) (xy 66.67453 -290.69907)
			(xy 66.693542 -290.685474) (xy 66.715646 -290.669542) (xy 66.763468 -290.64343) (xy 66.814518 -290.62439)
			(xy 66.867759 -290.612809) (xy 66.922107 -290.608923) (xy 66.976454 -290.612811) (xy 67.029694 -290.624394)
			(xy 67.080744 -290.643436) (xy 67.128565 -290.669549) (xy 67.172183 -290.702202) (xy 67.210709 -290.740731)
			(xy 67.24336 -290.78435) (xy 67.269472 -290.832171) (xy 67.288511 -290.883222) (xy 67.300091 -290.936464)
			(xy 67.301394 -290.954692) (xy 68.152574 -290.954692) (xy 68.156464 -290.900334) (xy 68.16805 -290.847083)
			(xy 68.187097 -290.796023) (xy 68.213218 -290.748194) (xy 68.245879 -290.704569) (xy 68.284418 -290.666037)
			(xy 68.328048 -290.633383) (xy 68.375881 -290.60727) (xy 68.426944 -290.588232) (xy 68.480197 -290.576654)
			(xy 68.534556 -290.572774) (xy 68.588913 -290.57667) (xy 68.642163 -290.588263) (xy 68.69322 -290.607317)
			(xy 68.741046 -290.633443) (xy 68.763134 -290.649406) (xy 68.782146 -290.663002) (xy 68.824029 -290.683734)
			(xy 68.868997 -290.69646) (xy 68.915534 -290.70075) (xy 68.962071 -290.69646) (xy 69.007039 -290.683734)
			(xy 69.048922 -290.663002) (xy 69.067934 -290.649406) (xy 69.090008 -290.63343) (xy 69.137832 -290.607313)
			(xy 69.188886 -290.588268) (xy 69.242131 -290.576682) (xy 69.296483 -290.572793) (xy 69.350835 -290.576678)
			(xy 69.404081 -290.588258) (xy 69.455137 -290.607299) (xy 69.502963 -290.633412) (xy 69.546586 -290.666065)
			(xy 69.585118 -290.704595) (xy 69.617775 -290.748216) (xy 69.643891 -290.79604) (xy 69.662935 -290.847095)
			(xy 69.674519 -290.90034) (xy 69.678407 -290.954692) (xy 69.674521 -291.009044) (xy 69.662939 -291.062289)
			(xy 69.643898 -291.113345) (xy 69.617784 -291.16117) (xy 69.585129 -291.204793) (xy 69.546599 -291.243324)
			(xy 69.502977 -291.275979) (xy 69.455152 -291.302094) (xy 69.404097 -291.321137) (xy 69.350852 -291.33272)
			(xy 69.2965 -291.336607) (xy 69.242148 -291.33272) (xy 69.188902 -291.321137) (xy 69.137848 -291.302094)
			(xy 69.090022 -291.275979) (xy 69.067934 -291.260022) (xy 69.048922 -291.246426) (xy 69.007039 -291.225694)
			(xy 68.962071 -291.212968) (xy 68.915534 -291.208678) (xy 68.868997 -291.212968) (xy 68.824029 -291.225694)
			(xy 68.782146 -291.246426) (xy 68.763134 -291.260022) (xy 68.741032 -291.275966) (xy 68.693205 -291.30209)
			(xy 68.642147 -291.321142) (xy 68.588897 -291.332732) (xy 68.534539 -291.336626) (xy 68.480181 -291.332743)
			(xy 68.426928 -291.321164) (xy 68.375866 -291.302123) (xy 68.328034 -291.276008) (xy 68.284405 -291.243352)
			(xy 68.245868 -291.204818) (xy 68.213208 -291.161192) (xy 68.18709 -291.113362) (xy 68.168045 -291.062301)
			(xy 68.156461 -291.00905) (xy 68.152574 -290.954692) (xy 67.301394 -290.954692) (xy 67.303977 -290.990811)
			(xy 67.300088 -291.045158) (xy 67.288505 -291.098398) (xy 67.269463 -291.149448) (xy 67.243349 -291.197269)
			(xy 67.210695 -291.240886) (xy 67.172166 -291.279412) (xy 67.128547 -291.312063) (xy 67.080725 -291.338173)
			(xy 67.029674 -291.357212) (xy 66.976432 -291.368792) (xy 66.922085 -291.372677) (xy 66.867738 -291.368788)
			(xy 66.814498 -291.357204) (xy 66.763448 -291.338161) (xy 66.715628 -291.312046) (xy 66.693542 -291.29609)
			(xy 66.67453 -291.282494) (xy 66.632647 -291.261762) (xy 66.587679 -291.249036) (xy 66.541142 -291.244746)
			(xy 66.494605 -291.249036) (xy 66.449637 -291.261762) (xy 66.407754 -291.282494) (xy 66.388742 -291.29609)
			(xy 66.36667 -291.312078) (xy 66.31884 -291.338208) (xy 66.267779 -291.357264) (xy 66.214525 -291.368859)
			(xy 66.160163 -291.372756) (xy 66.105799 -291.368877) (xy 66.052542 -291.357299) (xy 66.001474 -291.33826)
			(xy 65.953636 -291.312146) (xy 65.910002 -291.279489) (xy 65.871459 -291.240954) (xy 65.838794 -291.197326)
			(xy 65.812671 -291.149493) (xy 65.793622 -291.098429) (xy 65.782034 -291.045173) (xy 65.778144 -290.990811)
			(xy 65.005335 -290.990811) (xy 65.007931 -291.027098) (xy 65.004043 -291.081455) (xy 64.992458 -291.134707)
			(xy 64.973413 -291.185767) (xy 64.947294 -291.233597) (xy 64.914634 -291.277223) (xy 64.876097 -291.315756)
			(xy 64.832469 -291.348412) (xy 64.784637 -291.374527) (xy 64.733575 -291.393568) (xy 64.680322 -291.405148)
			(xy 64.625964 -291.409031) (xy 64.571607 -291.405137) (xy 64.518357 -291.393548) (xy 64.467298 -291.374497)
			(xy 64.419471 -291.348373) (xy 64.397382 -291.332412) (xy 64.37837 -291.318816) (xy 64.336487 -291.298084)
			(xy 64.291519 -291.285358) (xy 64.244982 -291.281068) (xy 64.198445 -291.285358) (xy 64.153477 -291.298084)
			(xy 64.111594 -291.318816) (xy 64.092582 -291.332412) (xy 64.07049 -291.348365) (xy 64.022666 -291.374482)
			(xy 63.971612 -291.393528) (xy 63.918367 -291.405113) (xy 63.864015 -291.409003) (xy 63.809663 -291.405117)
			(xy 63.756417 -291.393536) (xy 63.705362 -291.374495) (xy 63.657535 -291.348382) (xy 63.613913 -291.315727)
			(xy 63.575381 -291.277197) (xy 63.542725 -291.233576) (xy 63.51661 -291.18575) (xy 63.497567 -291.134695)
			(xy 63.485985 -291.08145) (xy 63.482097 -291.027098) (xy 62.781308 -291.027098) (xy 62.783926 -291.063712)
			(xy 62.780036 -291.11807) (xy 62.768449 -291.171321) (xy 62.749401 -291.222381) (xy 62.72328 -291.270211)
			(xy 62.690617 -291.313835) (xy 62.652078 -291.352367) (xy 62.608447 -291.385021) (xy 62.560612 -291.411132)
			(xy 62.509549 -291.43017) (xy 62.456295 -291.441747) (xy 62.401936 -291.445626) (xy 62.347578 -291.441728)
			(xy 62.294329 -291.430134) (xy 62.243271 -291.411079) (xy 62.195446 -291.384952) (xy 62.173358 -291.368988)
			(xy 62.154346 -291.355392) (xy 62.112463 -291.33466) (xy 62.067495 -291.321934) (xy 62.020958 -291.317644)
			(xy 61.974421 -291.321934) (xy 61.929453 -291.33466) (xy 61.88757 -291.355392) (xy 61.868558 -291.368988)
			(xy 61.84649 -291.384971) (xy 61.798666 -291.411088) (xy 61.747612 -291.430133) (xy 61.694367 -291.441718)
			(xy 61.640016 -291.445607) (xy 61.585665 -291.441722) (xy 61.532419 -291.430142) (xy 61.481364 -291.411101)
			(xy 61.433538 -291.384989) (xy 61.389915 -291.352336) (xy 61.351383 -291.313807) (xy 61.318726 -291.270186)
			(xy 61.29261 -291.222362) (xy 61.273566 -291.171308) (xy 61.261982 -291.118063) (xy 61.258093 -291.063712)
			(xy 60.252009 -291.063712) (xy 60.248119 -291.118066) (xy 60.236534 -291.171314) (xy 60.217487 -291.222371)
			(xy 60.191369 -291.270197) (xy 60.158709 -291.313819) (xy 60.120173 -291.352348) (xy 60.076546 -291.385001)
			(xy 60.028716 -291.411112) (xy 59.977656 -291.430151) (xy 59.924407 -291.441728) (xy 59.870052 -291.445609)
			(xy 59.815698 -291.441714) (xy 59.762451 -291.430124) (xy 59.711397 -291.411073) (xy 59.663573 -291.384949)
			(xy 59.641486 -291.368988) (xy 59.622474 -291.355392) (xy 59.580591 -291.33466) (xy 59.535623 -291.321934)
			(xy 59.489086 -291.317644) (xy 59.442549 -291.321934) (xy 59.397581 -291.33466) (xy 59.355698 -291.355392)
			(xy 59.336686 -291.368988) (xy 59.314617 -291.384974) (xy 59.266791 -291.411095) (xy 59.215735 -291.430143)
			(xy 59.162487 -291.441732) (xy 59.108132 -291.445624) (xy 59.053776 -291.441741) (xy 59.000527 -291.430162)
			(xy 58.949467 -291.411121) (xy 58.901637 -291.385008) (xy 58.85801 -291.352354) (xy 58.819475 -291.313823)
			(xy 58.786815 -291.2702) (xy 58.760697 -291.222373) (xy 58.741651 -291.171315) (xy 58.730065 -291.118067)
			(xy 58.726176 -291.063712) (xy 29.73324 -291.063712) (xy 29.73324 -295.215564) (xy 78.99984 -295.215564)
			(xy 79.003911 -295.159942) (xy 79.016037 -295.105505) (xy 79.03596 -295.053414) (xy 79.063256 -295.004779)
			(xy 79.097342 -294.960636) (xy 79.137491 -294.921927) (xy 79.182849 -294.889476) (xy 79.232449 -294.863975)
			(xy 79.285233 -294.845968) (xy 79.340076 -294.835838) (xy 79.39581 -294.833801) (xy 79.451247 -294.839901)
			(xy 79.505204 -294.854007) (xy 79.556533 -294.875819) (xy 79.604139 -294.904873) (xy 79.647007 -294.940548)
			(xy 79.684224 -294.982085) (xy 79.714997 -295.028598) (xy 79.738669 -295.079095) (xy 79.754737 -295.132502)
			(xy 79.762857 -295.187678) (xy 79.763366 -295.215564) (xy 79.762857 -295.24345) (xy 79.754737 -295.298626)
			(xy 79.738669 -295.352033) (xy 79.714997 -295.40253) (xy 79.684224 -295.449043) (xy 79.647007 -295.49058)
			(xy 79.604139 -295.526255) (xy 79.556533 -295.555309) (xy 79.505204 -295.577121) (xy 79.451247 -295.591227)
			(xy 79.39581 -295.597327) (xy 79.340076 -295.59529) (xy 79.285233 -295.58516) (xy 79.232449 -295.567153)
			(xy 79.182849 -295.541652) (xy 79.137491 -295.509201) (xy 79.097342 -295.470492) (xy 79.063256 -295.426349)
			(xy 79.03596 -295.377714) (xy 79.016037 -295.325623) (xy 79.003911 -295.271186) (xy 78.99984 -295.215564)
			(xy 29.73324 -295.215564) (xy 29.73324 -297.892216) (xy 79.043274 -297.892216) (xy 79.047345 -297.836594)
			(xy 79.059471 -297.782157) (xy 79.079394 -297.730066) (xy 79.10669 -297.681431) (xy 79.140776 -297.637288)
			(xy 79.180925 -297.598579) (xy 79.226283 -297.566128) (xy 79.275883 -297.540627) (xy 79.328667 -297.52262)
			(xy 79.38351 -297.51249) (xy 79.439244 -297.510453) (xy 79.494681 -297.516553) (xy 79.548638 -297.530659)
			(xy 79.599967 -297.552471) (xy 79.647573 -297.581525) (xy 79.690441 -297.6172) (xy 79.727658 -297.658737)
			(xy 79.758431 -297.70525) (xy 79.782103 -297.755747) (xy 79.798171 -297.809154) (xy 79.806291 -297.86433)
			(xy 79.8068 -297.892216) (xy 81.762344 -297.892216) (xy 81.766415 -297.836594) (xy 81.778541 -297.782157)
			(xy 81.798464 -297.730066) (xy 81.82576 -297.681431) (xy 81.859846 -297.637288) (xy 81.899995 -297.598579)
			(xy 81.945353 -297.566128) (xy 81.994953 -297.540627) (xy 82.047737 -297.52262) (xy 82.10258 -297.51249)
			(xy 82.158314 -297.510453) (xy 82.213751 -297.516553) (xy 82.267708 -297.530659) (xy 82.319037 -297.552471)
			(xy 82.366643 -297.581525) (xy 82.409511 -297.6172) (xy 82.446728 -297.658737) (xy 82.477501 -297.70525)
			(xy 82.501173 -297.755747) (xy 82.517241 -297.809154) (xy 82.525361 -297.86433) (xy 82.52587 -297.892216)
			(xy 82.525361 -297.920102) (xy 82.517241 -297.975278) (xy 82.501173 -298.028685) (xy 82.477501 -298.079182)
			(xy 82.446728 -298.125695) (xy 82.409511 -298.167232) (xy 82.366643 -298.202907) (xy 82.319037 -298.231961)
			(xy 82.267708 -298.253773) (xy 82.213751 -298.267879) (xy 82.158314 -298.273979) (xy 82.10258 -298.271942)
			(xy 82.047737 -298.261812) (xy 81.994953 -298.243805) (xy 81.945353 -298.218304) (xy 81.899995 -298.185853)
			(xy 81.859846 -298.147144) (xy 81.82576 -298.103001) (xy 81.798464 -298.054366) (xy 81.778541 -298.002275)
			(xy 81.766415 -297.947838) (xy 81.762344 -297.892216) (xy 79.8068 -297.892216) (xy 79.806291 -297.920102)
			(xy 79.798171 -297.975278) (xy 79.782103 -298.028685) (xy 79.758431 -298.079182) (xy 79.727658 -298.125695)
			(xy 79.690441 -298.167232) (xy 79.647573 -298.202907) (xy 79.599967 -298.231961) (xy 79.548638 -298.253773)
			(xy 79.494681 -298.267879) (xy 79.439244 -298.273979) (xy 79.38351 -298.271942) (xy 79.328667 -298.261812)
			(xy 79.275883 -298.243805) (xy 79.226283 -298.218304) (xy 79.180925 -298.185853) (xy 79.140776 -298.147144)
			(xy 79.10669 -298.103001) (xy 79.079394 -298.054366) (xy 79.059471 -298.002275) (xy 79.047345 -297.947838)
			(xy 79.043274 -297.892216) (xy 29.73324 -297.892216) (xy 29.73324 -300.851618) (xy 71.800243 -300.851618)
			(xy 71.804128 -300.797256) (xy 71.815712 -300.744) (xy 71.834757 -300.692935) (xy 71.860876 -300.6451)
			(xy 71.893537 -300.60147) (xy 71.932076 -300.562932) (xy 71.975707 -300.530272) (xy 72.023542 -300.504154)
			(xy 72.074607 -300.48511) (xy 72.127864 -300.473527) (xy 72.182226 -300.469643) (xy 72.236588 -300.473535)
			(xy 72.289842 -300.485124) (xy 72.340905 -300.504175) (xy 72.388737 -300.5303) (xy 72.410828 -300.546262)
			(xy 72.42984 -300.559858) (xy 72.471723 -300.58059) (xy 72.516691 -300.593316) (xy 72.563228 -300.597606)
			(xy 72.609765 -300.593316) (xy 72.654733 -300.58059) (xy 72.696616 -300.559858) (xy 72.715628 -300.546262)
			(xy 72.737744 -300.530345) (xy 72.785565 -300.504233) (xy 72.836617 -300.485192) (xy 72.889858 -300.473611)
			(xy 72.944206 -300.469724) (xy 72.998554 -300.473612) (xy 73.051795 -300.485195) (xy 73.102845 -300.504237)
			(xy 73.150666 -300.530351) (xy 73.194284 -300.563005) (xy 73.232811 -300.601534) (xy 73.265462 -300.645154)
			(xy 73.291572 -300.692976) (xy 73.310612 -300.744028) (xy 73.322191 -300.79727) (xy 73.323471 -300.815171)
			(xy 73.969202 -300.815171) (xy 73.973093 -300.760817) (xy 73.984682 -300.707571) (xy 74.00373 -300.656516)
			(xy 74.029851 -300.608691) (xy 74.062513 -300.565072) (xy 74.101051 -300.526545) (xy 74.14468 -300.493895)
			(xy 74.192511 -300.467787) (xy 74.243572 -300.448752) (xy 74.296821 -300.437178) (xy 74.351176 -300.433302)
			(xy 74.405529 -300.4372) (xy 74.458775 -300.448795) (xy 74.509827 -300.46785) (xy 74.557648 -300.493977)
			(xy 74.579734 -300.50994) (xy 74.598746 -300.523536) (xy 74.640629 -300.544268) (xy 74.685597 -300.556994)
			(xy 74.732134 -300.561284) (xy 74.778671 -300.556994) (xy 74.823639 -300.544268) (xy 74.865522 -300.523536)
			(xy 74.884534 -300.50994) (xy 74.906576 -300.493918) (xy 74.954402 -300.467797) (xy 75.005459 -300.448747)
			(xy 75.058707 -300.437158) (xy 75.113062 -300.433265) (xy 75.167419 -300.437148) (xy 75.220669 -300.448726)
			(xy 75.271729 -300.467765) (xy 75.319561 -300.493878) (xy 75.363189 -300.526531) (xy 75.401725 -300.565061)
			(xy 75.434387 -300.608684) (xy 75.460507 -300.65651) (xy 75.479555 -300.707567) (xy 75.491143 -300.760816)
			(xy 75.495035 -300.815171) (xy 75.491151 -300.869527) (xy 75.491136 -300.869598) (xy 75.993578 -300.869598)
			(xy 75.997467 -300.815241) (xy 76.009051 -300.761992) (xy 76.028097 -300.710933) (xy 76.054215 -300.663104)
			(xy 76.086875 -300.61948) (xy 76.125411 -300.580948) (xy 76.169039 -300.548293) (xy 76.21687 -300.52218)
			(xy 76.267931 -300.50314) (xy 76.321182 -300.491561) (xy 76.375538 -300.487678) (xy 76.429894 -300.491572)
			(xy 76.483143 -300.503161) (xy 76.5342 -300.522212) (xy 76.582026 -300.548335) (xy 76.604114 -300.564296)
			(xy 76.623126 -300.577892) (xy 76.665009 -300.598624) (xy 76.709977 -300.61135) (xy 76.756514 -300.61564)
			(xy 76.803051 -300.61135) (xy 76.848019 -300.598624) (xy 76.889902 -300.577892) (xy 76.908914 -300.564296)
			(xy 76.930998 -300.548332) (xy 76.978823 -300.522213) (xy 77.029878 -300.503166) (xy 77.083124 -300.491579)
			(xy 77.137478 -300.487689) (xy 77.191831 -300.491573) (xy 77.245079 -300.503153) (xy 77.296136 -300.522194)
			(xy 77.343964 -300.548308) (xy 77.387589 -300.580962) (xy 77.426122 -300.619493) (xy 77.458779 -300.663115)
			(xy 77.484895 -300.710941) (xy 77.50394 -300.761997) (xy 77.515523 -300.815244) (xy 77.519411 -300.869598)
			(xy 78.144495 -300.869598) (xy 78.148383 -300.815245) (xy 78.159967 -300.761999) (xy 78.17901 -300.710944)
			(xy 78.205126 -300.663118) (xy 78.237783 -300.619497) (xy 78.276316 -300.580967) (xy 78.319939 -300.548313)
			(xy 78.367766 -300.5222) (xy 78.418823 -300.50316) (xy 78.47207 -300.491579) (xy 78.526422 -300.487695)
			(xy 78.580775 -300.491586) (xy 78.63402 -300.503172) (xy 78.685074 -300.522219) (xy 78.732898 -300.548337)
			(xy 78.754986 -300.564296) (xy 78.773998 -300.577892) (xy 78.815881 -300.598624) (xy 78.860849 -300.61135)
			(xy 78.907386 -300.61564) (xy 78.953923 -300.61135) (xy 78.998891 -300.598624) (xy 79.040774 -300.577892)
			(xy 79.059786 -300.564296) (xy 79.081871 -300.548329) (xy 79.129697 -300.522206) (xy 79.180755 -300.503155)
			(xy 79.234005 -300.491565) (xy 79.288362 -300.487672) (xy 79.342719 -300.491554) (xy 79.395971 -300.503134)
			(xy 79.447033 -300.522174) (xy 79.494865 -300.548288) (xy 79.538493 -300.580944) (xy 79.57703 -300.619476)
			(xy 79.60969 -300.663101) (xy 79.635809 -300.71093) (xy 79.654855 -300.76199) (xy 79.66644 -300.81524)
			(xy 79.670305 -300.86927) (xy 80.373797 -300.86927) (xy 80.377689 -300.814915) (xy 80.389278 -300.761667)
			(xy 80.408327 -300.710611) (xy 80.43445 -300.662786) (xy 80.467113 -300.619166) (xy 80.505651 -300.580638)
			(xy 80.549281 -300.547988) (xy 80.597114 -300.52188) (xy 80.648176 -300.502846) (xy 80.701427 -300.491273)
			(xy 80.755783 -300.487397) (xy 80.810137 -300.491297) (xy 80.863383 -300.502893) (xy 80.914437 -300.521949)
			(xy 80.962258 -300.548078) (xy 80.984344 -300.564042) (xy 81.003356 -300.577638) (xy 81.045239 -300.59837)
			(xy 81.090207 -300.611096) (xy 81.136744 -300.615386) (xy 81.183281 -300.611096) (xy 81.228249 -300.59837)
			(xy 81.270132 -300.577638) (xy 81.289144 -300.564042) (xy 81.311184 -300.548018) (xy 81.35901 -300.521898)
			(xy 81.410066 -300.50285) (xy 81.463313 -300.491262) (xy 81.517667 -300.48737) (xy 81.572022 -300.491253)
			(xy 81.625271 -300.502832) (xy 81.67633 -300.521871) (xy 81.72416 -300.547983) (xy 81.767787 -300.580636)
			(xy 81.806323 -300.619165) (xy 81.838983 -300.662787) (xy 81.865103 -300.710612) (xy 81.884151 -300.761669)
			(xy 81.895738 -300.814916) (xy 81.89963 -300.86927) (xy 81.895747 -300.923625) (xy 81.884168 -300.976874)
			(xy 81.865128 -301.027933) (xy 81.839016 -301.075763) (xy 81.806362 -301.119389) (xy 81.767833 -301.157925)
			(xy 81.724211 -301.190585) (xy 81.676385 -301.216704) (xy 81.625329 -301.235752) (xy 81.572081 -301.247339)
			(xy 81.517727 -301.25123) (xy 81.463372 -301.247346) (xy 81.410123 -301.235767) (xy 81.359064 -301.216727)
			(xy 81.311235 -301.190614) (xy 81.289144 -301.174658) (xy 81.270132 -301.161062) (xy 81.228249 -301.14033)
			(xy 81.183281 -301.127604) (xy 81.136744 -301.123314) (xy 81.090207 -301.127604) (xy 81.045239 -301.14033)
			(xy 81.003356 -301.161062) (xy 80.984344 -301.174658) (xy 80.962208 -301.190554) (xy 80.914382 -301.216675)
			(xy 80.863326 -301.235724) (xy 80.810078 -301.247312) (xy 80.755723 -301.251203) (xy 80.701368 -301.247318)
			(xy 80.648118 -301.235737) (xy 80.59706 -301.216695) (xy 80.549231 -301.190579) (xy 80.505606 -301.157922)
			(xy 80.467073 -301.119389) (xy 80.434417 -301.075763) (xy 80.408302 -301.027934) (xy 80.389261 -300.976875)
			(xy 80.377681 -300.923626) (xy 80.373797 -300.86927) (xy 79.670305 -300.86927) (xy 79.670328 -300.869598)
			(xy 79.666441 -300.923955) (xy 79.654856 -300.977206) (xy 79.635811 -301.028265) (xy 79.609693 -301.076095)
			(xy 79.577033 -301.11972) (xy 79.538497 -301.158253) (xy 79.494869 -301.190909) (xy 79.447037 -301.217024)
			(xy 79.395976 -301.236065) (xy 79.342724 -301.247645) (xy 79.288366 -301.251528) (xy 79.234009 -301.247635)
			(xy 79.18076 -301.236046) (xy 79.129702 -301.216996) (xy 79.081875 -301.190873) (xy 79.059786 -301.174912)
			(xy 79.040774 -301.161316) (xy 78.998891 -301.140584) (xy 78.953923 -301.127858) (xy 78.907386 -301.123568)
			(xy 78.860849 -301.127858) (xy 78.815881 -301.140584) (xy 78.773998 -301.161316) (xy 78.754986 -301.174912)
			(xy 78.732894 -301.190865) (xy 78.68507 -301.216983) (xy 78.634016 -301.236029) (xy 78.58077 -301.247615)
			(xy 78.526418 -301.251505) (xy 78.472065 -301.24762) (xy 78.418818 -301.236039) (xy 78.367762 -301.216998)
			(xy 78.319935 -301.190884) (xy 78.276312 -301.15823) (xy 78.23778 -301.1197) (xy 78.205124 -301.076078)
			(xy 78.179008 -301.028252) (xy 78.159965 -300.977196) (xy 78.148382 -300.92395) (xy 78.144495 -300.869598)
			(xy 77.519411 -300.869598) (xy 77.515524 -300.923951) (xy 77.503941 -300.977198) (xy 77.484897 -301.028254)
			(xy 77.458782 -301.076081) (xy 77.426125 -301.119704) (xy 77.387592 -301.158235) (xy 77.343968 -301.19089)
			(xy 77.296141 -301.217004) (xy 77.245083 -301.236045) (xy 77.191836 -301.247626) (xy 77.137482 -301.251511)
			(xy 77.083129 -301.247621) (xy 77.029883 -301.236035) (xy 76.978827 -301.216989) (xy 76.931002 -301.190871)
			(xy 76.908914 -301.174912) (xy 76.889902 -301.161316) (xy 76.848019 -301.140584) (xy 76.803051 -301.127858)
			(xy 76.756514 -301.123568) (xy 76.709977 -301.127858) (xy 76.665009 -301.140584) (xy 76.623126 -301.161316)
			(xy 76.604114 -301.174912) (xy 76.582022 -301.190868) (xy 76.534196 -301.21699) (xy 76.483138 -301.23604)
			(xy 76.42989 -301.247629) (xy 76.375534 -301.251522) (xy 76.321177 -301.247639) (xy 76.267926 -301.236059)
			(xy 76.216866 -301.217018) (xy 76.169035 -301.190904) (xy 76.125407 -301.158248) (xy 76.086872 -301.119716)
			(xy 76.054213 -301.076091) (xy 76.028095 -301.028263) (xy 76.00905 -300.977204) (xy 75.997466 -300.923954)
			(xy 75.993578 -300.869598) (xy 75.491136 -300.869598) (xy 75.479571 -300.922777) (xy 75.460531 -300.973837)
			(xy 75.434418 -301.021668) (xy 75.401763 -301.065295) (xy 75.363232 -301.103831) (xy 75.319609 -301.136491)
			(xy 75.271782 -301.162611) (xy 75.220724 -301.181657) (xy 75.167476 -301.193244) (xy 75.11312 -301.197135)
			(xy 75.058764 -301.19325) (xy 75.005514 -301.181669) (xy 74.954455 -301.162627) (xy 74.906625 -301.136513)
			(xy 74.884534 -301.120556) (xy 74.865522 -301.10696) (xy 74.823639 -301.086228) (xy 74.778671 -301.073502)
			(xy 74.732134 -301.069212) (xy 74.685597 -301.073502) (xy 74.640629 -301.086228) (xy 74.598746 -301.10696)
			(xy 74.579734 -301.120556) (xy 74.5576 -301.136454) (xy 74.509775 -301.162574) (xy 74.458719 -301.181621)
			(xy 74.405472 -301.193208) (xy 74.351119 -301.197098) (xy 74.296764 -301.193213) (xy 74.243516 -301.181632)
			(xy 74.192459 -301.162589) (xy 74.144631 -301.136474) (xy 74.101007 -301.103818) (xy 74.062476 -301.065285)
			(xy 74.02982 -301.02166) (xy 74.003706 -300.973832) (xy 73.984665 -300.922774) (xy 73.973085 -300.869526)
			(xy 73.969202 -300.815171) (xy 73.323471 -300.815171) (xy 73.326076 -300.851618) (xy 73.322186 -300.905965)
			(xy 73.310601 -300.959206) (xy 73.291558 -301.010256) (xy 73.265442 -301.058076) (xy 73.232787 -301.101693)
			(xy 73.194257 -301.140219) (xy 73.150636 -301.172868) (xy 73.102813 -301.198978) (xy 73.05176 -301.218015)
			(xy 72.998518 -301.229593) (xy 72.94417 -301.233476) (xy 72.889823 -301.229584) (xy 72.836582 -301.217998)
			(xy 72.785533 -301.198952) (xy 72.737713 -301.172836) (xy 72.715628 -301.156878) (xy 72.696616 -301.143282)
			(xy 72.654733 -301.12255) (xy 72.609765 -301.109824) (xy 72.563228 -301.105534) (xy 72.516691 -301.109824)
			(xy 72.471723 -301.12255) (xy 72.42984 -301.143282) (xy 72.410828 -301.156878) (xy 72.388767 -301.172881)
			(xy 72.340938 -301.19901) (xy 72.289877 -301.218066) (xy 72.236624 -301.22966) (xy 72.182262 -301.233557)
			(xy 72.127899 -301.229678) (xy 72.074642 -301.218101) (xy 72.023575 -301.199061) (xy 71.975737 -301.172948)
			(xy 71.932103 -301.140292) (xy 71.893561 -301.101758) (xy 71.860895 -301.05813) (xy 71.834772 -301.010298)
			(xy 71.815722 -300.959235) (xy 71.804134 -300.90598) (xy 71.800243 -300.851618) (xy 29.73324 -300.851618)
			(xy 29.73324 -302.814511) (xy 71.800252 -302.814511) (xy 71.804139 -302.76015) (xy 71.815723 -302.706896)
			(xy 71.834769 -302.655832) (xy 71.860888 -302.607999) (xy 71.893549 -302.564371) (xy 71.932087 -302.525835)
			(xy 71.975718 -302.493176) (xy 72.023552 -302.467059) (xy 72.074617 -302.448017) (xy 72.127872 -302.436436)
			(xy 72.182233 -302.432552) (xy 72.236594 -302.436445) (xy 72.289847 -302.448035) (xy 72.340908 -302.467087)
			(xy 72.388738 -302.493212) (xy 72.410828 -302.509174) (xy 72.42984 -302.52277) (xy 72.471723 -302.543502)
			(xy 72.516691 -302.556228) (xy 72.563228 -302.560518) (xy 72.609765 -302.556228) (xy 72.654733 -302.543502)
			(xy 72.696616 -302.52277) (xy 72.715628 -302.509174) (xy 72.737732 -302.493241) (xy 72.785555 -302.467127)
			(xy 72.836607 -302.448085) (xy 72.88985 -302.436502) (xy 72.944199 -302.432615) (xy 72.998548 -302.436502)
			(xy 73.05179 -302.448084) (xy 73.102843 -302.467126) (xy 73.150665 -302.493239) (xy 73.194285 -302.525893)
			(xy 73.232813 -302.564422) (xy 73.265466 -302.608043) (xy 73.291578 -302.655866) (xy 73.310619 -302.706919)
			(xy 73.3222 -302.760162) (xy 73.323491 -302.778224) (xy 73.969131 -302.778224) (xy 73.973016 -302.72386)
			(xy 73.984599 -302.670602) (xy 74.003644 -302.619534) (xy 74.029764 -302.571698) (xy 74.062426 -302.528065)
			(xy 74.100965 -302.489526) (xy 74.144597 -302.456864) (xy 74.192434 -302.430745) (xy 74.243501 -302.411699)
			(xy 74.296759 -302.400116) (xy 74.351123 -302.396231) (xy 74.405487 -302.400123) (xy 74.458744 -302.411713)
			(xy 74.509809 -302.430764) (xy 74.557642 -302.456889) (xy 74.579734 -302.472852) (xy 74.598746 -302.486448)
			(xy 74.640629 -302.50718) (xy 74.685597 -302.519906) (xy 74.732134 -302.524196) (xy 74.778671 -302.519906)
			(xy 74.823639 -302.50718) (xy 74.865522 -302.486448) (xy 74.884534 -302.472852) (xy 74.906659 -302.456949)
			(xy 74.95448 -302.430839) (xy 75.00553 -302.4118) (xy 75.058769 -302.400221) (xy 75.113115 -302.396336)
			(xy 75.167461 -302.400225) (xy 75.2207 -302.411809) (xy 75.271748 -302.430852) (xy 75.319567 -302.456965)
			(xy 75.363182 -302.489619) (xy 75.401707 -302.528147) (xy 75.434356 -302.571766) (xy 75.460465 -302.619588)
			(xy 75.479502 -302.670638) (xy 75.491081 -302.723878) (xy 75.494964 -302.778224) (xy 75.49108 -302.83249)
			(xy 75.993588 -302.83249) (xy 75.997477 -302.778135) (xy 76.009063 -302.724887) (xy 76.028109 -302.67383)
			(xy 76.054227 -302.626004) (xy 76.086887 -302.582381) (xy 76.125423 -302.543851) (xy 76.16905 -302.511198)
			(xy 76.216881 -302.485086) (xy 76.26794 -302.466047) (xy 76.32119 -302.454469) (xy 76.375546 -302.450588)
			(xy 76.4299 -302.454482) (xy 76.483147 -302.466073) (xy 76.534202 -302.485124) (xy 76.582027 -302.511247)
			(xy 76.604114 -302.527208) (xy 76.623126 -302.540804) (xy 76.665009 -302.561536) (xy 76.709977 -302.574262)
			(xy 76.756514 -302.578552) (xy 76.803051 -302.574262) (xy 76.848019 -302.561536) (xy 76.889902 -302.540804)
			(xy 76.908914 -302.527208) (xy 76.930987 -302.511228) (xy 76.978812 -302.485107) (xy 77.029868 -302.466059)
			(xy 77.083116 -302.454471) (xy 77.13747 -302.450579) (xy 77.191825 -302.454463) (xy 77.245075 -302.466042)
			(xy 77.296134 -302.485082) (xy 77.343963 -302.511196) (xy 77.387589 -302.54385) (xy 77.426124 -302.582381)
			(xy 77.458783 -302.626004) (xy 77.484901 -302.673831) (xy 77.503947 -302.724888) (xy 77.515532 -302.778136)
			(xy 77.519421 -302.83249) (xy 78.144505 -302.83249) (xy 78.148393 -302.778139) (xy 78.159978 -302.724895)
			(xy 78.179022 -302.673841) (xy 78.205138 -302.626018) (xy 78.237795 -302.582398) (xy 78.276327 -302.543869)
			(xy 78.319951 -302.511217) (xy 78.367777 -302.485106) (xy 78.418833 -302.466067) (xy 78.472078 -302.454488)
			(xy 78.52643 -302.450605) (xy 78.580781 -302.454496) (xy 78.634024 -302.466084) (xy 78.685077 -302.48513)
			(xy 78.732899 -302.511249) (xy 78.754986 -302.527208) (xy 78.773998 -302.540804) (xy 78.815881 -302.561536)
			(xy 78.860849 -302.574262) (xy 78.907386 -302.578552) (xy 78.953923 -302.574262) (xy 78.998891 -302.561536)
			(xy 79.040774 -302.540804) (xy 79.059786 -302.527208) (xy 79.081859 -302.511225) (xy 79.129687 -302.4851)
			(xy 79.180746 -302.466048) (xy 79.233996 -302.454457) (xy 79.288354 -302.450562) (xy 79.342713 -302.454444)
			(xy 79.395967 -302.466022) (xy 79.44703 -302.485062) (xy 79.494864 -302.511176) (xy 79.538494 -302.543832)
			(xy 79.577032 -302.582364) (xy 79.609694 -302.62599) (xy 79.635815 -302.67382) (xy 79.654862 -302.72488)
			(xy 79.666448 -302.778132) (xy 79.670326 -302.832323) (xy 80.373727 -302.832323) (xy 80.377612 -302.777957)
			(xy 80.389196 -302.724698) (xy 80.408241 -302.67363) (xy 80.434362 -302.625793) (xy 80.467025 -302.58216)
			(xy 80.505565 -302.54362) (xy 80.549199 -302.510958) (xy 80.597037 -302.484838) (xy 80.648105 -302.465793)
			(xy 80.701365 -302.454211) (xy 80.75573 -302.450327) (xy 80.810095 -302.45422) (xy 80.863353 -302.465811)
			(xy 80.914418 -302.484863) (xy 80.962252 -302.51099) (xy 80.984344 -302.526954) (xy 81.003356 -302.54055)
			(xy 81.045239 -302.561282) (xy 81.090207 -302.574008) (xy 81.136744 -302.578298) (xy 81.183281 -302.574008)
			(xy 81.228249 -302.561282) (xy 81.270132 -302.54055) (xy 81.289144 -302.526954) (xy 81.311267 -302.511049)
			(xy 81.359087 -302.48494) (xy 81.410136 -302.465903) (xy 81.463375 -302.454324) (xy 81.51772 -302.45044)
			(xy 81.572064 -302.45433) (xy 81.625302 -302.465914) (xy 81.676349 -302.484957) (xy 81.724167 -302.51107)
			(xy 81.767781 -302.543724) (xy 81.806304 -302.582251) (xy 81.838953 -302.625869) (xy 81.865061 -302.67369)
			(xy 81.884098 -302.724739) (xy 81.895676 -302.777978) (xy 81.89956 -302.832323) (xy 81.89567 -302.886667)
			(xy 81.884085 -302.939905) (xy 81.865042 -302.990952) (xy 81.838928 -303.038769) (xy 81.806275 -303.082383)
			(xy 81.767746 -303.120906) (xy 81.724128 -303.153554) (xy 81.676308 -303.179662) (xy 81.625258 -303.198699)
			(xy 81.572019 -303.210277) (xy 81.517674 -303.21416) (xy 81.46333 -303.210269) (xy 81.410092 -303.198684)
			(xy 81.359046 -303.179641) (xy 81.311228 -303.153526) (xy 81.289144 -303.13757) (xy 81.270132 -303.123974)
			(xy 81.228249 -303.103242) (xy 81.183281 -303.090516) (xy 81.136744 -303.086226) (xy 81.090207 -303.090516)
			(xy 81.045239 -303.103242) (xy 81.003356 -303.123974) (xy 80.984344 -303.13757) (xy 80.96229 -303.153585)
			(xy 80.91446 -303.179718) (xy 80.863396 -303.198777) (xy 80.81014 -303.210374) (xy 80.755776 -303.214273)
			(xy 80.70141 -303.210395) (xy 80.648149 -303.198819) (xy 80.597078 -303.179781) (xy 80.549237 -303.153667)
			(xy 80.5056 -303.12101) (xy 80.467055 -303.082475) (xy 80.434386 -303.038846) (xy 80.40826 -302.991011)
			(xy 80.389208 -302.939945) (xy 80.377619 -302.886688) (xy 80.373727 -302.832323) (xy 79.670326 -302.832323)
			(xy 79.670338 -302.83249) (xy 79.666451 -302.886849) (xy 79.654867 -302.940101) (xy 79.635823 -302.991163)
			(xy 79.609705 -303.038994) (xy 79.577045 -303.082621) (xy 79.538508 -303.121156) (xy 79.49488 -303.153814)
			(xy 79.447048 -303.17993) (xy 79.395985 -303.198972) (xy 79.342733 -303.210553) (xy 79.288374 -303.214438)
			(xy 79.234015 -303.210546) (xy 79.180764 -303.198957) (xy 79.129704 -303.179908) (xy 79.081876 -303.153785)
			(xy 79.059786 -303.137824) (xy 79.040774 -303.124228) (xy 78.998891 -303.103496) (xy 78.953923 -303.09077)
			(xy 78.907386 -303.08648) (xy 78.860849 -303.09077) (xy 78.815881 -303.103496) (xy 78.773998 -303.124228)
			(xy 78.754986 -303.137824) (xy 78.732883 -303.153761) (xy 78.68506 -303.179878) (xy 78.634006 -303.198922)
			(xy 78.580762 -303.210506) (xy 78.52641 -303.214395) (xy 78.472059 -303.210509) (xy 78.418814 -303.198928)
			(xy 78.367759 -303.179886) (xy 78.319934 -303.153773) (xy 78.276313 -303.121118) (xy 78.237782 -303.082588)
			(xy 78.205128 -303.038966) (xy 78.179014 -302.991141) (xy 78.159972 -302.940087) (xy 78.148391 -302.886842)
			(xy 78.144505 -302.83249) (xy 77.519421 -302.83249) (xy 77.515535 -302.886845) (xy 77.503952 -302.940094)
			(xy 77.484909 -302.991152) (xy 77.458794 -303.03898) (xy 77.426137 -303.082605) (xy 77.387604 -303.121137)
			(xy 77.343979 -303.153794) (xy 77.296151 -303.17991) (xy 77.245093 -303.198952) (xy 77.191844 -303.210535)
			(xy 77.13749 -303.214421) (xy 77.083135 -303.210532) (xy 77.029887 -303.198946) (xy 76.97883 -303.179901)
			(xy 76.931003 -303.153783) (xy 76.908914 -303.137824) (xy 76.889902 -303.124228) (xy 76.848019 -303.103496)
			(xy 76.803051 -303.09077) (xy 76.756514 -303.08648) (xy 76.709977 -303.09077) (xy 76.665009 -303.103496)
			(xy 76.623126 -303.124228) (xy 76.604114 -303.137824) (xy 76.58201 -303.153764) (xy 76.534185 -303.179884)
			(xy 76.483129 -303.198933) (xy 76.429881 -303.210521) (xy 76.375526 -303.214412) (xy 76.321171 -303.210528)
			(xy 76.267922 -303.198948) (xy 76.216863 -303.179906) (xy 76.169034 -303.153792) (xy 76.125408 -303.121136)
			(xy 76.086875 -303.082604) (xy 76.054217 -303.03898) (xy 76.028101 -302.991152) (xy 76.009057 -302.940094)
			(xy 75.997474 -302.886845) (xy 75.993588 -302.83249) (xy 75.49108 -302.83249) (xy 75.491074 -302.832569)
			(xy 75.479489 -302.885808) (xy 75.460445 -302.936856) (xy 75.43433 -302.984674) (xy 75.401675 -303.028289)
			(xy 75.363146 -303.066812) (xy 75.319526 -303.099461) (xy 75.271705 -303.125568) (xy 75.220654 -303.144605)
			(xy 75.167413 -303.156182) (xy 75.113067 -303.160064) (xy 75.058722 -303.156173) (xy 75.005484 -303.144586)
			(xy 74.954436 -303.125541) (xy 74.906618 -303.099425) (xy 74.884534 -303.083468) (xy 74.865522 -303.069872)
			(xy 74.823639 -303.04914) (xy 74.778671 -303.036414) (xy 74.732134 -303.032124) (xy 74.685597 -303.036414)
			(xy 74.640629 -303.04914) (xy 74.598746 -303.069872) (xy 74.579734 -303.083468) (xy 74.557683 -303.099485)
			(xy 74.509852 -303.125616) (xy 74.45879 -303.144674) (xy 74.405535 -303.15627) (xy 74.351171 -303.160169)
			(xy 74.296807 -303.156291) (xy 74.243547 -303.144714) (xy 74.192478 -303.125675) (xy 74.144638 -303.099562)
			(xy 74.101001 -303.066905) (xy 74.062457 -303.028371) (xy 74.02979 -302.984743) (xy 74.003664 -302.936909)
			(xy 73.984613 -302.885844) (xy 73.973023 -302.832588) (xy 73.969131 -302.778224) (xy 73.323491 -302.778224)
			(xy 73.326085 -302.814511) (xy 73.322197 -302.86886) (xy 73.310613 -302.922102) (xy 73.291569 -302.973154)
			(xy 73.265454 -303.020976) (xy 73.232799 -303.064594) (xy 73.194269 -303.103121) (xy 73.150647 -303.135772)
			(xy 73.102823 -303.161883) (xy 73.05177 -303.180922) (xy 72.998526 -303.192501) (xy 72.944177 -303.196385)
			(xy 72.889828 -303.192495) (xy 72.836586 -303.180909) (xy 72.785535 -303.161864) (xy 72.737714 -303.135748)
			(xy 72.715628 -303.11979) (xy 72.696616 -303.106194) (xy 72.654733 -303.085462) (xy 72.609765 -303.072736)
			(xy 72.563228 -303.068446) (xy 72.516691 -303.072736) (xy 72.471723 -303.085462) (xy 72.42984 -303.106194)
			(xy 72.410828 -303.11979) (xy 72.388756 -303.135777) (xy 72.340928 -303.161904) (xy 72.289867 -303.180958)
			(xy 72.236615 -303.192552) (xy 72.182255 -303.196448) (xy 72.127893 -303.192567) (xy 72.074638 -303.180989)
			(xy 72.023572 -303.16195) (xy 71.975736 -303.135836) (xy 71.932104 -303.10318) (xy 71.893563 -303.064646)
			(xy 71.8609 -303.021019) (xy 71.834778 -302.973188) (xy 71.815729 -302.922125) (xy 71.804142 -302.868871)
			(xy 71.800252 -302.814511) (xy 29.73324 -302.814511) (xy 29.73324 -304.958007) (xy 71.800257 -304.958007)
			(xy 71.804144 -304.903647) (xy 71.815729 -304.850393) (xy 71.834774 -304.799331) (xy 71.860894 -304.751499)
			(xy 71.893555 -304.707871) (xy 71.932093 -304.669336) (xy 71.975724 -304.636678) (xy 72.023558 -304.610562)
			(xy 72.074622 -304.59152) (xy 72.127876 -304.57994) (xy 72.182237 -304.576057) (xy 72.236596 -304.579951)
			(xy 72.289849 -304.591541) (xy 72.340909 -304.610593) (xy 72.388738 -304.636718) (xy 72.410828 -304.65268)
			(xy 72.42984 -304.666276) (xy 72.471723 -304.687008) (xy 72.516691 -304.699734) (xy 72.563228 -304.704024)
			(xy 72.609765 -304.699734) (xy 72.654733 -304.687008) (xy 72.696616 -304.666276) (xy 72.715628 -304.65268)
			(xy 72.737727 -304.636739) (xy 72.78555 -304.610624) (xy 72.836602 -304.591581) (xy 72.889845 -304.579998)
			(xy 72.944195 -304.57611) (xy 72.998545 -304.579996) (xy 73.051788 -304.591578) (xy 73.102841 -304.61062)
			(xy 73.150665 -304.636733) (xy 73.194285 -304.669387) (xy 73.232814 -304.707916) (xy 73.265468 -304.751537)
			(xy 73.291581 -304.799361) (xy 73.310622 -304.850414) (xy 73.322204 -304.903657) (xy 73.323495 -304.92172)
			(xy 73.969136 -304.92172) (xy 73.973021 -304.867357) (xy 73.984605 -304.8141) (xy 74.00365 -304.763033)
			(xy 74.02977 -304.715197) (xy 74.062432 -304.671566) (xy 74.100971 -304.633027) (xy 74.144603 -304.600366)
			(xy 74.192439 -304.574247) (xy 74.243506 -304.555203) (xy 74.296763 -304.543621) (xy 74.351127 -304.539736)
			(xy 74.40549 -304.543628) (xy 74.458746 -304.555218) (xy 74.50981 -304.57427) (xy 74.557643 -304.600395)
			(xy 74.579734 -304.616358) (xy 74.598746 -304.629954) (xy 74.640629 -304.650686) (xy 74.685597 -304.663412)
			(xy 74.732134 -304.667702) (xy 74.778671 -304.663412) (xy 74.823639 -304.650686) (xy 74.865522 -304.629954)
			(xy 74.884534 -304.616358) (xy 74.906653 -304.600447) (xy 74.954474 -304.574336) (xy 75.005525 -304.555297)
			(xy 75.058765 -304.543716) (xy 75.113112 -304.539831) (xy 75.167458 -304.54372) (xy 75.220698 -304.555303)
			(xy 75.271747 -304.574346) (xy 75.319566 -304.600459) (xy 75.363183 -304.633113) (xy 75.401708 -304.671641)
			(xy 75.434358 -304.715261) (xy 75.460468 -304.763082) (xy 75.479506 -304.814133) (xy 75.491085 -304.867374)
			(xy 75.494969 -304.92172) (xy 75.491085 -304.975987) (xy 75.993593 -304.975987) (xy 75.997482 -304.921633)
			(xy 76.009068 -304.868385) (xy 76.028114 -304.817329) (xy 76.054233 -304.769503) (xy 76.086893 -304.725882)
			(xy 76.125429 -304.687352) (xy 76.169056 -304.6547) (xy 76.216886 -304.628589) (xy 76.267945 -304.609551)
			(xy 76.321194 -304.597973) (xy 76.375549 -304.594093) (xy 76.429903 -304.597987) (xy 76.483149 -304.609578)
			(xy 76.534204 -304.628629) (xy 76.582027 -304.654753) (xy 76.604114 -304.670714) (xy 76.623126 -304.68431)
			(xy 76.665009 -304.705042) (xy 76.709977 -304.717768) (xy 76.756514 -304.722058) (xy 76.803051 -304.717768)
			(xy 76.848019 -304.705042) (xy 76.889902 -304.68431) (xy 76.908914 -304.670714) (xy 76.930981 -304.654726)
			(xy 76.978807 -304.628604) (xy 77.029864 -304.609555) (xy 77.083112 -304.597967) (xy 77.137467 -304.594074)
			(xy 77.191823 -304.597957) (xy 77.245072 -304.609537) (xy 77.296132 -304.628577) (xy 77.343963 -304.65469)
			(xy 77.38759 -304.687344) (xy 77.426126 -304.725875) (xy 77.458785 -304.769498) (xy 77.484904 -304.817325)
			(xy 77.50395 -304.868383) (xy 77.515536 -304.921631) (xy 77.519426 -304.975987) (xy 78.144509 -304.975987)
			(xy 78.148399 -304.921636) (xy 78.159983 -304.868393) (xy 78.179028 -304.81734) (xy 78.205144 -304.769517)
			(xy 78.237801 -304.725898) (xy 78.276333 -304.687371) (xy 78.319956 -304.654719) (xy 78.367782 -304.628609)
			(xy 78.418837 -304.60957) (xy 78.472082 -304.597992) (xy 78.526433 -304.594109) (xy 78.580783 -304.598002)
			(xy 78.634026 -304.609589) (xy 78.685078 -304.628636) (xy 78.7329 -304.654755) (xy 78.754986 -304.670714)
			(xy 78.773998 -304.68431) (xy 78.815881 -304.705042) (xy 78.860849 -304.717768) (xy 78.907386 -304.722058)
			(xy 78.953923 -304.717768) (xy 78.998891 -304.705042) (xy 79.040774 -304.68431) (xy 79.059786 -304.670714)
			(xy 79.081854 -304.654723) (xy 79.129682 -304.628597) (xy 79.180741 -304.609545) (xy 79.233992 -304.597953)
			(xy 79.288351 -304.594057) (xy 79.342711 -304.597939) (xy 79.395965 -304.609517) (xy 79.447029 -304.628556)
			(xy 79.494863 -304.65467) (xy 79.538494 -304.687326) (xy 79.577034 -304.725858) (xy 79.609696 -304.769484)
			(xy 79.635818 -304.817314) (xy 79.654866 -304.868375) (xy 79.666453 -304.921628) (xy 79.670331 -304.975819)
			(xy 80.373731 -304.975819) (xy 80.377617 -304.921454) (xy 80.389201 -304.868196) (xy 80.408247 -304.817129)
			(xy 80.434368 -304.769292) (xy 80.467031 -304.72566) (xy 80.505571 -304.687121) (xy 80.549204 -304.65446)
			(xy 80.597042 -304.628341) (xy 80.64811 -304.609297) (xy 80.701369 -304.597715) (xy 80.755734 -304.593831)
			(xy 80.810098 -304.597725) (xy 80.863355 -304.609316) (xy 80.914419 -304.628369) (xy 80.962252 -304.654496)
			(xy 80.984344 -304.67046) (xy 81.003356 -304.684056) (xy 81.045239 -304.704788) (xy 81.090207 -304.717514)
			(xy 81.136744 -304.721804) (xy 81.183281 -304.717514) (xy 81.228249 -304.704788) (xy 81.270132 -304.684056)
			(xy 81.289144 -304.67046) (xy 81.311261 -304.654547) (xy 81.359082 -304.628437) (xy 81.410131 -304.609399)
			(xy 81.463371 -304.59782) (xy 81.517716 -304.593935) (xy 81.572061 -304.597825) (xy 81.6253 -304.609408)
			(xy 81.676348 -304.628451) (xy 81.724166 -304.654564) (xy 81.767781 -304.687218) (xy 81.806306 -304.725745)
			(xy 81.838955 -304.769364) (xy 81.865064 -304.817184) (xy 81.884102 -304.868234) (xy 81.89568 -304.921474)
			(xy 81.899565 -304.975819) (xy 81.895675 -305.030164) (xy 81.884091 -305.083403) (xy 81.865048 -305.13445)
			(xy 81.838934 -305.182269) (xy 81.80628 -305.225884) (xy 81.767752 -305.264408) (xy 81.724134 -305.297056)
			(xy 81.676313 -305.323165) (xy 81.625263 -305.342202) (xy 81.572023 -305.353781) (xy 81.517678 -305.357665)
			(xy 81.463333 -305.353775) (xy 81.410094 -305.34219) (xy 81.359047 -305.323147) (xy 81.311229 -305.297032)
			(xy 81.289144 -305.281076) (xy 81.270132 -305.26748) (xy 81.228249 -305.246748) (xy 81.183281 -305.234022)
			(xy 81.136744 -305.229732) (xy 81.090207 -305.234022) (xy 81.045239 -305.246748) (xy 81.003356 -305.26748)
			(xy 80.984344 -305.281076) (xy 80.962285 -305.297083) (xy 80.914454 -305.323215) (xy 80.863392 -305.342273)
			(xy 80.810136 -305.35387) (xy 80.755772 -305.357769) (xy 80.701407 -305.35389) (xy 80.648147 -305.342314)
			(xy 80.597077 -305.323275) (xy 80.549237 -305.297161) (xy 80.5056 -305.264504) (xy 80.467056 -305.225969)
			(xy 80.434388 -305.18234) (xy 80.408263 -305.134506) (xy 80.389212 -305.083441) (xy 80.377623 -305.030184)
			(xy 80.373731 -304.975819) (xy 79.670331 -304.975819) (xy 79.670343 -304.975987) (xy 79.666456 -305.030346)
			(xy 79.654873 -305.083599) (xy 79.635829 -305.134662) (xy 79.609711 -305.182494) (xy 79.577051 -305.226122)
			(xy 79.538514 -305.264657) (xy 79.494886 -305.297316) (xy 79.447053 -305.323433) (xy 79.39599 -305.342476)
			(xy 79.342737 -305.354058) (xy 79.288377 -305.357943) (xy 79.234018 -305.354051) (xy 79.180766 -305.342463)
			(xy 79.129706 -305.323414) (xy 79.081876 -305.297291) (xy 79.059786 -305.28133) (xy 79.040774 -305.267734)
			(xy 78.998891 -305.247002) (xy 78.953923 -305.234276) (xy 78.907386 -305.229986) (xy 78.860849 -305.234276)
			(xy 78.815881 -305.247002) (xy 78.773998 -305.267734) (xy 78.754986 -305.28133) (xy 78.732878 -305.297259)
			(xy 78.685054 -305.323375) (xy 78.634001 -305.342418) (xy 78.580757 -305.354002) (xy 78.526407 -305.357891)
			(xy 78.472056 -305.354004) (xy 78.418812 -305.342422) (xy 78.367758 -305.32338) (xy 78.319934 -305.297267)
			(xy 78.276313 -305.264612) (xy 78.237784 -305.226082) (xy 78.20513 -305.182461) (xy 78.179017 -305.134636)
			(xy 78.159976 -305.083582) (xy 78.148395 -305.030337) (xy 78.144509 -304.975987) (xy 77.519426 -304.975987)
			(xy 77.51554 -305.030342) (xy 77.503958 -305.083592) (xy 77.484915 -305.134651) (xy 77.4588 -305.18248)
			(xy 77.426143 -305.226105) (xy 77.38761 -305.264639) (xy 77.343985 -305.297296) (xy 77.296156 -305.323412)
			(xy 77.245098 -305.342456) (xy 77.191849 -305.354039) (xy 77.137493 -305.357926) (xy 77.083138 -305.354037)
			(xy 77.029889 -305.342452) (xy 76.978831 -305.323407) (xy 76.931003 -305.297289) (xy 76.908914 -305.28133)
			(xy 76.889902 -305.267734) (xy 76.848019 -305.247002) (xy 76.803051 -305.234276) (xy 76.756514 -305.229986)
			(xy 76.709977 -305.234276) (xy 76.665009 -305.247002) (xy 76.623126 -305.267734) (xy 76.604114 -305.28133)
			(xy 76.582005 -305.297261) (xy 76.53418 -305.323382) (xy 76.483124 -305.342429) (xy 76.429877 -305.354016)
			(xy 76.375523 -305.357907) (xy 76.321168 -305.354023) (xy 76.26792 -305.342442) (xy 76.216862 -305.3234)
			(xy 76.169033 -305.297286) (xy 76.125409 -305.26463) (xy 76.086876 -305.226098) (xy 76.054219 -305.182475)
			(xy 76.028103 -305.134647) (xy 76.009061 -305.083589) (xy 75.997479 -305.030341) (xy 75.993593 -304.975987)
			(xy 75.491085 -304.975987) (xy 75.491079 -304.976067) (xy 75.479494 -305.029306) (xy 75.460451 -305.080355)
			(xy 75.434336 -305.128174) (xy 75.401681 -305.171789) (xy 75.363152 -305.210314) (xy 75.319532 -305.242963)
			(xy 75.27171 -305.269071) (xy 75.220659 -305.288108) (xy 75.167418 -305.299686) (xy 75.113071 -305.303569)
			(xy 75.058725 -305.299678) (xy 75.005486 -305.288092) (xy 74.954437 -305.269047) (xy 74.906619 -305.242931)
			(xy 74.884534 -305.226974) (xy 74.865522 -305.213378) (xy 74.823639 -305.192646) (xy 74.778671 -305.17992)
			(xy 74.732134 -305.17563) (xy 74.685597 -305.17992) (xy 74.640629 -305.192646) (xy 74.598746 -305.213378)
			(xy 74.579734 -305.226974) (xy 74.557677 -305.242983) (xy 74.509847 -305.269113) (xy 74.458785 -305.28817)
			(xy 74.405531 -305.299766) (xy 74.351168 -305.303664) (xy 74.296804 -305.299785) (xy 74.243545 -305.288209)
			(xy 74.192476 -305.26917) (xy 74.144637 -305.243056) (xy 74.101002 -305.2104) (xy 74.062458 -305.171865)
			(xy 74.029792 -305.128237) (xy 74.003667 -305.080404) (xy 73.984616 -305.02934) (xy 73.973027 -304.976084)
			(xy 73.969136 -304.92172) (xy 73.323495 -304.92172) (xy 73.32609 -304.958007) (xy 73.322202 -305.012357)
			(xy 73.310618 -305.0656) (xy 73.291575 -305.116652) (xy 73.26546 -305.164475) (xy 73.232805 -305.208094)
			(xy 73.194274 -305.246622) (xy 73.150653 -305.279274) (xy 73.102828 -305.305386) (xy 73.051774 -305.324426)
			(xy 72.998531 -305.336006) (xy 72.944181 -305.33989) (xy 72.889831 -305.336) (xy 72.836588 -305.324415)
			(xy 72.785537 -305.30537) (xy 72.737715 -305.279254) (xy 72.715628 -305.263296) (xy 72.696616 -305.2497)
			(xy 72.654733 -305.228968) (xy 72.609765 -305.216242) (xy 72.563228 -305.211952) (xy 72.516691 -305.216242)
			(xy 72.471723 -305.228968) (xy 72.42984 -305.2497) (xy 72.410828 -305.263296) (xy 72.38875 -305.279275)
			(xy 72.340922 -305.305401) (xy 72.289863 -305.324455) (xy 72.236611 -305.336047) (xy 72.182251 -305.339943)
			(xy 72.127891 -305.336062) (xy 72.074636 -305.324484) (xy 72.023571 -305.305444) (xy 71.975736 -305.27933)
			(xy 71.932104 -305.246674) (xy 71.893565 -305.20814) (xy 71.860902 -305.164513) (xy 71.83478 -305.116682)
			(xy 71.815733 -305.06562) (xy 71.804146 -305.012367) (xy 71.800257 -304.958007) (xy 29.73324 -304.958007)
			(xy 29.73324 -306.423737) (xy 47.775358 -306.423737) (xy 47.775358 -306.342627) (xy 47.783308 -306.261908)
			(xy 47.799131 -306.182357) (xy 47.822676 -306.104741) (xy 47.853715 -306.029805) (xy 47.89195 -305.958273)
			(xy 47.937012 -305.890833) (xy 47.988467 -305.828134) (xy 48.04582 -305.770781) (xy 48.108519 -305.719326)
			(xy 48.175959 -305.674264) (xy 48.247491 -305.636029) (xy 48.322427 -305.60499) (xy 48.400043 -305.581445)
			(xy 48.479594 -305.565622) (xy 48.560313 -305.557672) (xy 48.641423 -305.557672) (xy 48.722142 -305.565622)
			(xy 48.801693 -305.581445) (xy 48.879309 -305.60499) (xy 48.954245 -305.636029) (xy 49.025777 -305.674264)
			(xy 49.093217 -305.719326) (xy 49.155916 -305.770781) (xy 49.213269 -305.828134) (xy 49.264724 -305.890833)
			(xy 49.309786 -305.958273) (xy 49.348021 -306.029805) (xy 49.37906 -306.104741) (xy 49.402605 -306.182357)
			(xy 49.418428 -306.261908) (xy 49.426378 -306.342627) (xy 49.426876 -306.383182) (xy 49.426378 -306.423737)
			(xy 51.275478 -306.423737) (xy 51.275478 -306.342627) (xy 51.283428 -306.261908) (xy 51.299251 -306.182357)
			(xy 51.322796 -306.104741) (xy 51.353835 -306.029805) (xy 51.39207 -305.958273) (xy 51.437132 -305.890833)
			(xy 51.488587 -305.828134) (xy 51.54594 -305.770781) (xy 51.608639 -305.719326) (xy 51.676079 -305.674264)
			(xy 51.747611 -305.636029) (xy 51.822547 -305.60499) (xy 51.900163 -305.581445) (xy 51.979714 -305.565622)
			(xy 52.060433 -305.557672) (xy 52.141543 -305.557672) (xy 52.222262 -305.565622) (xy 52.301813 -305.581445)
			(xy 52.379429 -305.60499) (xy 52.454365 -305.636029) (xy 52.525897 -305.674264) (xy 52.593337 -305.719326)
			(xy 52.656036 -305.770781) (xy 52.713389 -305.828134) (xy 52.764844 -305.890833) (xy 52.809906 -305.958273)
			(xy 52.848141 -306.029805) (xy 52.87918 -306.104741) (xy 52.902725 -306.182357) (xy 52.918548 -306.261908)
			(xy 52.926498 -306.342627) (xy 52.926996 -306.383182) (xy 52.926498 -306.423737) (xy 52.918548 -306.504456)
			(xy 52.902725 -306.584007) (xy 52.87918 -306.661623) (xy 52.848141 -306.736559) (xy 52.809906 -306.808091)
			(xy 52.764844 -306.875531) (xy 52.713389 -306.93823) (xy 52.656036 -306.995583) (xy 52.593337 -307.047038)
			(xy 52.525897 -307.0921) (xy 52.454365 -307.130335) (xy 52.379429 -307.161374) (xy 52.301813 -307.184919)
			(xy 52.222262 -307.200742) (xy 52.141543 -307.208692) (xy 52.060433 -307.208692) (xy 51.979714 -307.200742)
			(xy 51.900163 -307.184919) (xy 51.822547 -307.161374) (xy 51.747611 -307.130335) (xy 51.676079 -307.0921)
			(xy 51.608639 -307.047038) (xy 51.54594 -306.995583) (xy 51.488587 -306.93823) (xy 51.437132 -306.875531)
			(xy 51.39207 -306.808091) (xy 51.353835 -306.736559) (xy 51.322796 -306.661623) (xy 51.299251 -306.584007)
			(xy 51.283428 -306.504456) (xy 51.275478 -306.423737) (xy 49.426378 -306.423737) (xy 49.418428 -306.504456)
			(xy 49.402605 -306.584007) (xy 49.37906 -306.661623) (xy 49.348021 -306.736559) (xy 49.309786 -306.808091)
			(xy 49.264724 -306.875531) (xy 49.213269 -306.93823) (xy 49.155916 -306.995583) (xy 49.093217 -307.047038)
			(xy 49.025777 -307.0921) (xy 48.954245 -307.130335) (xy 48.879309 -307.161374) (xy 48.801693 -307.184919)
			(xy 48.722142 -307.200742) (xy 48.641423 -307.208692) (xy 48.560313 -307.208692) (xy 48.479594 -307.200742)
			(xy 48.400043 -307.184919) (xy 48.322427 -307.161374) (xy 48.247491 -307.130335) (xy 48.175959 -307.0921)
			(xy 48.108519 -307.047038) (xy 48.04582 -306.995583) (xy 47.988467 -306.93823) (xy 47.937012 -306.875531)
			(xy 47.89195 -306.808091) (xy 47.853715 -306.736559) (xy 47.822676 -306.661623) (xy 47.799131 -306.584007)
			(xy 47.783308 -306.504456) (xy 47.775358 -306.423737) (xy 29.73324 -306.423737) (xy 29.73324 -318.06007)
			(xy 39.818564 -318.06007) (xy 39.819058 -318.002661) (xy 39.826902 -317.888113) (xy 39.842544 -317.774366)
			(xy 39.865911 -317.661952) (xy 39.896896 -317.551394) (xy 39.935352 -317.443209) (xy 39.981101 -317.3379)
			(xy 40.03393 -317.235958) (xy 40.093592 -317.137859) (xy 40.159809 -317.04406) (xy 40.232272 -316.954998)
			(xy 40.310645 -316.871089) (xy 40.39456 -316.792723) (xy 40.483627 -316.720266) (xy 40.577431 -316.654056)
			(xy 40.675535 -316.594402) (xy 40.777481 -316.541581) (xy 40.882793 -316.495839) (xy 40.990981 -316.457391)
			(xy 41.101541 -316.426415) (xy 41.213957 -316.403056) (xy 41.327705 -316.387423) (xy 41.442254 -316.379588)
			(xy 41.557072 -316.379588) (xy 41.671621 -316.387423) (xy 41.785369 -316.403056) (xy 41.897785 -316.426415)
			(xy 42.008345 -316.457391) (xy 42.116533 -316.495839) (xy 42.221845 -316.541581) (xy 42.323791 -316.594402)
			(xy 42.421895 -316.654056) (xy 42.501239 -316.71006) (xy 63.647577 -316.71006) (xy 63.651612 -316.634356)
			(xy 63.663671 -316.559511) (xy 63.683617 -316.48637) (xy 63.711224 -316.415765) (xy 63.74618 -316.348494)
			(xy 63.788088 -316.285319) (xy 63.836474 -316.226957) (xy 63.89079 -316.174069) (xy 63.950419 -316.127254)
			(xy 64.014687 -316.087042) (xy 64.082864 -316.05389) (xy 64.15418 -316.028172) (xy 64.227825 -316.01018)
			(xy 64.302965 -316.000118) (xy 64.378749 -315.998099) (xy 64.454319 -316.004148) (xy 64.528817 -316.018195)
			(xy 64.6014 -316.040081) (xy 64.671246 -316.069558) (xy 64.737563 -316.106293) (xy 64.799599 -316.149868)
			(xy 64.856652 -316.19979) (xy 64.908076 -316.255494) (xy 64.953287 -316.316349) (xy 64.991774 -316.381664)
			(xy 65.0231 -316.4507) (xy 65.04691 -316.522675) (xy 65.062935 -316.596773) (xy 65.070994 -316.672154)
			(xy 65.071498 -316.71006) (xy 66.187577 -316.71006) (xy 66.191612 -316.634356) (xy 66.203671 -316.559511)
			(xy 66.223617 -316.48637) (xy 66.251224 -316.415765) (xy 66.28618 -316.348494) (xy 66.328088 -316.285319)
			(xy 66.376474 -316.226957) (xy 66.43079 -316.174069) (xy 66.490419 -316.127254) (xy 66.554687 -316.087042)
			(xy 66.622864 -316.05389) (xy 66.69418 -316.028172) (xy 66.767825 -316.01018) (xy 66.842965 -316.000118)
			(xy 66.918749 -315.998099) (xy 66.994319 -316.004148) (xy 67.068817 -316.018195) (xy 67.1414 -316.040081)
			(xy 67.211246 -316.069558) (xy 67.277563 -316.106293) (xy 67.339599 -316.149868) (xy 67.396652 -316.19979)
			(xy 67.448076 -316.255494) (xy 67.493287 -316.316349) (xy 67.531774 -316.381664) (xy 67.5631 -316.4507)
			(xy 67.58691 -316.522675) (xy 67.602935 -316.596773) (xy 67.610994 -316.672154) (xy 67.611498 -316.71006)
			(xy 68.727577 -316.71006) (xy 68.731612 -316.634356) (xy 68.743671 -316.559511) (xy 68.763617 -316.48637)
			(xy 68.791224 -316.415765) (xy 68.82618 -316.348494) (xy 68.868088 -316.285319) (xy 68.916474 -316.226957)
			(xy 68.97079 -316.174069) (xy 69.030419 -316.127254) (xy 69.094687 -316.087042) (xy 69.162864 -316.05389)
			(xy 69.23418 -316.028172) (xy 69.307825 -316.01018) (xy 69.382965 -316.000118) (xy 69.458749 -315.998099)
			(xy 69.534319 -316.004148) (xy 69.608817 -316.018195) (xy 69.6814 -316.040081) (xy 69.751246 -316.069558)
			(xy 69.817563 -316.106293) (xy 69.879599 -316.149868) (xy 69.936652 -316.19979) (xy 69.988076 -316.255494)
			(xy 70.033287 -316.316349) (xy 70.071774 -316.381664) (xy 70.1031 -316.4507) (xy 70.12691 -316.522675)
			(xy 70.142935 -316.596773) (xy 70.150994 -316.672154) (xy 70.151498 -316.71006) (xy 71.267577 -316.71006)
			(xy 71.271612 -316.634356) (xy 71.283671 -316.559511) (xy 71.303617 -316.48637) (xy 71.331224 -316.415765)
			(xy 71.36618 -316.348494) (xy 71.408088 -316.285319) (xy 71.456474 -316.226957) (xy 71.51079 -316.174069)
			(xy 71.570419 -316.127254) (xy 71.634687 -316.087042) (xy 71.702864 -316.05389) (xy 71.77418 -316.028172)
			(xy 71.847825 -316.01018) (xy 71.922965 -316.000118) (xy 71.998749 -315.998099) (xy 72.074319 -316.004148)
			(xy 72.148817 -316.018195) (xy 72.2214 -316.040081) (xy 72.291246 -316.069558) (xy 72.357563 -316.106293)
			(xy 72.419599 -316.149868) (xy 72.476652 -316.19979) (xy 72.528076 -316.255494) (xy 72.573287 -316.316349)
			(xy 72.611774 -316.381664) (xy 72.6431 -316.4507) (xy 72.66691 -316.522675) (xy 72.682935 -316.596773)
			(xy 72.690994 -316.672154) (xy 72.691498 -316.71006) (xy 73.807577 -316.71006) (xy 73.811612 -316.634356)
			(xy 73.823671 -316.559511) (xy 73.843617 -316.48637) (xy 73.871224 -316.415765) (xy 73.90618 -316.348494)
			(xy 73.948088 -316.285319) (xy 73.996474 -316.226957) (xy 74.05079 -316.174069) (xy 74.110419 -316.127254)
			(xy 74.174687 -316.087042) (xy 74.242864 -316.05389) (xy 74.31418 -316.028172) (xy 74.387825 -316.01018)
			(xy 74.462965 -316.000118) (xy 74.538749 -315.998099) (xy 74.614319 -316.004148) (xy 74.688817 -316.018195)
			(xy 74.7614 -316.040081) (xy 74.831246 -316.069558) (xy 74.897563 -316.106293) (xy 74.959599 -316.149868)
			(xy 75.016652 -316.19979) (xy 75.068076 -316.255494) (xy 75.113287 -316.316349) (xy 75.151774 -316.381664)
			(xy 75.1831 -316.4507) (xy 75.20691 -316.522675) (xy 75.222935 -316.596773) (xy 75.230994 -316.672154)
			(xy 75.231498 -316.71006) (xy 76.347577 -316.71006) (xy 76.351612 -316.634356) (xy 76.363671 -316.559511)
			(xy 76.383617 -316.48637) (xy 76.411224 -316.415765) (xy 76.44618 -316.348494) (xy 76.488088 -316.285319)
			(xy 76.536474 -316.226957) (xy 76.59079 -316.174069) (xy 76.650419 -316.127254) (xy 76.714687 -316.087042)
			(xy 76.782864 -316.05389) (xy 76.85418 -316.028172) (xy 76.927825 -316.01018) (xy 77.002965 -316.000118)
			(xy 77.078749 -315.998099) (xy 77.154319 -316.004148) (xy 77.228817 -316.018195) (xy 77.3014 -316.040081)
			(xy 77.371246 -316.069558) (xy 77.437563 -316.106293) (xy 77.499599 -316.149868) (xy 77.556652 -316.19979)
			(xy 77.608076 -316.255494) (xy 77.653287 -316.316349) (xy 77.691774 -316.381664) (xy 77.7231 -316.4507)
			(xy 77.74691 -316.522675) (xy 77.762935 -316.596773) (xy 77.770994 -316.672154) (xy 77.771498 -316.71006)
			(xy 78.887577 -316.71006) (xy 78.891612 -316.634356) (xy 78.903671 -316.559511) (xy 78.923617 -316.48637)
			(xy 78.951224 -316.415765) (xy 78.98618 -316.348494) (xy 79.028088 -316.285319) (xy 79.076474 -316.226957)
			(xy 79.13079 -316.174069) (xy 79.190419 -316.127254) (xy 79.254687 -316.087042) (xy 79.322864 -316.05389)
			(xy 79.39418 -316.028172) (xy 79.467825 -316.01018) (xy 79.542965 -316.000118) (xy 79.618749 -315.998099)
			(xy 79.694319 -316.004148) (xy 79.768817 -316.018195) (xy 79.8414 -316.040081) (xy 79.911246 -316.069558)
			(xy 79.977563 -316.106293) (xy 80.039599 -316.149868) (xy 80.096652 -316.19979) (xy 80.148076 -316.255494)
			(xy 80.193287 -316.316349) (xy 80.231774 -316.381664) (xy 80.2631 -316.4507) (xy 80.28691 -316.522675)
			(xy 80.302935 -316.596773) (xy 80.310994 -316.672154) (xy 80.311498 -316.71006) (xy 80.310994 -316.747966)
			(xy 80.302935 -316.823347) (xy 80.28691 -316.897445) (xy 80.2631 -316.96942) (xy 80.231774 -317.038456)
			(xy 80.193287 -317.103771) (xy 80.148076 -317.164626) (xy 80.096652 -317.22033) (xy 80.039599 -317.270252)
			(xy 79.977563 -317.313827) (xy 79.911246 -317.350562) (xy 79.8414 -317.380039) (xy 79.768817 -317.401925)
			(xy 79.694319 -317.415972) (xy 79.618749 -317.422021) (xy 79.542965 -317.420002) (xy 79.467825 -317.40994)
			(xy 79.39418 -317.391948) (xy 79.322864 -317.36623) (xy 79.254687 -317.333078) (xy 79.190419 -317.292866)
			(xy 79.13079 -317.246051) (xy 79.076474 -317.193163) (xy 79.028088 -317.134801) (xy 78.98618 -317.071626)
			(xy 78.951224 -317.004355) (xy 78.923617 -316.93375) (xy 78.903671 -316.860609) (xy 78.891612 -316.785764)
			(xy 78.887577 -316.71006) (xy 77.771498 -316.71006) (xy 77.770994 -316.747966) (xy 77.762935 -316.823347)
			(xy 77.74691 -316.897445) (xy 77.7231 -316.96942) (xy 77.691774 -317.038456) (xy 77.653287 -317.103771)
			(xy 77.608076 -317.164626) (xy 77.556652 -317.22033) (xy 77.499599 -317.270252) (xy 77.437563 -317.313827)
			(xy 77.371246 -317.350562) (xy 77.3014 -317.380039) (xy 77.228817 -317.401925) (xy 77.154319 -317.415972)
			(xy 77.078749 -317.422021) (xy 77.002965 -317.420002) (xy 76.927825 -317.40994) (xy 76.85418 -317.391948)
			(xy 76.782864 -317.36623) (xy 76.714687 -317.333078) (xy 76.650419 -317.292866) (xy 76.59079 -317.246051)
			(xy 76.536474 -317.193163) (xy 76.488088 -317.134801) (xy 76.44618 -317.071626) (xy 76.411224 -317.004355)
			(xy 76.383617 -316.93375) (xy 76.363671 -316.860609) (xy 76.351612 -316.785764) (xy 76.347577 -316.71006)
			(xy 75.231498 -316.71006) (xy 75.230994 -316.747966) (xy 75.222935 -316.823347) (xy 75.20691 -316.897445)
			(xy 75.1831 -316.96942) (xy 75.151774 -317.038456) (xy 75.113287 -317.103771) (xy 75.068076 -317.164626)
			(xy 75.016652 -317.22033) (xy 74.959599 -317.270252) (xy 74.897563 -317.313827) (xy 74.831246 -317.350562)
			(xy 74.7614 -317.380039) (xy 74.688817 -317.401925) (xy 74.614319 -317.415972) (xy 74.538749 -317.422021)
			(xy 74.462965 -317.420002) (xy 74.387825 -317.40994) (xy 74.31418 -317.391948) (xy 74.242864 -317.36623)
			(xy 74.174687 -317.333078) (xy 74.110419 -317.292866) (xy 74.05079 -317.246051) (xy 73.996474 -317.193163)
			(xy 73.948088 -317.134801) (xy 73.90618 -317.071626) (xy 73.871224 -317.004355) (xy 73.843617 -316.93375)
			(xy 73.823671 -316.860609) (xy 73.811612 -316.785764) (xy 73.807577 -316.71006) (xy 72.691498 -316.71006)
			(xy 72.690994 -316.747966) (xy 72.682935 -316.823347) (xy 72.66691 -316.897445) (xy 72.6431 -316.96942)
			(xy 72.611774 -317.038456) (xy 72.573287 -317.103771) (xy 72.528076 -317.164626) (xy 72.476652 -317.22033)
			(xy 72.419599 -317.270252) (xy 72.357563 -317.313827) (xy 72.291246 -317.350562) (xy 72.2214 -317.380039)
			(xy 72.148817 -317.401925) (xy 72.074319 -317.415972) (xy 71.998749 -317.422021) (xy 71.922965 -317.420002)
			(xy 71.847825 -317.40994) (xy 71.77418 -317.391948) (xy 71.702864 -317.36623) (xy 71.634687 -317.333078)
			(xy 71.570419 -317.292866) (xy 71.51079 -317.246051) (xy 71.456474 -317.193163) (xy 71.408088 -317.134801)
			(xy 71.36618 -317.071626) (xy 71.331224 -317.004355) (xy 71.303617 -316.93375) (xy 71.283671 -316.860609)
			(xy 71.271612 -316.785764) (xy 71.267577 -316.71006) (xy 70.151498 -316.71006) (xy 70.150994 -316.747966)
			(xy 70.142935 -316.823347) (xy 70.12691 -316.897445) (xy 70.1031 -316.96942) (xy 70.071774 -317.038456)
			(xy 70.033287 -317.103771) (xy 69.988076 -317.164626) (xy 69.936652 -317.22033) (xy 69.879599 -317.270252)
			(xy 69.817563 -317.313827) (xy 69.751246 -317.350562) (xy 69.6814 -317.380039) (xy 69.608817 -317.401925)
			(xy 69.534319 -317.415972) (xy 69.458749 -317.422021) (xy 69.382965 -317.420002) (xy 69.307825 -317.40994)
			(xy 69.23418 -317.391948) (xy 69.162864 -317.36623) (xy 69.094687 -317.333078) (xy 69.030419 -317.292866)
			(xy 68.97079 -317.246051) (xy 68.916474 -317.193163) (xy 68.868088 -317.134801) (xy 68.82618 -317.071626)
			(xy 68.791224 -317.004355) (xy 68.763617 -316.93375) (xy 68.743671 -316.860609) (xy 68.731612 -316.785764)
			(xy 68.727577 -316.71006) (xy 67.611498 -316.71006) (xy 67.610994 -316.747966) (xy 67.602935 -316.823347)
			(xy 67.58691 -316.897445) (xy 67.5631 -316.96942) (xy 67.531774 -317.038456) (xy 67.493287 -317.103771)
			(xy 67.448076 -317.164626) (xy 67.396652 -317.22033) (xy 67.339599 -317.270252) (xy 67.277563 -317.313827)
			(xy 67.211246 -317.350562) (xy 67.1414 -317.380039) (xy 67.068817 -317.401925) (xy 66.994319 -317.415972)
			(xy 66.918749 -317.422021) (xy 66.842965 -317.420002) (xy 66.767825 -317.40994) (xy 66.69418 -317.391948)
			(xy 66.622864 -317.36623) (xy 66.554687 -317.333078) (xy 66.490419 -317.292866) (xy 66.43079 -317.246051)
			(xy 66.376474 -317.193163) (xy 66.328088 -317.134801) (xy 66.28618 -317.071626) (xy 66.251224 -317.004355)
			(xy 66.223617 -316.93375) (xy 66.203671 -316.860609) (xy 66.191612 -316.785764) (xy 66.187577 -316.71006)
			(xy 65.071498 -316.71006) (xy 65.070994 -316.747966) (xy 65.062935 -316.823347) (xy 65.04691 -316.897445)
			(xy 65.0231 -316.96942) (xy 64.991774 -317.038456) (xy 64.953287 -317.103771) (xy 64.908076 -317.164626)
			(xy 64.856652 -317.22033) (xy 64.799599 -317.270252) (xy 64.737563 -317.313827) (xy 64.671246 -317.350562)
			(xy 64.6014 -317.380039) (xy 64.528817 -317.401925) (xy 64.454319 -317.415972) (xy 64.378749 -317.422021)
			(xy 64.302965 -317.420002) (xy 64.227825 -317.40994) (xy 64.15418 -317.391948) (xy 64.082864 -317.36623)
			(xy 64.014687 -317.333078) (xy 63.950419 -317.292866) (xy 63.89079 -317.246051) (xy 63.836474 -317.193163)
			(xy 63.788088 -317.134801) (xy 63.74618 -317.071626) (xy 63.711224 -317.004355) (xy 63.683617 -316.93375)
			(xy 63.663671 -316.860609) (xy 63.651612 -316.785764) (xy 63.647577 -316.71006) (xy 42.501239 -316.71006)
			(xy 42.515699 -316.720266) (xy 42.604766 -316.792723) (xy 42.688681 -316.871089) (xy 42.767054 -316.954998)
			(xy 42.839517 -317.04406) (xy 42.905734 -317.137859) (xy 42.965396 -317.235958) (xy 43.018225 -317.3379)
			(xy 43.063974 -317.443209) (xy 43.10243 -317.551394) (xy 43.133415 -317.661952) (xy 43.156782 -317.774366)
			(xy 43.172424 -317.888113) (xy 43.180268 -318.002661) (xy 43.180762 -318.06007) (xy 43.180576 -318.093253)
			(xy 43.177909 -318.159567) (xy 43.175428 -318.192658) (xy 43.170272 -318.250942) (xy 43.152948 -318.366671)
			(xy 43.127616 -318.480914) (xy 43.094401 -318.593119) (xy 43.053462 -318.702742) (xy 43.004999 -318.809253)
			(xy 42.949245 -318.912135) (xy 42.886471 -319.010891) (xy 42.816981 -319.105042) (xy 42.741111 -319.194132)
			(xy 42.659229 -319.277729) (xy 42.571732 -319.35543) (xy 42.500813 -319.41008) (xy 63.647577 -319.41008)
			(xy 63.651612 -319.334376) (xy 63.663671 -319.259531) (xy 63.683617 -319.18639) (xy 63.711224 -319.115785)
			(xy 63.74618 -319.048514) (xy 63.788088 -318.985339) (xy 63.836474 -318.926977) (xy 63.89079 -318.874089)
			(xy 63.950419 -318.827274) (xy 64.014687 -318.787062) (xy 64.082864 -318.75391) (xy 64.15418 -318.728192)
			(xy 64.227825 -318.7102) (xy 64.302965 -318.700138) (xy 64.378749 -318.698119) (xy 64.454319 -318.704168)
			(xy 64.528817 -318.718215) (xy 64.6014 -318.740101) (xy 64.671246 -318.769578) (xy 64.737563 -318.806313)
			(xy 64.799599 -318.849888) (xy 64.856652 -318.89981) (xy 64.908076 -318.955514) (xy 64.953287 -319.016369)
			(xy 64.991774 -319.081684) (xy 65.0231 -319.15072) (xy 65.04691 -319.222695) (xy 65.062935 -319.296793)
			(xy 65.070994 -319.372174) (xy 65.071498 -319.41008) (xy 66.187577 -319.41008) (xy 66.191612 -319.334376)
			(xy 66.203671 -319.259531) (xy 66.223617 -319.18639) (xy 66.251224 -319.115785) (xy 66.28618 -319.048514)
			(xy 66.328088 -318.985339) (xy 66.376474 -318.926977) (xy 66.43079 -318.874089) (xy 66.490419 -318.827274)
			(xy 66.554687 -318.787062) (xy 66.622864 -318.75391) (xy 66.69418 -318.728192) (xy 66.767825 -318.7102)
			(xy 66.842965 -318.700138) (xy 66.918749 -318.698119) (xy 66.994319 -318.704168) (xy 67.068817 -318.718215)
			(xy 67.1414 -318.740101) (xy 67.211246 -318.769578) (xy 67.277563 -318.806313) (xy 67.339599 -318.849888)
			(xy 67.396652 -318.89981) (xy 67.448076 -318.955514) (xy 67.493287 -319.016369) (xy 67.531774 -319.081684)
			(xy 67.5631 -319.15072) (xy 67.58691 -319.222695) (xy 67.602935 -319.296793) (xy 67.610994 -319.372174)
			(xy 67.611498 -319.41008) (xy 68.727577 -319.41008) (xy 68.731612 -319.334376) (xy 68.743671 -319.259531)
			(xy 68.763617 -319.18639) (xy 68.791224 -319.115785) (xy 68.82618 -319.048514) (xy 68.868088 -318.985339)
			(xy 68.916474 -318.926977) (xy 68.97079 -318.874089) (xy 69.030419 -318.827274) (xy 69.094687 -318.787062)
			(xy 69.162864 -318.75391) (xy 69.23418 -318.728192) (xy 69.307825 -318.7102) (xy 69.382965 -318.700138)
			(xy 69.458749 -318.698119) (xy 69.534319 -318.704168) (xy 69.608817 -318.718215) (xy 69.6814 -318.740101)
			(xy 69.751246 -318.769578) (xy 69.817563 -318.806313) (xy 69.879599 -318.849888) (xy 69.936652 -318.89981)
			(xy 69.988076 -318.955514) (xy 70.033287 -319.016369) (xy 70.071774 -319.081684) (xy 70.1031 -319.15072)
			(xy 70.12691 -319.222695) (xy 70.142935 -319.296793) (xy 70.150994 -319.372174) (xy 70.151498 -319.41008)
			(xy 71.267577 -319.41008) (xy 71.271612 -319.334376) (xy 71.283671 -319.259531) (xy 71.303617 -319.18639)
			(xy 71.331224 -319.115785) (xy 71.36618 -319.048514) (xy 71.408088 -318.985339) (xy 71.456474 -318.926977)
			(xy 71.51079 -318.874089) (xy 71.570419 -318.827274) (xy 71.634687 -318.787062) (xy 71.702864 -318.75391)
			(xy 71.77418 -318.728192) (xy 71.847825 -318.7102) (xy 71.922965 -318.700138) (xy 71.998749 -318.698119)
			(xy 72.074319 -318.704168) (xy 72.148817 -318.718215) (xy 72.2214 -318.740101) (xy 72.291246 -318.769578)
			(xy 72.357563 -318.806313) (xy 72.419599 -318.849888) (xy 72.476652 -318.89981) (xy 72.528076 -318.955514)
			(xy 72.573287 -319.016369) (xy 72.611774 -319.081684) (xy 72.6431 -319.15072) (xy 72.66691 -319.222695)
			(xy 72.682935 -319.296793) (xy 72.690994 -319.372174) (xy 72.691498 -319.41008) (xy 73.807577 -319.41008)
			(xy 73.811612 -319.334376) (xy 73.823671 -319.259531) (xy 73.843617 -319.18639) (xy 73.871224 -319.115785)
			(xy 73.90618 -319.048514) (xy 73.948088 -318.985339) (xy 73.996474 -318.926977) (xy 74.05079 -318.874089)
			(xy 74.110419 -318.827274) (xy 74.174687 -318.787062) (xy 74.242864 -318.75391) (xy 74.31418 -318.728192)
			(xy 74.387825 -318.7102) (xy 74.462965 -318.700138) (xy 74.538749 -318.698119) (xy 74.614319 -318.704168)
			(xy 74.688817 -318.718215) (xy 74.7614 -318.740101) (xy 74.831246 -318.769578) (xy 74.897563 -318.806313)
			(xy 74.959599 -318.849888) (xy 75.016652 -318.89981) (xy 75.068076 -318.955514) (xy 75.113287 -319.016369)
			(xy 75.151774 -319.081684) (xy 75.1831 -319.15072) (xy 75.20691 -319.222695) (xy 75.222935 -319.296793)
			(xy 75.230994 -319.372174) (xy 75.231498 -319.41008) (xy 76.347577 -319.41008) (xy 76.351612 -319.334376)
			(xy 76.363671 -319.259531) (xy 76.383617 -319.18639) (xy 76.411224 -319.115785) (xy 76.44618 -319.048514)
			(xy 76.488088 -318.985339) (xy 76.536474 -318.926977) (xy 76.59079 -318.874089) (xy 76.650419 -318.827274)
			(xy 76.714687 -318.787062) (xy 76.782864 -318.75391) (xy 76.85418 -318.728192) (xy 76.927825 -318.7102)
			(xy 77.002965 -318.700138) (xy 77.078749 -318.698119) (xy 77.154319 -318.704168) (xy 77.228817 -318.718215)
			(xy 77.3014 -318.740101) (xy 77.371246 -318.769578) (xy 77.437563 -318.806313) (xy 77.499599 -318.849888)
			(xy 77.556652 -318.89981) (xy 77.608076 -318.955514) (xy 77.653287 -319.016369) (xy 77.691774 -319.081684)
			(xy 77.7231 -319.15072) (xy 77.74691 -319.222695) (xy 77.762935 -319.296793) (xy 77.770994 -319.372174)
			(xy 77.771498 -319.41008) (xy 78.887577 -319.41008) (xy 78.891612 -319.334376) (xy 78.903671 -319.259531)
			(xy 78.923617 -319.18639) (xy 78.951224 -319.115785) (xy 78.98618 -319.048514) (xy 79.028088 -318.985339)
			(xy 79.076474 -318.926977) (xy 79.13079 -318.874089) (xy 79.190419 -318.827274) (xy 79.254687 -318.787062)
			(xy 79.322864 -318.75391) (xy 79.39418 -318.728192) (xy 79.467825 -318.7102) (xy 79.542965 -318.700138)
			(xy 79.618749 -318.698119) (xy 79.694319 -318.704168) (xy 79.768817 -318.718215) (xy 79.8414 -318.740101)
			(xy 79.911246 -318.769578) (xy 79.977563 -318.806313) (xy 80.039599 -318.849888) (xy 80.096652 -318.89981)
			(xy 80.148076 -318.955514) (xy 80.193287 -319.016369) (xy 80.231774 -319.081684) (xy 80.2631 -319.15072)
			(xy 80.28691 -319.222695) (xy 80.302935 -319.296793) (xy 80.310994 -319.372174) (xy 80.311498 -319.41008)
			(xy 80.310994 -319.447986) (xy 80.302935 -319.523367) (xy 80.28691 -319.597465) (xy 80.2631 -319.66944)
			(xy 80.231774 -319.738476) (xy 80.193287 -319.803791) (xy 80.148076 -319.864646) (xy 80.096652 -319.92035)
			(xy 80.039599 -319.970272) (xy 79.977563 -320.013847) (xy 79.911246 -320.050582) (xy 79.8414 -320.080059)
			(xy 79.768817 -320.101945) (xy 79.694319 -320.115992) (xy 79.618749 -320.122041) (xy 79.542965 -320.120022)
			(xy 79.467825 -320.10996) (xy 79.39418 -320.091968) (xy 79.322864 -320.06625) (xy 79.254687 -320.033098)
			(xy 79.190419 -319.992886) (xy 79.13079 -319.946071) (xy 79.076474 -319.893183) (xy 79.028088 -319.834821)
			(xy 78.98618 -319.771646) (xy 78.951224 -319.704375) (xy 78.923617 -319.63377) (xy 78.903671 -319.560629)
			(xy 78.891612 -319.485784) (xy 78.887577 -319.41008) (xy 77.771498 -319.41008) (xy 77.770994 -319.447986)
			(xy 77.762935 -319.523367) (xy 77.74691 -319.597465) (xy 77.7231 -319.66944) (xy 77.691774 -319.738476)
			(xy 77.653287 -319.803791) (xy 77.608076 -319.864646) (xy 77.556652 -319.92035) (xy 77.499599 -319.970272)
			(xy 77.437563 -320.013847) (xy 77.371246 -320.050582) (xy 77.3014 -320.080059) (xy 77.228817 -320.101945)
			(xy 77.154319 -320.115992) (xy 77.078749 -320.122041) (xy 77.002965 -320.120022) (xy 76.927825 -320.10996)
			(xy 76.85418 -320.091968) (xy 76.782864 -320.06625) (xy 76.714687 -320.033098) (xy 76.650419 -319.992886)
			(xy 76.59079 -319.946071) (xy 76.536474 -319.893183) (xy 76.488088 -319.834821) (xy 76.44618 -319.771646)
			(xy 76.411224 -319.704375) (xy 76.383617 -319.63377) (xy 76.363671 -319.560629) (xy 76.351612 -319.485784)
			(xy 76.347577 -319.41008) (xy 75.231498 -319.41008) (xy 75.230994 -319.447986) (xy 75.222935 -319.523367)
			(xy 75.20691 -319.597465) (xy 75.1831 -319.66944) (xy 75.151774 -319.738476) (xy 75.113287 -319.803791)
			(xy 75.068076 -319.864646) (xy 75.016652 -319.92035) (xy 74.959599 -319.970272) (xy 74.897563 -320.013847)
			(xy 74.831246 -320.050582) (xy 74.7614 -320.080059) (xy 74.688817 -320.101945) (xy 74.614319 -320.115992)
			(xy 74.538749 -320.122041) (xy 74.462965 -320.120022) (xy 74.387825 -320.10996) (xy 74.31418 -320.091968)
			(xy 74.242864 -320.06625) (xy 74.174687 -320.033098) (xy 74.110419 -319.992886) (xy 74.05079 -319.946071)
			(xy 73.996474 -319.893183) (xy 73.948088 -319.834821) (xy 73.90618 -319.771646) (xy 73.871224 -319.704375)
			(xy 73.843617 -319.63377) (xy 73.823671 -319.560629) (xy 73.811612 -319.485784) (xy 73.807577 -319.41008)
			(xy 72.691498 -319.41008) (xy 72.690994 -319.447986) (xy 72.682935 -319.523367) (xy 72.66691 -319.597465)
			(xy 72.6431 -319.66944) (xy 72.611774 -319.738476) (xy 72.573287 -319.803791) (xy 72.528076 -319.864646)
			(xy 72.476652 -319.92035) (xy 72.419599 -319.970272) (xy 72.357563 -320.013847) (xy 72.291246 -320.050582)
			(xy 72.2214 -320.080059) (xy 72.148817 -320.101945) (xy 72.074319 -320.115992) (xy 71.998749 -320.122041)
			(xy 71.922965 -320.120022) (xy 71.847825 -320.10996) (xy 71.77418 -320.091968) (xy 71.702864 -320.06625)
			(xy 71.634687 -320.033098) (xy 71.570419 -319.992886) (xy 71.51079 -319.946071) (xy 71.456474 -319.893183)
			(xy 71.408088 -319.834821) (xy 71.36618 -319.771646) (xy 71.331224 -319.704375) (xy 71.303617 -319.63377)
			(xy 71.283671 -319.560629) (xy 71.271612 -319.485784) (xy 71.267577 -319.41008) (xy 70.151498 -319.41008)
			(xy 70.150994 -319.447986) (xy 70.142935 -319.523367) (xy 70.12691 -319.597465) (xy 70.1031 -319.66944)
			(xy 70.071774 -319.738476) (xy 70.033287 -319.803791) (xy 69.988076 -319.864646) (xy 69.936652 -319.92035)
			(xy 69.879599 -319.970272) (xy 69.817563 -320.013847) (xy 69.751246 -320.050582) (xy 69.6814 -320.080059)
			(xy 69.608817 -320.101945) (xy 69.534319 -320.115992) (xy 69.458749 -320.122041) (xy 69.382965 -320.120022)
			(xy 69.307825 -320.10996) (xy 69.23418 -320.091968) (xy 69.162864 -320.06625) (xy 69.094687 -320.033098)
			(xy 69.030419 -319.992886) (xy 68.97079 -319.946071) (xy 68.916474 -319.893183) (xy 68.868088 -319.834821)
			(xy 68.82618 -319.771646) (xy 68.791224 -319.704375) (xy 68.763617 -319.63377) (xy 68.743671 -319.560629)
			(xy 68.731612 -319.485784) (xy 68.727577 -319.41008) (xy 67.611498 -319.41008) (xy 67.610994 -319.447986)
			(xy 67.602935 -319.523367) (xy 67.58691 -319.597465) (xy 67.5631 -319.66944) (xy 67.531774 -319.738476)
			(xy 67.493287 -319.803791) (xy 67.448076 -319.864646) (xy 67.396652 -319.92035) (xy 67.339599 -319.970272)
			(xy 67.277563 -320.013847) (xy 67.211246 -320.050582) (xy 67.1414 -320.080059) (xy 67.068817 -320.101945)
			(xy 66.994319 -320.115992) (xy 66.918749 -320.122041) (xy 66.842965 -320.120022) (xy 66.767825 -320.10996)
			(xy 66.69418 -320.091968) (xy 66.622864 -320.06625) (xy 66.554687 -320.033098) (xy 66.490419 -319.992886)
			(xy 66.43079 -319.946071) (xy 66.376474 -319.893183) (xy 66.328088 -319.834821) (xy 66.28618 -319.771646)
			(xy 66.251224 -319.704375) (xy 66.223617 -319.63377) (xy 66.203671 -319.560629) (xy 66.191612 -319.485784)
			(xy 66.187577 -319.41008) (xy 65.071498 -319.41008) (xy 65.070994 -319.447986) (xy 65.062935 -319.523367)
			(xy 65.04691 -319.597465) (xy 65.0231 -319.66944) (xy 64.991774 -319.738476) (xy 64.953287 -319.803791)
			(xy 64.908076 -319.864646) (xy 64.856652 -319.92035) (xy 64.799599 -319.970272) (xy 64.737563 -320.013847)
			(xy 64.671246 -320.050582) (xy 64.6014 -320.080059) (xy 64.528817 -320.101945) (xy 64.454319 -320.115992)
			(xy 64.378749 -320.122041) (xy 64.302965 -320.120022) (xy 64.227825 -320.10996) (xy 64.15418 -320.091968)
			(xy 64.082864 -320.06625) (xy 64.014687 -320.033098) (xy 63.950419 -319.992886) (xy 63.89079 -319.946071)
			(xy 63.836474 -319.893183) (xy 63.788088 -319.834821) (xy 63.74618 -319.771646) (xy 63.711224 -319.704375)
			(xy 63.683617 -319.63377) (xy 63.663671 -319.560629) (xy 63.651612 -319.485784) (xy 63.647577 -319.41008)
			(xy 42.500813 -319.41008) (xy 42.479042 -319.426857) (xy 42.381609 -319.491665) (xy 42.279905 -319.54954)
			(xy 42.174422 -319.600202) (xy 42.065671 -319.643404) (xy 41.954179 -319.678939) (xy 41.840485 -319.706634)
			(xy 41.725141 -319.726354) (xy 41.608704 -319.738005) (xy 41.491739 -319.74153) (xy 41.374812 -319.736912)
			(xy 41.258489 -319.724173) (xy 41.143334 -319.703375) (xy 41.029905 -319.674618) (xy 40.91875 -319.638042)
			(xy 40.810407 -319.593825) (xy 40.705403 -319.542179) (xy 40.604244 -319.483356) (xy 40.507421 -319.41764)
			(xy 40.415403 -319.345349) (xy 40.328636 -319.266834) (xy 40.247539 -319.182474) (xy 40.172506 -319.092679)
			(xy 40.103899 -318.997883) (xy 40.042051 -318.898544) (xy 39.987262 -318.795145) (xy 39.939796 -318.688186)
			(xy 39.899884 -318.578185) (xy 39.86772 -318.465674) (xy 39.843457 -318.351199) (xy 39.827215 -318.235313)
			(xy 39.819072 -318.118579) (xy 39.818564 -318.06007) (xy 29.73324 -318.06007) (xy 29.73324 -319.493138)
			(xy 29.733718 -319.51598) (xy 29.741878 -319.56093) (xy 29.757945 -319.603696) (xy 29.781402 -319.642898)
			(xy 29.811492 -319.677274) (xy 29.847245 -319.705713) (xy 29.887507 -319.7273) (xy 29.930982 -319.741337)
			(xy 29.976265 -319.747373) (xy 30.021899 -319.745213) (xy 30.06641 -319.734926) (xy 30.08757 -319.72631)
			(xy 30.127491 -319.709645) (xy 30.20975 -319.682851) (xy 30.294124 -319.663727) (xy 30.379897 -319.652433)
			(xy 30.466345 -319.649066) (xy 30.552736 -319.653654) (xy 30.638341 -319.666158) (xy 30.722436 -319.686472)
			(xy 30.804309 -319.714424) (xy 30.883269 -319.74978) (xy 30.958647 -319.792238) (xy 31.029806 -319.84144)
			(xy 31.096145 -319.896971) (xy 31.157103 -319.958361) (xy 31.212165 -320.025091) (xy 31.260864 -320.096596)
			(xy 31.302789 -320.172272) (xy 31.337586 -320.251479) (xy 31.36496 -320.333547) (xy 31.38468 -320.417783)
			(xy 31.39658 -320.503474) (xy 31.400557 -320.589896) (xy 31.398557 -320.63336) (xy 34.599874 -320.63336)
			(xy 34.599874 -320.54646) (xy 34.607892 -320.459931) (xy 34.62386 -320.374511) (xy 34.647641 -320.290929)
			(xy 34.679033 -320.209897) (xy 34.717767 -320.132108) (xy 34.763514 -320.058224) (xy 34.815883 -319.988877)
			(xy 34.874427 -319.924657) (xy 34.938647 -319.866113) (xy 35.007994 -319.813744) (xy 35.081878 -319.767997)
			(xy 35.159667 -319.729263) (xy 35.240699 -319.697871) (xy 35.324281 -319.67409) (xy 35.409701 -319.658122)
			(xy 35.49623 -319.650104) (xy 35.58313 -319.650104) (xy 35.669659 -319.658122) (xy 35.755079 -319.67409)
			(xy 35.838661 -319.697871) (xy 35.919693 -319.729263) (xy 35.997482 -319.767997) (xy 36.071366 -319.813744)
			(xy 36.140713 -319.866113) (xy 36.204933 -319.924657) (xy 36.263477 -319.988877) (xy 36.315846 -320.058224)
			(xy 36.361593 -320.132108) (xy 36.400327 -320.209897) (xy 36.431719 -320.290929) (xy 36.4555 -320.374511)
			(xy 36.471468 -320.459931) (xy 36.479486 -320.54646) (xy 36.479988 -320.58991) (xy 36.479486 -320.63336)
			(xy 36.471468 -320.719889) (xy 36.4555 -320.805309) (xy 36.431719 -320.888891) (xy 36.400327 -320.969923)
			(xy 36.361593 -321.047712) (xy 36.315846 -321.121596) (xy 36.263477 -321.190943) (xy 36.204933 -321.255163)
			(xy 36.140713 -321.313707) (xy 36.071366 -321.366076) (xy 35.997482 -321.411823) (xy 35.919693 -321.450557)
			(xy 35.838661 -321.481949) (xy 35.755079 -321.50573) (xy 35.669659 -321.521698) (xy 35.58313 -321.529716)
			(xy 35.49623 -321.529716) (xy 35.409701 -321.521698) (xy 35.324281 -321.50573) (xy 35.240699 -321.481949)
			(xy 35.159667 -321.450557) (xy 35.081878 -321.411823) (xy 35.007994 -321.366076) (xy 34.938647 -321.313707)
			(xy 34.874427 -321.255163) (xy 34.815883 -321.190943) (xy 34.763514 -321.121596) (xy 34.717767 -321.047712)
			(xy 34.679033 -320.969923) (xy 34.647641 -320.888891) (xy 34.62386 -320.805309) (xy 34.607892 -320.719889)
			(xy 34.599874 -320.63336) (xy 31.398557 -320.63336) (xy 31.39658 -320.676318) (xy 31.384682 -320.762009)
			(xy 31.364962 -320.846245) (xy 31.337589 -320.928314) (xy 31.302793 -321.007521) (xy 31.260868 -321.083198)
			(xy 31.212169 -321.154703) (xy 31.157109 -321.221433) (xy 31.096151 -321.282823) (xy 31.029813 -321.338355)
			(xy 30.958653 -321.387558) (xy 30.883276 -321.430017) (xy 30.804316 -321.465373) (xy 30.722444 -321.493326)
			(xy 30.638349 -321.513641) (xy 30.552744 -321.526145) (xy 30.466352 -321.530734) (xy 30.379905 -321.527368)
			(xy 30.294131 -321.516075) (xy 30.209758 -321.496951) (xy 30.127498 -321.470158) (xy 30.08757 -321.45351)
			(xy 30.066403 -321.444941) (xy 30.021906 -321.434702) (xy 29.976295 -321.432576) (xy 29.931038 -321.438634)
			(xy 29.887591 -321.452679) (xy 29.847352 -321.474259) (xy 29.811616 -321.502681) (xy 29.781532 -321.53703)
			(xy 29.758068 -321.576201) (xy 29.74198 -321.618933) (xy 29.733784 -321.663852) (xy 29.73324 -321.686682)
			(xy 29.73324 -322.033138) (xy 29.733718 -322.05598) (xy 29.741878 -322.10093) (xy 29.757945 -322.143696)
			(xy 29.781402 -322.182898) (xy 29.811492 -322.217274) (xy 29.847245 -322.245713) (xy 29.887507 -322.2673)
			(xy 29.930982 -322.281337) (xy 29.976265 -322.287373) (xy 30.021899 -322.285213) (xy 30.06641 -322.274926)
			(xy 30.08757 -322.26631) (xy 30.127491 -322.249645) (xy 30.20975 -322.222851) (xy 30.294124 -322.203727)
			(xy 30.379897 -322.192433) (xy 30.466345 -322.189066) (xy 30.552736 -322.193654) (xy 30.638341 -322.206158)
			(xy 30.722436 -322.226472) (xy 30.804309 -322.254424) (xy 30.883269 -322.28978) (xy 30.958647 -322.332238)
			(xy 31.029806 -322.38144) (xy 31.096145 -322.436971) (xy 31.157103 -322.498361) (xy 31.212165 -322.565091)
			(xy 31.260864 -322.636596) (xy 31.302789 -322.712272) (xy 31.337586 -322.791479) (xy 31.36496 -322.873547)
			(xy 31.38468 -322.957783) (xy 31.39658 -323.043474) (xy 31.400557 -323.129896) (xy 31.398557 -323.17336)
			(xy 34.599874 -323.17336) (xy 34.599874 -323.08646) (xy 34.607892 -322.999931) (xy 34.62386 -322.914511)
			(xy 34.647641 -322.830929) (xy 34.679033 -322.749897) (xy 34.717767 -322.672108) (xy 34.763514 -322.598224)
			(xy 34.815883 -322.528877) (xy 34.874427 -322.464657) (xy 34.938647 -322.406113) (xy 35.007994 -322.353744)
			(xy 35.081878 -322.307997) (xy 35.159667 -322.269263) (xy 35.240699 -322.237871) (xy 35.324281 -322.21409)
			(xy 35.409701 -322.198122) (xy 35.49623 -322.190104) (xy 35.58313 -322.190104) (xy 35.669659 -322.198122)
			(xy 35.755079 -322.21409) (xy 35.838661 -322.237871) (xy 35.919693 -322.269263) (xy 35.997482 -322.307997)
			(xy 36.071366 -322.353744) (xy 36.140713 -322.406113) (xy 36.204933 -322.464657) (xy 36.263477 -322.528877)
			(xy 36.315846 -322.598224) (xy 36.361593 -322.672108) (xy 36.400327 -322.749897) (xy 36.431719 -322.830929)
			(xy 36.4555 -322.914511) (xy 36.471468 -322.999931) (xy 36.479486 -323.08646) (xy 36.479988 -323.12991)
			(xy 36.479486 -323.17336) (xy 36.477278 -323.197188) (xy 64.789715 -323.197188) (xy 64.793604 -323.142839)
			(xy 64.805188 -323.089597) (xy 64.824232 -323.038545) (xy 64.850347 -322.990723) (xy 64.883002 -322.947105)
			(xy 64.921533 -322.908578) (xy 64.965155 -322.875927) (xy 65.012979 -322.849816) (xy 65.064033 -322.830778)
			(xy 65.117276 -322.819199) (xy 65.171625 -322.815315) (xy 65.225974 -322.819206) (xy 65.279216 -322.830792)
			(xy 65.330267 -322.849837) (xy 65.378088 -322.875954) (xy 65.400174 -322.891912) (xy 65.419186 -322.905508)
			(xy 65.461069 -322.92624) (xy 65.506037 -322.938966) (xy 65.552574 -322.943256) (xy 65.599111 -322.938966)
			(xy 65.644079 -322.92624) (xy 65.685962 -322.905508) (xy 65.704974 -322.891912) (xy 65.727044 -322.875923)
			(xy 65.774873 -322.849795) (xy 65.825933 -322.830741) (xy 65.879185 -322.819148) (xy 65.933545 -322.815252)
			(xy 65.987906 -322.819132) (xy 66.041162 -322.83071) (xy 66.092228 -322.84975) (xy 66.140064 -322.875864)
			(xy 66.183696 -322.90852) (xy 66.222237 -322.947053) (xy 66.2549 -322.99068) (xy 66.281022 -323.038511)
			(xy 66.300071 -323.089574) (xy 66.311658 -323.142827) (xy 66.315548 -323.197188) (xy 67.594107 -323.197188)
			(xy 67.597996 -323.142837) (xy 67.609581 -323.089593) (xy 67.628625 -323.03854) (xy 67.654742 -322.990716)
			(xy 67.687398 -322.947097) (xy 67.725931 -322.908569) (xy 67.769554 -322.875917) (xy 67.817381 -322.849806)
			(xy 67.868436 -322.830768) (xy 67.921682 -322.819189) (xy 67.976033 -322.815307) (xy 68.030384 -322.819199)
			(xy 68.083627 -322.830786) (xy 68.13468 -322.849834) (xy 68.182502 -322.875953) (xy 68.204588 -322.891912)
			(xy 68.2236 -322.905508) (xy 68.265483 -322.92624) (xy 68.310451 -322.938966) (xy 68.356988 -322.943256)
			(xy 68.403525 -322.938966) (xy 68.448493 -322.92624) (xy 68.490376 -322.905508) (xy 68.509388 -322.891912)
			(xy 68.531458 -322.875924) (xy 68.579285 -322.849799) (xy 68.630344 -322.830747) (xy 68.683595 -322.819155)
			(xy 68.737953 -322.81526) (xy 68.792312 -322.819142) (xy 68.845566 -322.83072) (xy 68.89663 -322.84976)
			(xy 68.944463 -322.875873) (xy 68.988094 -322.908529) (xy 69.026633 -322.947062) (xy 69.059295 -322.990687)
			(xy 69.085416 -323.038517) (xy 69.104463 -323.089578) (xy 69.11605 -323.142829) (xy 69.11994 -323.197188)
			(xy 69.116053 -323.251547) (xy 69.10447 -323.304799) (xy 69.085426 -323.355861) (xy 69.059308 -323.403693)
			(xy 69.026648 -323.44732) (xy 68.988112 -323.485855) (xy 68.944484 -323.518514) (xy 68.896651 -323.54463)
			(xy 68.845589 -323.563673) (xy 68.792336 -323.575255) (xy 68.737977 -323.57914) (xy 68.683619 -323.575248)
			(xy 68.630367 -323.56366) (xy 68.579307 -323.544611) (xy 68.531478 -323.518489) (xy 68.509388 -323.502528)
			(xy 68.490376 -323.488932) (xy 68.448493 -323.4682) (xy 68.403525 -323.455474) (xy 68.356988 -323.451184)
			(xy 68.310451 -323.455474) (xy 68.265483 -323.4682) (xy 68.2236 -323.488932) (xy 68.204588 -323.502528)
			(xy 68.182481 -323.51846) (xy 68.134658 -323.544576) (xy 68.083604 -323.56362) (xy 68.03036 -323.575205)
			(xy 67.976009 -323.579093) (xy 67.921658 -323.575207) (xy 67.868413 -323.563625) (xy 67.817359 -323.544584)
			(xy 67.769534 -323.51847) (xy 67.725913 -323.485815) (xy 67.687383 -323.447285) (xy 67.654729 -323.403664)
			(xy 67.628615 -323.355839) (xy 67.609574 -323.304784) (xy 67.597992 -323.251539) (xy 67.594107 -323.197188)
			(xy 66.315548 -323.197188) (xy 66.311662 -323.251549) (xy 66.300078 -323.304803) (xy 66.281032 -323.355867)
			(xy 66.254913 -323.4037) (xy 66.222252 -323.447328) (xy 66.183714 -323.485865) (xy 66.140084 -323.518523)
			(xy 66.09225 -323.54464) (xy 66.041185 -323.563683) (xy 65.98793 -323.575264) (xy 65.933569 -323.579148)
			(xy 65.879209 -323.575255) (xy 65.825956 -323.563666) (xy 65.774894 -323.544615) (xy 65.727064 -323.51849)
			(xy 65.704974 -323.502528) (xy 65.685962 -323.488932) (xy 65.644079 -323.4682) (xy 65.599111 -323.455474)
			(xy 65.552574 -323.451184) (xy 65.506037 -323.455474) (xy 65.461069 -323.4682) (xy 65.419186 -323.488932)
			(xy 65.400174 -323.502528) (xy 65.378068 -323.518459) (xy 65.330245 -323.544573) (xy 65.279193 -323.563615)
			(xy 65.22595 -323.575198) (xy 65.171601 -323.579085) (xy 65.117252 -323.575198) (xy 65.064009 -323.563616)
			(xy 65.012957 -323.544574) (xy 64.965134 -323.51846) (xy 64.921515 -323.485806) (xy 64.882987 -323.447277)
			(xy 64.850334 -323.403657) (xy 64.824222 -323.355833) (xy 64.805181 -323.30478) (xy 64.793601 -323.251537)
			(xy 64.789715 -323.197188) (xy 36.477278 -323.197188) (xy 36.471468 -323.259889) (xy 36.4555 -323.345309)
			(xy 36.431719 -323.428891) (xy 36.400327 -323.509923) (xy 36.361593 -323.587712) (xy 36.315846 -323.661596)
			(xy 36.263477 -323.730943) (xy 36.204933 -323.795163) (xy 36.140713 -323.853707) (xy 36.071366 -323.906076)
			(xy 35.997482 -323.951823) (xy 35.919693 -323.990557) (xy 35.838661 -324.021949) (xy 35.755079 -324.04573)
			(xy 35.669659 -324.061698) (xy 35.58313 -324.069716) (xy 35.49623 -324.069716) (xy 35.409701 -324.061698)
			(xy 35.324281 -324.04573) (xy 35.240699 -324.021949) (xy 35.159667 -323.990557) (xy 35.081878 -323.951823)
			(xy 35.007994 -323.906076) (xy 34.938647 -323.853707) (xy 34.874427 -323.795163) (xy 34.815883 -323.730943)
			(xy 34.763514 -323.661596) (xy 34.717767 -323.587712) (xy 34.679033 -323.509923) (xy 34.647641 -323.428891)
			(xy 34.62386 -323.345309) (xy 34.607892 -323.259889) (xy 34.599874 -323.17336) (xy 31.398557 -323.17336)
			(xy 31.39658 -323.216318) (xy 31.384682 -323.302009) (xy 31.364962 -323.386245) (xy 31.337589 -323.468314)
			(xy 31.302793 -323.547521) (xy 31.260868 -323.623198) (xy 31.212169 -323.694703) (xy 31.157109 -323.761433)
			(xy 31.096151 -323.822823) (xy 31.029813 -323.878355) (xy 30.958653 -323.927558) (xy 30.883276 -323.970017)
			(xy 30.804316 -324.005373) (xy 30.722444 -324.033326) (xy 30.638349 -324.053641) (xy 30.552744 -324.066145)
			(xy 30.466352 -324.070734) (xy 30.379905 -324.067368) (xy 30.294131 -324.056075) (xy 30.209758 -324.036951)
			(xy 30.127498 -324.010158) (xy 30.08757 -323.99351) (xy 30.066403 -323.984941) (xy 30.021906 -323.974702)
			(xy 29.976295 -323.972576) (xy 29.931038 -323.978634) (xy 29.887591 -323.992679) (xy 29.847352 -324.014259)
			(xy 29.811616 -324.042681) (xy 29.781532 -324.07703) (xy 29.758068 -324.116201) (xy 29.74198 -324.158933)
			(xy 29.733784 -324.203852) (xy 29.73324 -324.226682) (xy 29.73324 -324.573138) (xy 29.733718 -324.59598)
			(xy 29.741878 -324.64093) (xy 29.757945 -324.683696) (xy 29.781402 -324.722898) (xy 29.811492 -324.757274)
			(xy 29.847245 -324.785713) (xy 29.887507 -324.8073) (xy 29.930982 -324.821337) (xy 29.976265 -324.827373)
			(xy 30.021899 -324.825213) (xy 30.06641 -324.814926) (xy 30.08757 -324.80631) (xy 30.127491 -324.789645)
			(xy 30.20975 -324.762851) (xy 30.294124 -324.743727) (xy 30.379897 -324.732433) (xy 30.466345 -324.729066)
			(xy 30.552736 -324.733654) (xy 30.638341 -324.746158) (xy 30.722436 -324.766472) (xy 30.804309 -324.794424)
			(xy 30.883269 -324.82978) (xy 30.958647 -324.872238) (xy 31.029806 -324.92144) (xy 31.096145 -324.976971)
			(xy 31.157103 -325.038361) (xy 31.212165 -325.105091) (xy 31.260864 -325.176596) (xy 31.302789 -325.252272)
			(xy 31.337586 -325.331479) (xy 31.36496 -325.413547) (xy 31.38468 -325.497783) (xy 31.39658 -325.583474)
			(xy 31.400557 -325.669896) (xy 31.398557 -325.71336) (xy 34.599874 -325.71336) (xy 34.599874 -325.62646)
			(xy 34.607892 -325.539931) (xy 34.62386 -325.454511) (xy 34.647641 -325.370929) (xy 34.679033 -325.289897)
			(xy 34.717767 -325.212108) (xy 34.763514 -325.138224) (xy 34.815883 -325.068877) (xy 34.874427 -325.004657)
			(xy 34.938647 -324.946113) (xy 35.007994 -324.893744) (xy 35.081878 -324.847997) (xy 35.159667 -324.809263)
			(xy 35.240699 -324.777871) (xy 35.324281 -324.75409) (xy 35.409701 -324.738122) (xy 35.49623 -324.730104)
			(xy 35.58313 -324.730104) (xy 35.669659 -324.738122) (xy 35.755079 -324.75409) (xy 35.838661 -324.777871)
			(xy 35.919693 -324.809263) (xy 35.997482 -324.847997) (xy 36.071366 -324.893744) (xy 36.140713 -324.946113)
			(xy 36.204933 -325.004657) (xy 36.263477 -325.068877) (xy 36.315846 -325.138224) (xy 36.361593 -325.212108)
			(xy 36.400327 -325.289897) (xy 36.431719 -325.370929) (xy 36.4555 -325.454511) (xy 36.471468 -325.539931)
			(xy 36.479486 -325.62646) (xy 36.479988 -325.66991) (xy 36.479486 -325.71336) (xy 36.471468 -325.799889)
			(xy 36.458739 -325.867982) (xy 64.789723 -325.867982) (xy 64.793613 -325.813634) (xy 64.805198 -325.760393)
			(xy 64.824242 -325.709343) (xy 64.850357 -325.661523) (xy 64.883012 -325.617906) (xy 64.921543 -325.57938)
			(xy 64.965164 -325.54673) (xy 65.012988 -325.520621) (xy 65.064041 -325.501584) (xy 65.117283 -325.490006)
			(xy 65.171631 -325.486123) (xy 65.225979 -325.490015) (xy 65.279219 -325.501601) (xy 65.330269 -325.520647)
			(xy 65.378089 -325.546764) (xy 65.400174 -325.562722) (xy 65.419186 -325.576318) (xy 65.461069 -325.59705)
			(xy 65.506037 -325.609776) (xy 65.552574 -325.614066) (xy 65.599111 -325.609776) (xy 65.644079 -325.59705)
			(xy 65.685962 -325.576318) (xy 65.704974 -325.562722) (xy 65.727035 -325.546719) (xy 65.774864 -325.520591)
			(xy 65.825925 -325.501535) (xy 65.879178 -325.489941) (xy 65.933539 -325.486044) (xy 65.987902 -325.489924)
			(xy 66.041159 -325.501501) (xy 66.092226 -325.52054) (xy 66.140063 -325.546654) (xy 66.183697 -325.57931)
			(xy 66.222239 -325.617844) (xy 66.254904 -325.661471) (xy 66.281027 -325.709303) (xy 66.300077 -325.760366)
			(xy 66.311665 -325.81362) (xy 66.315556 -325.867982) (xy 67.594115 -325.867982) (xy 67.598005 -325.813632)
			(xy 67.60959 -325.760389) (xy 67.628635 -325.709337) (xy 67.654752 -325.661516) (xy 67.687408 -325.617897)
			(xy 67.725941 -325.579371) (xy 67.769564 -325.546721) (xy 67.81739 -325.520611) (xy 67.868444 -325.501574)
			(xy 67.921689 -325.489996) (xy 67.976039 -325.486115) (xy 68.030389 -325.490008) (xy 68.083631 -325.501596)
			(xy 68.134682 -325.520644) (xy 68.182502 -325.546763) (xy 68.204588 -325.562722) (xy 68.2236 -325.576318)
			(xy 68.265483 -325.59705) (xy 68.310451 -325.609776) (xy 68.356988 -325.614066) (xy 68.403525 -325.609776)
			(xy 68.448493 -325.59705) (xy 68.490376 -325.576318) (xy 68.509388 -325.562722) (xy 68.531448 -325.546721)
			(xy 68.579276 -325.520594) (xy 68.630336 -325.501541) (xy 68.683588 -325.489948) (xy 68.737947 -325.486052)
			(xy 68.792308 -325.489933) (xy 68.845562 -325.501511) (xy 68.896627 -325.52055) (xy 68.944463 -325.546663)
			(xy 68.988095 -325.579319) (xy 69.026635 -325.617852) (xy 69.059298 -325.661478) (xy 69.08542 -325.709308)
			(xy 69.104469 -325.76037) (xy 69.116057 -325.813622) (xy 69.119948 -325.867982) (xy 69.116062 -325.922342)
			(xy 69.104479 -325.975596) (xy 69.085435 -326.026659) (xy 69.059318 -326.074492) (xy 69.026658 -326.118121)
			(xy 68.988122 -326.156657) (xy 68.944493 -326.189317) (xy 68.89666 -326.215435) (xy 68.845597 -326.234479)
			(xy 68.792343 -326.246062) (xy 68.737983 -326.249948) (xy 68.683623 -326.246057) (xy 68.630371 -326.23447)
			(xy 68.579309 -326.215421) (xy 68.531479 -326.189299) (xy 68.509388 -326.173338) (xy 68.490376 -326.159742)
			(xy 68.448493 -326.13901) (xy 68.403525 -326.126284) (xy 68.356988 -326.121994) (xy 68.310451 -326.126284)
			(xy 68.265483 -326.13901) (xy 68.2236 -326.159742) (xy 68.204588 -326.173338) (xy 68.182472 -326.189256)
			(xy 68.134649 -326.215371) (xy 68.083596 -326.234414) (xy 68.030353 -326.245998) (xy 67.976003 -326.249885)
			(xy 67.921653 -326.245998) (xy 67.86841 -326.234416) (xy 67.817357 -326.215374) (xy 67.769533 -326.18926)
			(xy 67.725913 -326.156605) (xy 67.687385 -326.118075) (xy 67.654732 -326.074454) (xy 67.62862 -326.02663)
			(xy 67.60958 -325.975576) (xy 67.597999 -325.922332) (xy 67.594115 -325.867982) (xy 66.315556 -325.867982)
			(xy 66.31167 -325.922344) (xy 66.300087 -325.9756) (xy 66.281042 -326.026665) (xy 66.254923 -326.074499)
			(xy 66.222262 -326.118129) (xy 66.183724 -326.156667) (xy 66.140093 -326.189327) (xy 66.092258 -326.215445)
			(xy 66.041193 -326.234489) (xy 65.987937 -326.246071) (xy 65.933575 -326.249956) (xy 65.879214 -326.246064)
			(xy 65.825959 -326.234475) (xy 65.774896 -326.215424) (xy 65.727065 -326.1893) (xy 65.704974 -326.173338)
			(xy 65.685962 -326.159742) (xy 65.644079 -326.13901) (xy 65.599111 -326.126284) (xy 65.552574 -326.121994)
			(xy 65.506037 -326.126284) (xy 65.461069 -326.13901) (xy 65.419186 -326.159742) (xy 65.400174 -326.173338)
			(xy 65.378058 -326.189255) (xy 65.330236 -326.215368) (xy 65.279185 -326.234409) (xy 65.225943 -326.24599)
			(xy 65.171595 -326.249877) (xy 65.117247 -326.245989) (xy 65.064006 -326.234406) (xy 65.012955 -326.215364)
			(xy 64.965134 -326.18925) (xy 64.921516 -326.156596) (xy 64.882989 -326.118067) (xy 64.850338 -326.074447)
			(xy 64.824227 -326.026624) (xy 64.805187 -325.975572) (xy 64.793608 -325.92233) (xy 64.789723 -325.867982)
			(xy 36.458739 -325.867982) (xy 36.4555 -325.885309) (xy 36.431719 -325.968891) (xy 36.400327 -326.049923)
			(xy 36.361593 -326.127712) (xy 36.315846 -326.201596) (xy 36.263477 -326.270943) (xy 36.204933 -326.335163)
			(xy 36.140713 -326.393707) (xy 36.071366 -326.446076) (xy 35.997482 -326.491823) (xy 35.919693 -326.530557)
			(xy 35.838661 -326.561949) (xy 35.755079 -326.58573) (xy 35.669659 -326.601698) (xy 35.58313 -326.609716)
			(xy 35.49623 -326.609716) (xy 35.409701 -326.601698) (xy 35.324281 -326.58573) (xy 35.240699 -326.561949)
			(xy 35.159667 -326.530557) (xy 35.081878 -326.491823) (xy 35.007994 -326.446076) (xy 34.938647 -326.393707)
			(xy 34.874427 -326.335163) (xy 34.815883 -326.270943) (xy 34.763514 -326.201596) (xy 34.717767 -326.127712)
			(xy 34.679033 -326.049923) (xy 34.647641 -325.968891) (xy 34.62386 -325.885309) (xy 34.607892 -325.799889)
			(xy 34.599874 -325.71336) (xy 31.398557 -325.71336) (xy 31.39658 -325.756318) (xy 31.384682 -325.842009)
			(xy 31.364962 -325.926245) (xy 31.337589 -326.008314) (xy 31.302793 -326.087521) (xy 31.260868 -326.163198)
			(xy 31.212169 -326.234703) (xy 31.157109 -326.301433) (xy 31.096151 -326.362823) (xy 31.029813 -326.418355)
			(xy 30.958653 -326.467558) (xy 30.883276 -326.510017) (xy 30.804316 -326.545373) (xy 30.722444 -326.573326)
			(xy 30.638349 -326.593641) (xy 30.552744 -326.606145) (xy 30.466352 -326.610734) (xy 30.379905 -326.607368)
			(xy 30.294131 -326.596075) (xy 30.209758 -326.576951) (xy 30.127498 -326.550158) (xy 30.08757 -326.53351)
			(xy 30.066403 -326.524941) (xy 30.021906 -326.514702) (xy 29.976295 -326.512576) (xy 29.931038 -326.518634)
			(xy 29.887591 -326.532679) (xy 29.847352 -326.554259) (xy 29.811616 -326.582681) (xy 29.781532 -326.61703)
			(xy 29.758068 -326.656201) (xy 29.74198 -326.698933) (xy 29.733784 -326.743852) (xy 29.73324 -326.766682)
			(xy 29.73324 -326.967107) (xy 55.2985 -326.967107) (xy 55.302386 -326.912757) (xy 55.313968 -326.859513)
			(xy 55.333009 -326.808459) (xy 55.359122 -326.760635) (xy 55.391776 -326.717013) (xy 55.430305 -326.678483)
			(xy 55.473925 -326.645828) (xy 55.521749 -326.619714) (xy 55.572802 -326.600671) (xy 55.626046 -326.589088)
			(xy 55.680396 -326.5852) (xy 55.734746 -326.589087) (xy 55.78799 -326.600669) (xy 55.839044 -326.61971)
			(xy 55.886868 -326.645824) (xy 55.908956 -326.66178) (xy 55.927968 -326.675376) (xy 55.969851 -326.696108)
			(xy 56.014819 -326.708834) (xy 56.061356 -326.713124) (xy 56.107893 -326.708834) (xy 56.152861 -326.696108)
			(xy 56.194744 -326.675376) (xy 56.213756 -326.66178) (xy 56.235856 -326.645833) (xy 56.283684 -326.619706)
			(xy 56.334744 -326.600653) (xy 56.387995 -326.589061) (xy 56.442354 -326.585167) (xy 56.496714 -326.589048)
			(xy 56.549968 -326.600627) (xy 56.601032 -326.619668) (xy 56.648866 -326.645783) (xy 56.692497 -326.67844)
			(xy 56.731035 -326.716974) (xy 56.763696 -326.760601) (xy 56.789816 -326.808433) (xy 56.808862 -326.859495)
			(xy 56.820446 -326.912748) (xy 56.824333 -326.967107) (xy 57.185193 -326.967107) (xy 57.189079 -326.912755)
			(xy 57.200661 -326.85951) (xy 57.219703 -326.808454) (xy 57.245817 -326.760629) (xy 57.278472 -326.717006)
			(xy 57.317003 -326.678475) (xy 57.360625 -326.64582) (xy 57.40845 -326.619705) (xy 57.459505 -326.600663)
			(xy 57.512751 -326.58908) (xy 57.567103 -326.585193) (xy 57.621455 -326.589081) (xy 57.6747 -326.600664)
			(xy 57.725755 -326.619707) (xy 57.77358 -326.645823) (xy 57.795668 -326.66178) (xy 57.81468 -326.675376)
			(xy 57.856563 -326.696108) (xy 57.901531 -326.708834) (xy 57.948068 -326.713124) (xy 57.994605 -326.708834)
			(xy 58.039573 -326.696108) (xy 58.081456 -326.675376) (xy 58.100468 -326.66178) (xy 58.122568 -326.645834)
			(xy 58.170395 -326.619709) (xy 58.221453 -326.600658) (xy 58.274703 -326.589068) (xy 58.329061 -326.585174)
			(xy 58.383419 -326.589056) (xy 58.436672 -326.600636) (xy 58.487734 -326.619677) (xy 58.535566 -326.645791)
			(xy 58.579195 -326.678448) (xy 58.617731 -326.716981) (xy 58.650391 -326.760607) (xy 58.67651 -326.808437)
			(xy 58.695555 -326.859498) (xy 58.707139 -326.912749) (xy 58.711026 -326.967107) (xy 58.707137 -327.021465)
			(xy 58.695551 -327.074716) (xy 58.676504 -327.125776) (xy 58.650384 -327.173605) (xy 58.617722 -327.21723)
			(xy 58.579184 -327.255762) (xy 58.535554 -327.288416) (xy 58.487721 -327.314529) (xy 58.436658 -327.333568)
			(xy 58.383405 -327.345146) (xy 58.329047 -327.349026) (xy 58.274689 -327.34513) (xy 58.22144 -327.333538)
			(xy 58.170382 -327.314485) (xy 58.122556 -327.288359) (xy 58.100468 -327.272396) (xy 58.081456 -327.2588)
			(xy 58.039573 -327.238068) (xy 57.994605 -327.225342) (xy 57.948068 -327.221052) (xy 57.901531 -327.225342)
			(xy 57.856563 -327.238068) (xy 57.81468 -327.2588) (xy 57.795668 -327.272396) (xy 57.773592 -327.288369)
			(xy 57.725768 -327.314487) (xy 57.674714 -327.333532) (xy 57.621469 -327.345117) (xy 57.567117 -327.349007)
			(xy 57.512765 -327.345122) (xy 57.459519 -327.333541) (xy 57.408463 -327.314501) (xy 57.360637 -327.288388)
			(xy 57.317014 -327.255734) (xy 57.278482 -327.217205) (xy 57.245825 -327.173584) (xy 57.219709 -327.125759)
			(xy 57.200665 -327.074704) (xy 57.189081 -327.021459) (xy 57.185193 -326.967107) (xy 56.824333 -326.967107)
			(xy 56.820444 -327.021467) (xy 56.808858 -327.074719) (xy 56.78981 -327.125781) (xy 56.763688 -327.173611)
			(xy 56.731025 -327.217237) (xy 56.692486 -327.25577) (xy 56.648854 -327.288425) (xy 56.601019 -327.314538)
			(xy 56.549954 -327.333577) (xy 56.4967 -327.345154) (xy 56.44234 -327.349033) (xy 56.387981 -327.345136)
			(xy 56.33473 -327.333543) (xy 56.283671 -327.314488) (xy 56.235844 -327.28836) (xy 56.213756 -327.272396)
			(xy 56.194744 -327.2588) (xy 56.152861 -327.238068) (xy 56.107893 -327.225342) (xy 56.061356 -327.221052)
			(xy 56.014819 -327.225342) (xy 55.969851 -327.238068) (xy 55.927968 -327.2588) (xy 55.908956 -327.272396)
			(xy 55.88688 -327.288368) (xy 55.839057 -327.314484) (xy 55.788004 -327.333527) (xy 55.73476 -327.345111)
			(xy 55.68041 -327.349) (xy 55.62606 -327.345114) (xy 55.572816 -327.333533) (xy 55.521762 -327.314492)
			(xy 55.473937 -327.288379) (xy 55.430316 -327.255726) (xy 55.391785 -327.217198) (xy 55.35913 -327.173578)
			(xy 55.333015 -327.125754) (xy 55.313972 -327.074701) (xy 55.302388 -327.021457) (xy 55.2985 -326.967107)
			(xy 29.73324 -326.967107) (xy 29.73324 -327.113138) (xy 29.733718 -327.13598) (xy 29.741878 -327.18093)
			(xy 29.757945 -327.223696) (xy 29.781402 -327.262898) (xy 29.811492 -327.297274) (xy 29.847245 -327.325713)
			(xy 29.887507 -327.3473) (xy 29.930982 -327.361337) (xy 29.976265 -327.367373) (xy 30.021899 -327.365213)
			(xy 30.06641 -327.354926) (xy 30.08757 -327.34631) (xy 30.127491 -327.329645) (xy 30.20975 -327.302851)
			(xy 30.294124 -327.283727) (xy 30.379897 -327.272433) (xy 30.466345 -327.269066) (xy 30.552736 -327.273654)
			(xy 30.638341 -327.286158) (xy 30.722436 -327.306472) (xy 30.804309 -327.334424) (xy 30.883269 -327.36978)
			(xy 30.958647 -327.412238) (xy 31.029806 -327.46144) (xy 31.096145 -327.516971) (xy 31.157103 -327.578361)
			(xy 31.212165 -327.645091) (xy 31.260864 -327.716596) (xy 31.302789 -327.792272) (xy 31.337586 -327.871479)
			(xy 31.36496 -327.953547) (xy 31.38468 -328.037783) (xy 31.39658 -328.123474) (xy 31.400557 -328.209896)
			(xy 31.398557 -328.25336) (xy 34.599874 -328.25336) (xy 34.599874 -328.16646) (xy 34.607892 -328.079931)
			(xy 34.62386 -327.994511) (xy 34.647641 -327.910929) (xy 34.679033 -327.829897) (xy 34.717767 -327.752108)
			(xy 34.763514 -327.678224) (xy 34.815883 -327.608877) (xy 34.874427 -327.544657) (xy 34.938647 -327.486113)
			(xy 35.007994 -327.433744) (xy 35.081878 -327.387997) (xy 35.159667 -327.349263) (xy 35.240699 -327.317871)
			(xy 35.324281 -327.29409) (xy 35.409701 -327.278122) (xy 35.49623 -327.270104) (xy 35.58313 -327.270104)
			(xy 35.669659 -327.278122) (xy 35.755079 -327.29409) (xy 35.838661 -327.317871) (xy 35.919693 -327.349263)
			(xy 35.997482 -327.387997) (xy 36.071366 -327.433744) (xy 36.140713 -327.486113) (xy 36.204933 -327.544657)
			(xy 36.263477 -327.608877) (xy 36.315846 -327.678224) (xy 36.361593 -327.752108) (xy 36.400327 -327.829897)
			(xy 36.431719 -327.910929) (xy 36.4555 -327.994511) (xy 36.471468 -328.079931) (xy 36.479486 -328.16646)
			(xy 36.479988 -328.20991) (xy 36.479486 -328.25336) (xy 36.471468 -328.339889) (xy 36.4555 -328.425309)
			(xy 36.431719 -328.508891) (xy 36.400327 -328.589923) (xy 36.361593 -328.667712) (xy 36.315846 -328.741596)
			(xy 36.271218 -328.800692) (xy 55.298521 -328.800692) (xy 55.302409 -328.746344) (xy 55.313992 -328.693104)
			(xy 55.333035 -328.642053) (xy 55.359148 -328.594233) (xy 55.391802 -328.550615) (xy 55.43033 -328.512089)
			(xy 55.473949 -328.479437) (xy 55.521771 -328.453326) (xy 55.572823 -328.434287) (xy 55.626064 -328.422706)
			(xy 55.680411 -328.418821) (xy 55.734759 -328.42271) (xy 55.787999 -328.434293) (xy 55.839049 -328.453336)
			(xy 55.88687 -328.47945) (xy 55.908956 -328.495406) (xy 55.927968 -328.509002) (xy 55.969851 -328.529734)
			(xy 56.014819 -328.54246) (xy 56.061356 -328.54675) (xy 56.107893 -328.54246) (xy 56.152861 -328.529734)
			(xy 56.194744 -328.509002) (xy 56.213756 -328.495406) (xy 56.235832 -328.479423) (xy 56.283661 -328.453294)
			(xy 56.334723 -328.434238) (xy 56.387977 -328.422643) (xy 56.442339 -328.418746) (xy 56.496702 -328.422626)
			(xy 56.549959 -328.434203) (xy 56.601027 -328.453243) (xy 56.648864 -328.479357) (xy 56.692499 -328.512014)
			(xy 56.73104 -328.550549) (xy 56.763705 -328.594177) (xy 56.789828 -328.64201) (xy 56.808877 -328.693074)
			(xy 56.820464 -328.746329) (xy 56.824354 -328.800692) (xy 57.185214 -328.800692) (xy 57.189102 -328.746343)
			(xy 57.200686 -328.6931) (xy 57.219729 -328.642049) (xy 57.245843 -328.594227) (xy 57.278498 -328.550608)
			(xy 57.317028 -328.512081) (xy 57.360649 -328.479429) (xy 57.408473 -328.453318) (xy 57.459526 -328.434278)
			(xy 57.512769 -328.422698) (xy 57.567118 -328.418814) (xy 57.621467 -328.422704) (xy 57.674709 -328.434289)
			(xy 57.72576 -328.453333) (xy 57.773582 -328.479449) (xy 57.795668 -328.495406) (xy 57.81468 -328.509002)
			(xy 57.856563 -328.529734) (xy 57.901531 -328.54246) (xy 57.948068 -328.54675) (xy 57.994605 -328.54246)
			(xy 58.039573 -328.529734) (xy 58.081456 -328.509002) (xy 58.100468 -328.495406) (xy 58.122544 -328.479424)
			(xy 58.170372 -328.453297) (xy 58.221433 -328.434242) (xy 58.274685 -328.422649) (xy 58.329045 -328.418753)
			(xy 58.383407 -328.422634) (xy 58.436663 -328.434212) (xy 58.487728 -328.453251) (xy 58.535564 -328.479365)
			(xy 58.579197 -328.512022) (xy 58.617737 -328.550556) (xy 58.650401 -328.594183) (xy 58.676522 -328.642014)
			(xy 58.695571 -328.693077) (xy 58.707157 -328.746331) (xy 58.711047 -328.800692) (xy 59.426189 -328.800692)
			(xy 59.430078 -328.746337) (xy 59.441663 -328.693089) (xy 59.460709 -328.642032) (xy 59.486827 -328.594206)
			(xy 59.519486 -328.550583) (xy 59.558022 -328.512053) (xy 59.601648 -328.4794) (xy 59.649478 -328.453288)
			(xy 59.700538 -328.434249) (xy 59.753787 -328.42267) (xy 59.808142 -328.418789) (xy 59.862496 -328.422682)
			(xy 59.915743 -328.434272) (xy 59.966798 -328.453323) (xy 60.014623 -328.479445) (xy 60.03671 -328.495406)
			(xy 60.055722 -328.509002) (xy 60.097605 -328.529734) (xy 60.142573 -328.54246) (xy 60.18911 -328.54675)
			(xy 60.235647 -328.54246) (xy 60.280615 -328.529734) (xy 60.322498 -328.509002) (xy 60.34151 -328.495406)
			(xy 60.363585 -328.479428) (xy 60.41141 -328.453307) (xy 60.462467 -328.434259) (xy 60.515714 -328.42267)
			(xy 60.570069 -328.418778) (xy 60.624425 -328.422662) (xy 60.677674 -328.434241) (xy 60.728734 -328.453282)
			(xy 60.776563 -328.479395) (xy 60.82019 -328.512049) (xy 60.858725 -328.55058) (xy 60.891384 -328.594204)
			(xy 60.917502 -328.642031) (xy 60.936548 -328.693088) (xy 60.948133 -328.746337) (xy 60.952022 -328.800692)
			(xy 61.330198 -328.800692) (xy 61.334087 -328.746339) (xy 61.345672 -328.693093) (xy 61.364716 -328.642039)
			(xy 61.390833 -328.594214) (xy 61.423491 -328.550593) (xy 61.462024 -328.512064) (xy 61.505649 -328.479411)
			(xy 61.553476 -328.453299) (xy 61.604533 -328.43426) (xy 61.65778 -328.422681) (xy 61.712133 -328.418798)
			(xy 61.766485 -328.422691) (xy 61.81973 -328.434279) (xy 61.870784 -328.453326) (xy 61.918607 -328.479447)
			(xy 61.940694 -328.495406) (xy 61.959706 -328.509002) (xy 62.001589 -328.529734) (xy 62.046557 -328.54246)
			(xy 62.093094 -328.54675) (xy 62.139631 -328.54246) (xy 62.184599 -328.529734) (xy 62.226482 -328.509002)
			(xy 62.245494 -328.495406) (xy 62.267569 -328.479427) (xy 62.315396 -328.453303) (xy 62.366454 -328.434252)
			(xy 62.419703 -328.422662) (xy 62.47406 -328.418769) (xy 62.528418 -328.422651) (xy 62.58167 -328.43423)
			(xy 62.632732 -328.45327) (xy 62.680564 -328.479384) (xy 62.724193 -328.512039) (xy 62.748457 -328.5363)
			(xy 64.789699 -328.5363) (xy 64.793586 -328.481949) (xy 64.805169 -328.428704) (xy 64.824212 -328.377649)
			(xy 64.850327 -328.329825) (xy 64.882982 -328.286204) (xy 64.921514 -328.247674) (xy 64.965136 -328.21502)
			(xy 65.012961 -328.188907) (xy 65.064016 -328.169866) (xy 65.117262 -328.158285) (xy 65.171613 -328.154399)
			(xy 65.225964 -328.158288) (xy 65.279209 -328.169873) (xy 65.330263 -328.188918) (xy 65.378086 -328.215034)
			(xy 65.400174 -328.230992) (xy 65.419186 -328.244588) (xy 65.461069 -328.26532) (xy 65.506037 -328.278046)
			(xy 65.552574 -328.282336) (xy 65.599111 -328.278046) (xy 65.644079 -328.26532) (xy 65.685962 -328.244588)
			(xy 65.704974 -328.230992) (xy 65.727063 -328.21503) (xy 65.77489 -328.188905) (xy 65.825949 -328.169853)
			(xy 65.879199 -328.158262) (xy 65.933557 -328.154368) (xy 65.987916 -328.15825) (xy 66.041169 -328.169829)
			(xy 66.092232 -328.188869) (xy 66.140065 -328.214984) (xy 66.183695 -328.24764) (xy 66.222232 -328.286173)
			(xy 66.254893 -328.329799) (xy 66.281013 -328.377629) (xy 66.300059 -328.42869) (xy 66.311644 -328.481942)
			(xy 66.315532 -328.5363) (xy 67.594091 -328.5363) (xy 67.597978 -328.481947) (xy 67.609562 -328.4287)
			(xy 67.628605 -328.377644) (xy 67.654722 -328.329818) (xy 67.687379 -328.286195) (xy 67.725911 -328.247665)
			(xy 67.769536 -328.21501) (xy 67.817363 -328.188897) (xy 67.86842 -328.169856) (xy 67.921668 -328.158275)
			(xy 67.976021 -328.154391) (xy 68.030374 -328.158281) (xy 68.08362 -328.169868) (xy 68.134675 -328.188914)
			(xy 68.1825 -328.215033) (xy 68.204588 -328.230992) (xy 68.2236 -328.244588) (xy 68.265483 -328.26532)
			(xy 68.310451 -328.278046) (xy 68.356988 -328.282336) (xy 68.403525 -328.278046) (xy 68.448493 -328.26532)
			(xy 68.490376 -328.244588) (xy 68.509388 -328.230992) (xy 68.531476 -328.215031) (xy 68.579303 -328.188908)
			(xy 68.63036 -328.169858) (xy 68.683609 -328.158269) (xy 68.737965 -328.154376) (xy 68.792322 -328.158259)
			(xy 68.845573 -328.169839) (xy 68.896634 -328.188879) (xy 68.944465 -328.214993) (xy 68.988092 -328.247649)
			(xy 69.026628 -328.286181) (xy 69.059288 -328.329806) (xy 69.085406 -328.377635) (xy 69.104451 -328.428694)
			(xy 69.116036 -328.481943) (xy 69.119924 -328.5363) (xy 69.116036 -328.590657) (xy 69.104451 -328.643906)
			(xy 69.085406 -328.694965) (xy 69.059288 -328.742794) (xy 69.026628 -328.786419) (xy 68.988092 -328.824951)
			(xy 68.944465 -328.857607) (xy 68.896634 -328.883721) (xy 68.845573 -328.902761) (xy 68.792322 -328.914341)
			(xy 68.737965 -328.918224) (xy 68.683609 -328.914331) (xy 68.63036 -328.902742) (xy 68.579303 -328.883692)
			(xy 68.531476 -328.857569) (xy 68.509388 -328.841608) (xy 68.490376 -328.828012) (xy 68.448493 -328.80728)
			(xy 68.403525 -328.794554) (xy 68.356988 -328.790264) (xy 68.310451 -328.794554) (xy 68.265483 -328.80728)
			(xy 68.2236 -328.828012) (xy 68.204588 -328.841608) (xy 68.1825 -328.857567) (xy 68.134675 -328.883686)
			(xy 68.08362 -328.902732) (xy 68.030374 -328.914319) (xy 67.976021 -328.918209) (xy 67.921668 -328.914325)
			(xy 67.86842 -328.902744) (xy 67.817363 -328.883703) (xy 67.769536 -328.85759) (xy 67.725911 -328.824935)
			(xy 67.687379 -328.786405) (xy 67.654722 -328.742782) (xy 67.628605 -328.694956) (xy 67.609562 -328.6439)
			(xy 67.597978 -328.590653) (xy 67.594091 -328.5363) (xy 66.315532 -328.5363) (xy 66.311644 -328.590658)
			(xy 66.300059 -328.64391) (xy 66.281013 -328.694971) (xy 66.254893 -328.742801) (xy 66.222232 -328.786427)
			(xy 66.183695 -328.82496) (xy 66.140065 -328.857616) (xy 66.092232 -328.883731) (xy 66.041169 -328.902771)
			(xy 65.987916 -328.91435) (xy 65.933557 -328.918232) (xy 65.879199 -328.914338) (xy 65.825949 -328.902747)
			(xy 65.77489 -328.883695) (xy 65.727063 -328.85757) (xy 65.704974 -328.841608) (xy 65.685962 -328.828012)
			(xy 65.644079 -328.80728) (xy 65.599111 -328.794554) (xy 65.552574 -328.790264) (xy 65.506037 -328.794554)
			(xy 65.461069 -328.80728) (xy 65.419186 -328.828012) (xy 65.400174 -328.841608) (xy 65.378086 -328.857566)
			(xy 65.330263 -328.883682) (xy 65.279209 -328.902727) (xy 65.225964 -328.914312) (xy 65.171613 -328.918201)
			(xy 65.117262 -328.914315) (xy 65.064016 -328.902734) (xy 65.012961 -328.883693) (xy 64.965136 -328.85758)
			(xy 64.921514 -328.824926) (xy 64.882982 -328.786396) (xy 64.850327 -328.742775) (xy 64.824212 -328.694951)
			(xy 64.805169 -328.643896) (xy 64.793586 -328.590651) (xy 64.789699 -328.5363) (xy 62.748457 -328.5363)
			(xy 62.76273 -328.550571) (xy 62.79539 -328.594196) (xy 62.82151 -328.642025) (xy 62.840556 -328.693084)
			(xy 62.852142 -328.746334) (xy 62.856031 -328.800692) (xy 62.852145 -328.855049) (xy 62.840561 -328.9083)
			(xy 62.821517 -328.95936) (xy 62.795399 -329.00719) (xy 62.762741 -329.050816) (xy 62.724205 -329.08935)
			(xy 62.680578 -329.122007) (xy 62.632747 -329.148123) (xy 62.581686 -329.167165) (xy 62.528435 -329.178747)
			(xy 62.474077 -329.182631) (xy 62.41972 -329.17874) (xy 62.36647 -329.167152) (xy 62.315411 -329.148104)
			(xy 62.267583 -329.121982) (xy 62.245494 -329.106022) (xy 62.226482 -329.092426) (xy 62.184599 -329.071694)
			(xy 62.139631 -329.058968) (xy 62.093094 -329.054678) (xy 62.046557 -329.058968) (xy 62.001589 -329.071694)
			(xy 61.959706 -329.092426) (xy 61.940694 -329.106022) (xy 61.918593 -329.121963) (xy 61.870769 -329.14808)
			(xy 61.819714 -329.167126) (xy 61.766469 -329.178712) (xy 61.712116 -329.182602) (xy 61.657764 -329.178717)
			(xy 61.604517 -329.167135) (xy 61.553461 -329.148094) (xy 61.505634 -329.12198) (xy 61.462011 -329.089325)
			(xy 61.42348 -329.050795) (xy 61.390824 -329.007172) (xy 61.364709 -328.959346) (xy 61.345667 -328.90829)
			(xy 61.334085 -328.855044) (xy 61.330198 -328.800692) (xy 60.952022 -328.800692) (xy 60.948135 -328.855047)
			(xy 60.936552 -328.908296) (xy 60.917509 -328.959354) (xy 60.891393 -329.007182) (xy 60.858736 -329.050807)
			(xy 60.820203 -329.08934) (xy 60.776578 -329.121996) (xy 60.728749 -329.148111) (xy 60.67769 -329.167154)
			(xy 60.624441 -329.178736) (xy 60.570086 -329.182622) (xy 60.515731 -329.178732) (xy 60.462483 -329.167146)
			(xy 60.411426 -329.1481) (xy 60.363599 -329.121981) (xy 60.34151 -329.106022) (xy 60.322498 -329.092426)
			(xy 60.280615 -329.071694) (xy 60.235647 -329.058968) (xy 60.18911 -329.054678) (xy 60.142573 -329.058968)
			(xy 60.097605 -329.071694) (xy 60.055722 -329.092426) (xy 60.03671 -329.106022) (xy 60.014608 -329.121964)
			(xy 59.966783 -329.148084) (xy 59.915727 -329.167132) (xy 59.86248 -329.17872) (xy 59.808125 -329.182611)
			(xy 59.75377 -329.178727) (xy 59.700522 -329.167147) (xy 59.649463 -329.148105) (xy 59.601634 -329.121991)
			(xy 59.558009 -329.089336) (xy 59.519475 -329.050804) (xy 59.486818 -329.00718) (xy 59.460702 -328.959352)
			(xy 59.441658 -328.908295) (xy 59.430075 -328.855046) (xy 59.426189 -328.800692) (xy 58.711047 -328.800692)
			(xy 58.70716 -328.855053) (xy 58.695575 -328.908307) (xy 58.676529 -328.95937) (xy 58.65041 -329.007203)
			(xy 58.617748 -329.050832) (xy 58.579209 -329.089367) (xy 58.535578 -329.122026) (xy 58.487744 -329.148142)
			(xy 58.436679 -329.167184) (xy 58.383423 -329.178764) (xy 58.329062 -329.182647) (xy 58.274702 -329.178753)
			(xy 58.221449 -329.167162) (xy 58.170388 -329.14811) (xy 58.122558 -329.121985) (xy 58.100468 -329.106022)
			(xy 58.081456 -329.092426) (xy 58.039573 -329.071694) (xy 57.994605 -329.058968) (xy 57.948068 -329.054678)
			(xy 57.901531 -329.058968) (xy 57.856563 -329.071694) (xy 57.81468 -329.092426) (xy 57.795668 -329.106022)
			(xy 57.773567 -329.12196) (xy 57.725745 -329.148074) (xy 57.674693 -329.167116) (xy 57.62145 -329.178699)
			(xy 57.567101 -329.182586) (xy 57.512752 -329.178699) (xy 57.45951 -329.167117) (xy 57.408458 -329.148075)
			(xy 57.360635 -329.121962) (xy 57.317015 -329.089308) (xy 57.278487 -329.050779) (xy 57.245834 -329.007159)
			(xy 57.219722 -328.959336) (xy 57.200681 -328.908283) (xy 57.1891 -328.855041) (xy 57.185214 -328.800692)
			(xy 56.824354 -328.800692) (xy 56.820467 -328.855054) (xy 56.808882 -328.90831) (xy 56.789835 -328.959375)
			(xy 56.763714 -329.007209) (xy 56.731051 -329.050839) (xy 56.692511 -329.089375) (xy 56.648879 -329.122034)
			(xy 56.601042 -329.14815) (xy 56.549975 -329.167192) (xy 56.496718 -329.178772) (xy 56.442355 -329.182654)
			(xy 56.387993 -329.178759) (xy 56.334739 -329.167167) (xy 56.283677 -329.148113) (xy 56.235846 -329.121986)
			(xy 56.213756 -329.106022) (xy 56.194744 -329.092426) (xy 56.152861 -329.071694) (xy 56.107893 -329.058968)
			(xy 56.061356 -329.054678) (xy 56.014819 -329.058968) (xy 55.969851 -329.071694) (xy 55.927968 -329.092426)
			(xy 55.908956 -329.106022) (xy 55.886856 -329.121959) (xy 55.839034 -329.148071) (xy 55.787983 -329.167112)
			(xy 55.734742 -329.178693) (xy 55.680395 -329.182579) (xy 55.626047 -329.178691) (xy 55.572807 -329.167108)
			(xy 55.521756 -329.148067) (xy 55.473935 -329.121954) (xy 55.430317 -329.0893) (xy 55.391791 -329.050772)
			(xy 55.359139 -329.007153) (xy 55.333028 -328.959331) (xy 55.313988 -328.90828) (xy 55.302407 -328.855039)
			(xy 55.298521 -328.800692) (xy 36.271218 -328.800692) (xy 36.263477 -328.810943) (xy 36.204933 -328.875163)
			(xy 36.140713 -328.933707) (xy 36.071366 -328.986076) (xy 35.997482 -329.031823) (xy 35.919693 -329.070557)
			(xy 35.838661 -329.101949) (xy 35.755079 -329.12573) (xy 35.669659 -329.141698) (xy 35.58313 -329.149716)
			(xy 35.49623 -329.149716) (xy 35.409701 -329.141698) (xy 35.324281 -329.12573) (xy 35.240699 -329.101949)
			(xy 35.159667 -329.070557) (xy 35.081878 -329.031823) (xy 35.007994 -328.986076) (xy 34.938647 -328.933707)
			(xy 34.874427 -328.875163) (xy 34.815883 -328.810943) (xy 34.763514 -328.741596) (xy 34.717767 -328.667712)
			(xy 34.679033 -328.589923) (xy 34.647641 -328.508891) (xy 34.62386 -328.425309) (xy 34.607892 -328.339889)
			(xy 34.599874 -328.25336) (xy 31.398557 -328.25336) (xy 31.39658 -328.296318) (xy 31.384682 -328.382009)
			(xy 31.364962 -328.466245) (xy 31.337589 -328.548314) (xy 31.302793 -328.627521) (xy 31.260868 -328.703198)
			(xy 31.212169 -328.774703) (xy 31.157109 -328.841433) (xy 31.096151 -328.902823) (xy 31.029813 -328.958355)
			(xy 30.958653 -329.007558) (xy 30.883276 -329.050017) (xy 30.804316 -329.085373) (xy 30.722444 -329.113326)
			(xy 30.638349 -329.133641) (xy 30.552744 -329.146145) (xy 30.466352 -329.150734) (xy 30.379905 -329.147368)
			(xy 30.294131 -329.136075) (xy 30.209758 -329.116951) (xy 30.127498 -329.090158) (xy 30.08757 -329.07351)
			(xy 30.066403 -329.064941) (xy 30.021906 -329.054702) (xy 29.976295 -329.052576) (xy 29.931038 -329.058634)
			(xy 29.887591 -329.072679) (xy 29.847352 -329.094259) (xy 29.811616 -329.122681) (xy 29.781532 -329.15703)
			(xy 29.758068 -329.196201) (xy 29.74198 -329.238933) (xy 29.733784 -329.283852) (xy 29.73324 -329.306682)
			(xy 29.73324 -329.653138) (xy 29.733718 -329.67598) (xy 29.741878 -329.72093) (xy 29.757945 -329.763696)
			(xy 29.781402 -329.802898) (xy 29.811492 -329.837274) (xy 29.847245 -329.865713) (xy 29.887507 -329.8873)
			(xy 29.930982 -329.901337) (xy 29.976265 -329.907373) (xy 30.021899 -329.905213) (xy 30.06641 -329.894926)
			(xy 30.08757 -329.88631) (xy 30.127491 -329.869645) (xy 30.20975 -329.842851) (xy 30.294124 -329.823727)
			(xy 30.379897 -329.812433) (xy 30.466345 -329.809066) (xy 30.552736 -329.813654) (xy 30.638341 -329.826158)
			(xy 30.722436 -329.846472) (xy 30.804309 -329.874424) (xy 30.883269 -329.90978) (xy 30.958647 -329.952238)
			(xy 31.029806 -330.00144) (xy 31.096145 -330.056971) (xy 31.157103 -330.118361) (xy 31.212165 -330.185091)
			(xy 31.260864 -330.256596) (xy 31.302789 -330.332272) (xy 31.337586 -330.411479) (xy 31.36496 -330.493547)
			(xy 31.38468 -330.577783) (xy 31.39658 -330.663474) (xy 31.400557 -330.749896) (xy 31.398557 -330.79336)
			(xy 34.599874 -330.79336) (xy 34.599874 -330.70646) (xy 34.607892 -330.619931) (xy 34.62386 -330.534511)
			(xy 34.647641 -330.450929) (xy 34.679033 -330.369897) (xy 34.717767 -330.292108) (xy 34.763514 -330.218224)
			(xy 34.815883 -330.148877) (xy 34.874427 -330.084657) (xy 34.938647 -330.026113) (xy 35.007994 -329.973744)
			(xy 35.081878 -329.927997) (xy 35.159667 -329.889263) (xy 35.240699 -329.857871) (xy 35.324281 -329.83409)
			(xy 35.409701 -329.818122) (xy 35.49623 -329.810104) (xy 35.58313 -329.810104) (xy 35.669659 -329.818122)
			(xy 35.755079 -329.83409) (xy 35.838661 -329.857871) (xy 35.919693 -329.889263) (xy 35.997482 -329.927997)
			(xy 36.071366 -329.973744) (xy 36.12331 -330.012971) (xy 47.903374 -330.012971) (xy 47.903374 -329.931861)
			(xy 47.911324 -329.851142) (xy 47.927147 -329.771591) (xy 47.950692 -329.693975) (xy 47.981731 -329.619039)
			(xy 48.019966 -329.547507) (xy 48.065028 -329.480067) (xy 48.116483 -329.417368) (xy 48.173836 -329.360015)
			(xy 48.236535 -329.30856) (xy 48.303975 -329.263498) (xy 48.375507 -329.225263) (xy 48.450443 -329.194224)
			(xy 48.528059 -329.170679) (xy 48.60761 -329.154856) (xy 48.688329 -329.146906) (xy 48.769439 -329.146906)
			(xy 48.850158 -329.154856) (xy 48.929709 -329.170679) (xy 49.007325 -329.194224) (xy 49.082261 -329.225263)
			(xy 49.153793 -329.263498) (xy 49.221233 -329.30856) (xy 49.283932 -329.360015) (xy 49.341285 -329.417368)
			(xy 49.39274 -329.480067) (xy 49.437802 -329.547507) (xy 49.476037 -329.619039) (xy 49.507076 -329.693975)
			(xy 49.530621 -329.771591) (xy 49.546444 -329.851142) (xy 49.554394 -329.931861) (xy 49.554892 -329.972416)
			(xy 49.554394 -330.012971) (xy 51.403494 -330.012971) (xy 51.403494 -329.931861) (xy 51.411444 -329.851142)
			(xy 51.427267 -329.771591) (xy 51.450812 -329.693975) (xy 51.481851 -329.619039) (xy 51.520086 -329.547507)
			(xy 51.565148 -329.480067) (xy 51.616603 -329.417368) (xy 51.673956 -329.360015) (xy 51.736655 -329.30856)
			(xy 51.804095 -329.263498) (xy 51.875627 -329.225263) (xy 51.950563 -329.194224) (xy 52.028179 -329.170679)
			(xy 52.10773 -329.154856) (xy 52.188449 -329.146906) (xy 52.269559 -329.146906) (xy 52.350278 -329.154856)
			(xy 52.429829 -329.170679) (xy 52.507445 -329.194224) (xy 52.582381 -329.225263) (xy 52.653913 -329.263498)
			(xy 52.721353 -329.30856) (xy 52.784052 -329.360015) (xy 52.841405 -329.417368) (xy 52.89286 -329.480067)
			(xy 52.937922 -329.547507) (xy 52.976157 -329.619039) (xy 53.007196 -329.693975) (xy 53.030741 -329.771591)
			(xy 53.046564 -329.851142) (xy 53.054514 -329.931861) (xy 53.055012 -329.972416) (xy 53.054514 -330.012971)
			(xy 53.046564 -330.09369) (xy 53.030741 -330.173241) (xy 53.007196 -330.250857) (xy 52.976157 -330.325793)
			(xy 52.937922 -330.397325) (xy 52.89286 -330.464765) (xy 52.841405 -330.527464) (xy 52.784052 -330.584817)
			(xy 52.721353 -330.636272) (xy 52.653913 -330.681334) (xy 52.616054 -330.70157) (xy 55.29855 -330.70157)
			(xy 55.302441 -330.647227) (xy 55.314026 -330.593991) (xy 55.33307 -330.542946) (xy 55.359184 -330.49513)
			(xy 55.391837 -330.451518) (xy 55.430365 -330.412996) (xy 55.473983 -330.38035) (xy 55.521803 -330.354244)
			(xy 55.572852 -330.335208) (xy 55.626089 -330.323632) (xy 55.680433 -330.31975) (xy 55.734776 -330.323641)
			(xy 55.788012 -330.335227) (xy 55.839057 -330.354271) (xy 55.886872 -330.380386) (xy 55.908956 -330.396342)
			(xy 55.927968 -330.409938) (xy 55.969851 -330.43067) (xy 56.014819 -330.443396) (xy 56.061356 -330.447686)
			(xy 56.107893 -330.443396) (xy 56.152861 -330.43067) (xy 56.194744 -330.409938) (xy 56.213756 -330.396342)
			(xy 56.235798 -330.380311) (xy 56.28363 -330.354177) (xy 56.334694 -330.335116) (xy 56.387951 -330.323518)
			(xy 56.442317 -330.319617) (xy 56.496684 -330.323494) (xy 56.549947 -330.335069) (xy 56.601019 -330.354108)
			(xy 56.648862 -330.380221) (xy 56.692501 -330.412878) (xy 56.731048 -330.451413) (xy 56.763718 -330.495043)
			(xy 56.789845 -330.542878) (xy 56.808899 -330.593945) (xy 56.82049 -330.647204) (xy 56.824383 -330.70157)
			(xy 57.185243 -330.70157) (xy 57.189134 -330.647225) (xy 57.20072 -330.593988) (xy 57.219764 -330.542941)
			(xy 57.245879 -330.495124) (xy 57.278534 -330.451511) (xy 57.317063 -330.412988) (xy 57.360683 -330.380342)
			(xy 57.408505 -330.354235) (xy 57.459555 -330.3352) (xy 57.512795 -330.323624) (xy 57.56714 -330.319743)
			(xy 57.621484 -330.323635) (xy 57.674722 -330.335222) (xy 57.725768 -330.354268) (xy 57.773584 -330.380385)
			(xy 57.795668 -330.396342) (xy 57.81468 -330.409938) (xy 57.856563 -330.43067) (xy 57.901531 -330.443396)
			(xy 57.948068 -330.447686) (xy 57.994605 -330.443396) (xy 58.039573 -330.43067) (xy 58.081456 -330.409938)
			(xy 58.100468 -330.396342) (xy 58.12251 -330.380312) (xy 58.170341 -330.35418) (xy 58.221404 -330.335121)
			(xy 58.27466 -330.323524) (xy 58.329024 -330.319624) (xy 58.383389 -330.323502) (xy 58.43665 -330.335078)
			(xy 58.487721 -330.354116) (xy 58.535562 -330.380229) (xy 58.579199 -330.412886) (xy 58.617745 -330.451421)
			(xy 58.650413 -330.495049) (xy 58.67654 -330.542883) (xy 58.695592 -330.593948) (xy 58.707183 -330.647205)
			(xy 58.711076 -330.70157) (xy 59.426218 -330.70157) (xy 59.430109 -330.64722) (xy 59.441697 -330.593977)
			(xy 59.460744 -330.542925) (xy 59.486863 -330.495103) (xy 59.519522 -330.451486) (xy 59.558057 -330.412961)
			(xy 59.601682 -330.380312) (xy 59.64951 -330.354205) (xy 59.700567 -330.33517) (xy 59.753813 -330.323596)
			(xy 59.808164 -330.319718) (xy 59.862514 -330.323614) (xy 59.915756 -330.335206) (xy 59.966806 -330.354258)
			(xy 60.014625 -330.380381) (xy 60.03671 -330.396342) (xy 60.055722 -330.409938) (xy 60.097605 -330.43067)
			(xy 60.142573 -330.443396) (xy 60.18911 -330.447686) (xy 60.235647 -330.443396) (xy 60.280615 -330.43067)
			(xy 60.322498 -330.409938) (xy 60.34151 -330.396342) (xy 60.363551 -330.380315) (xy 60.411379 -330.35419)
			(xy 60.462438 -330.335137) (xy 60.515689 -330.323545) (xy 60.570048 -330.319649) (xy 60.624407 -330.32353)
			(xy 60.677662 -330.335108) (xy 60.728726 -330.354146) (xy 60.776561 -330.380259) (xy 60.820193 -330.412913)
			(xy 60.858733 -330.451445) (xy 60.891397 -330.49507) (xy 60.917519 -330.542899) (xy 60.936569 -330.593959)
			(xy 60.948158 -330.647211) (xy 60.952051 -330.70157) (xy 61.330227 -330.70157) (xy 61.334119 -330.647222)
			(xy 61.345705 -330.593981) (xy 61.364751 -330.542931) (xy 61.390869 -330.495111) (xy 61.423527 -330.451495)
			(xy 61.462059 -330.412971) (xy 61.505682 -330.380323) (xy 61.553508 -330.354216) (xy 61.604562 -330.335182)
			(xy 61.657806 -330.323607) (xy 61.712155 -330.319727) (xy 61.766502 -330.323622) (xy 61.819743 -330.335212)
			(xy 61.870792 -330.354262) (xy 61.91861 -330.380382) (xy 61.940694 -330.396342) (xy 61.959706 -330.409938)
			(xy 62.001589 -330.43067) (xy 62.046557 -330.443396) (xy 62.093094 -330.447686) (xy 62.139631 -330.443396)
			(xy 62.184599 -330.43067) (xy 62.226482 -330.409938) (xy 62.245494 -330.396342) (xy 62.267535 -330.380314)
			(xy 62.315364 -330.354186) (xy 62.366425 -330.335131) (xy 62.419678 -330.323537) (xy 62.474039 -330.31964)
			(xy 62.528401 -330.323519) (xy 62.581657 -330.335096) (xy 62.632724 -330.354135) (xy 62.680561 -330.380248)
			(xy 62.724195 -330.412903) (xy 62.762737 -330.451436) (xy 62.795403 -330.495062) (xy 62.821527 -330.542893)
			(xy 62.840578 -330.593955) (xy 62.852168 -330.647209) (xy 62.85606 -330.70157) (xy 62.852176 -330.755932)
			(xy 62.840595 -330.809187) (xy 62.821552 -330.860252) (xy 62.795537 -330.907901) (xy 64.789697 -330.907901)
			(xy 64.793585 -330.85355) (xy 64.805168 -330.800304) (xy 64.82421 -330.74925) (xy 64.850325 -330.701425)
			(xy 64.88298 -330.657803) (xy 64.921512 -330.619273) (xy 64.965134 -330.586619) (xy 65.01296 -330.560506)
			(xy 65.064015 -330.541464) (xy 65.11726 -330.529883) (xy 65.171612 -330.525997) (xy 65.225964 -330.529887)
			(xy 65.279208 -330.541471) (xy 65.330262 -330.560516) (xy 65.378086 -330.586632) (xy 65.400174 -330.60259)
			(xy 65.419186 -330.616186) (xy 65.461069 -330.636918) (xy 65.506037 -330.649644) (xy 65.552574 -330.653934)
			(xy 65.599111 -330.649644) (xy 65.644079 -330.636918) (xy 65.685962 -330.616186) (xy 65.704974 -330.60259)
			(xy 65.727065 -330.586631) (xy 65.774892 -330.560506) (xy 65.82595 -330.541454) (xy 65.879201 -330.529863)
			(xy 65.933558 -330.525969) (xy 65.987917 -330.529852) (xy 66.04117 -330.541431) (xy 66.092232 -330.560471)
			(xy 66.140065 -330.586586) (xy 66.183695 -330.619242) (xy 66.222232 -330.657775) (xy 66.254893 -330.701401)
			(xy 66.281012 -330.749231) (xy 66.300058 -330.800291) (xy 66.311643 -330.853543) (xy 66.315531 -330.907901)
			(xy 67.594089 -330.907901) (xy 67.597976 -330.853548) (xy 67.60956 -330.800301) (xy 67.628604 -330.749244)
			(xy 67.65472 -330.701418) (xy 67.687377 -330.657795) (xy 67.725909 -330.619264) (xy 67.769534 -330.586609)
			(xy 67.817361 -330.560496) (xy 67.868419 -330.541455) (xy 67.921666 -330.529874) (xy 67.97602 -330.525989)
			(xy 68.030373 -330.529879) (xy 68.08362 -330.541466) (xy 68.134675 -330.560512) (xy 68.1825 -330.586631)
			(xy 68.204588 -330.60259) (xy 68.2236 -330.616186) (xy 68.265483 -330.636918) (xy 68.310451 -330.649644)
			(xy 68.356988 -330.653934) (xy 68.403525 -330.649644) (xy 68.448493 -330.636918) (xy 68.490376 -330.616186)
			(xy 68.509388 -330.60259) (xy 68.531478 -330.586632) (xy 68.579305 -330.560509) (xy 68.630362 -330.54146)
			(xy 68.68361 -330.529871) (xy 68.737966 -330.525978) (xy 68.792323 -330.529861) (xy 68.845574 -330.541441)
			(xy 68.896634 -330.560481) (xy 68.944465 -330.586595) (xy 68.988092 -330.619251) (xy 69.026628 -330.657783)
			(xy 69.059287 -330.701408) (xy 69.085405 -330.749236) (xy 69.10445 -330.800295) (xy 69.116034 -330.853545)
			(xy 69.119922 -330.907901) (xy 69.116034 -330.962258) (xy 69.104449 -331.015507) (xy 69.085404 -331.066566)
			(xy 69.059286 -331.114394) (xy 69.026626 -331.158019) (xy 68.988091 -331.196551) (xy 68.944463 -331.229206)
			(xy 68.896632 -331.25532) (xy 68.845571 -331.27436) (xy 68.792321 -331.285939) (xy 68.737964 -331.289822)
			(xy 68.683608 -331.285929) (xy 68.630359 -331.27434) (xy 68.579302 -331.25529) (xy 68.531476 -331.229167)
			(xy 68.509388 -331.213206) (xy 68.490376 -331.19961) (xy 68.448493 -331.178878) (xy 68.403525 -331.166152)
			(xy 68.356988 -331.161862) (xy 68.310451 -331.166152) (xy 68.265483 -331.178878) (xy 68.2236 -331.19961)
			(xy 68.204588 -331.213206) (xy 68.182502 -331.229168) (xy 68.134677 -331.255287) (xy 68.083622 -331.274333)
			(xy 68.030376 -331.28592) (xy 67.976022 -331.289811) (xy 67.921669 -331.285927) (xy 67.868421 -331.274346)
			(xy 67.817364 -331.255305) (xy 67.769536 -331.229192) (xy 67.725911 -331.196537) (xy 67.687378 -331.158007)
			(xy 67.654721 -331.114384) (xy 67.628605 -331.066558) (xy 67.609561 -331.015502) (xy 67.597977 -330.962255)
			(xy 67.594089 -330.907901) (xy 66.315531 -330.907901) (xy 66.311642 -330.962259) (xy 66.300057 -331.015511)
			(xy 66.281011 -331.066571) (xy 66.254891 -331.114401) (xy 66.22223 -331.158027) (xy 66.183693 -331.19656)
			(xy 66.140063 -331.229216) (xy 66.09223 -331.25533) (xy 66.041167 -331.27437) (xy 65.987915 -331.285949)
			(xy 65.933556 -331.289831) (xy 65.879198 -331.285936) (xy 65.825948 -331.274345) (xy 65.77489 -331.255293)
			(xy 65.727063 -331.229168) (xy 65.704974 -331.213206) (xy 65.685962 -331.19961) (xy 65.644079 -331.178878)
			(xy 65.599111 -331.166152) (xy 65.552574 -331.161862) (xy 65.506037 -331.166152) (xy 65.461069 -331.178878)
			(xy 65.419186 -331.19961) (xy 65.400174 -331.213206) (xy 65.378088 -331.229166) (xy 65.330264 -331.255283)
			(xy 65.279211 -331.274328) (xy 65.225966 -331.285913) (xy 65.171614 -331.289803) (xy 65.117263 -331.285917)
			(xy 65.064017 -331.274336) (xy 65.012962 -331.255295) (xy 64.965136 -331.229182) (xy 64.921513 -331.196528)
			(xy 64.882982 -331.157998) (xy 64.850326 -331.114377) (xy 64.824211 -331.066552) (xy 64.805168 -331.015498)
			(xy 64.793585 -330.962253) (xy 64.789697 -330.907901) (xy 62.795537 -330.907901) (xy 62.795435 -330.908088)
			(xy 62.762777 -330.951719) (xy 62.72424 -330.990258) (xy 62.680612 -331.02292) (xy 62.632778 -331.04904)
			(xy 62.581715 -331.068087) (xy 62.52846 -331.079672) (xy 62.474099 -331.08356) (xy 62.419737 -331.079672)
			(xy 62.366483 -331.068086) (xy 62.315419 -331.049039) (xy 62.267586 -331.022918) (xy 62.245494 -331.006958)
			(xy 62.226482 -330.993362) (xy 62.184599 -330.97263) (xy 62.139631 -330.959904) (xy 62.093094 -330.955614)
			(xy 62.046557 -330.959904) (xy 62.001589 -330.97263) (xy 61.959706 -330.993362) (xy 61.940694 -331.006958)
			(xy 61.918559 -331.02285) (xy 61.870737 -331.048963) (xy 61.819685 -331.068005) (xy 61.766443 -331.079586)
			(xy 61.712095 -331.083473) (xy 61.657746 -331.079585) (xy 61.604505 -331.068002) (xy 61.553453 -331.048959)
			(xy 61.505632 -331.022844) (xy 61.462014 -330.990189) (xy 61.423487 -330.951659) (xy 61.390837 -330.908038)
			(xy 61.364727 -330.860215) (xy 61.345688 -330.809162) (xy 61.33411 -330.755919) (xy 61.330227 -330.70157)
			(xy 60.952051 -330.70157) (xy 60.948167 -330.75593) (xy 60.936586 -330.809183) (xy 60.917544 -330.860246)
			(xy 60.891429 -330.90808) (xy 60.858772 -330.951709) (xy 60.820238 -330.990247) (xy 60.776611 -331.022909)
			(xy 60.728781 -331.049029) (xy 60.677719 -331.068076) (xy 60.624467 -331.079661) (xy 60.570108 -331.083551)
			(xy 60.515748 -331.079664) (xy 60.462496 -331.06808) (xy 60.411433 -331.049035) (xy 60.363602 -331.022917)
			(xy 60.34151 -331.006958) (xy 60.322498 -330.993362) (xy 60.280615 -330.97263) (xy 60.235647 -330.959904)
			(xy 60.18911 -330.955614) (xy 60.142573 -330.959904) (xy 60.097605 -330.97263) (xy 60.055722 -330.993362)
			(xy 60.03671 -331.006958) (xy 60.014575 -331.022851) (xy 59.966751 -331.048967) (xy 59.915698 -331.068011)
			(xy 59.862454 -331.079595) (xy 59.808104 -331.083482) (xy 59.753753 -331.079596) (xy 59.700509 -331.068013)
			(xy 59.649455 -331.04897) (xy 59.601632 -331.022855) (xy 59.558011 -330.9902) (xy 59.519483 -330.951669)
			(xy 59.48683 -330.908046) (xy 59.460719 -330.860221) (xy 59.44168 -330.809166) (xy 59.430101 -330.755921)
			(xy 59.426218 -330.70157) (xy 58.711076 -330.70157) (xy 58.707191 -330.755935) (xy 58.695609 -330.809194)
			(xy 58.676565 -330.860263) (xy 58.650446 -330.908101) (xy 58.617784 -330.951734) (xy 58.579245 -330.990275)
			(xy 58.535612 -331.022938) (xy 58.487775 -331.049059) (xy 58.436707 -331.068105) (xy 58.383449 -331.079689)
			(xy 58.329084 -331.083576) (xy 58.274719 -331.079685) (xy 58.221461 -331.068096) (xy 58.170395 -331.049045)
			(xy 58.122561 -331.022921) (xy 58.100468 -331.006958) (xy 58.081456 -330.993362) (xy 58.039573 -330.97263)
			(xy 57.994605 -330.959904) (xy 57.948068 -330.955614) (xy 57.901531 -330.959904) (xy 57.856563 -330.97263)
			(xy 57.81468 -330.993362) (xy 57.795668 -331.006958) (xy 57.773534 -331.022848) (xy 57.725713 -331.048957)
			(xy 57.674664 -331.067995) (xy 57.621425 -331.079573) (xy 57.56708 -331.083457) (xy 57.512735 -331.079568)
			(xy 57.459497 -331.067983) (xy 57.40845 -331.04894) (xy 57.360632 -331.022826) (xy 57.317018 -330.990172)
			(xy 57.278495 -330.951644) (xy 57.245847 -330.908025) (xy 57.219739 -330.860204) (xy 57.200703 -330.809155)
			(xy 57.189125 -330.755915) (xy 57.185243 -330.70157) (xy 56.824383 -330.70157) (xy 56.820498 -330.755937)
			(xy 56.808916 -330.809197) (xy 56.78987 -330.860267) (xy 56.76375 -330.908107) (xy 56.731087 -330.951741)
			(xy 56.692546 -330.990283) (xy 56.648912 -331.022947) (xy 56.601074 -331.049067) (xy 56.550004 -331.068114)
			(xy 56.496744 -331.079697) (xy 56.442377 -331.083583) (xy 56.388011 -331.079691) (xy 56.334752 -331.068101)
			(xy 56.283684 -331.049048) (xy 56.235849 -331.022922) (xy 56.213756 -331.006958) (xy 56.194744 -330.993362)
			(xy 56.152861 -330.97263) (xy 56.107893 -330.959904) (xy 56.061356 -330.955614) (xy 56.014819 -330.959904)
			(xy 55.969851 -330.97263) (xy 55.927968 -330.993362) (xy 55.908956 -331.006958) (xy 55.886822 -331.022847)
			(xy 55.839002 -331.048954) (xy 55.787954 -331.06799) (xy 55.734716 -331.079567) (xy 55.680373 -331.08345)
			(xy 55.62603 -331.07956) (xy 55.572794 -331.067975) (xy 55.521748 -331.048932) (xy 55.473933 -331.022818)
			(xy 55.43032 -330.990164) (xy 55.391798 -330.951637) (xy 55.359152 -330.908019) (xy 55.333045 -330.8602)
			(xy 55.314009 -330.809151) (xy 55.302432 -330.755914) (xy 55.29855 -330.70157) (xy 52.616054 -330.70157)
			(xy 52.582381 -330.719569) (xy 52.507445 -330.750608) (xy 52.429829 -330.774153) (xy 52.350278 -330.789976)
			(xy 52.269559 -330.797926) (xy 52.188449 -330.797926) (xy 52.10773 -330.789976) (xy 52.028179 -330.774153)
			(xy 51.950563 -330.750608) (xy 51.875627 -330.719569) (xy 51.804095 -330.681334) (xy 51.736655 -330.636272)
			(xy 51.673956 -330.584817) (xy 51.616603 -330.527464) (xy 51.565148 -330.464765) (xy 51.520086 -330.397325)
			(xy 51.481851 -330.325793) (xy 51.450812 -330.250857) (xy 51.427267 -330.173241) (xy 51.411444 -330.09369)
			(xy 51.403494 -330.012971) (xy 49.554394 -330.012971) (xy 49.546444 -330.09369) (xy 49.530621 -330.173241)
			(xy 49.507076 -330.250857) (xy 49.476037 -330.325793) (xy 49.437802 -330.397325) (xy 49.39274 -330.464765)
			(xy 49.341285 -330.527464) (xy 49.283932 -330.584817) (xy 49.221233 -330.636272) (xy 49.153793 -330.681334)
			(xy 49.082261 -330.719569) (xy 49.007325 -330.750608) (xy 48.929709 -330.774153) (xy 48.850158 -330.789976)
			(xy 48.769439 -330.797926) (xy 48.688329 -330.797926) (xy 48.60761 -330.789976) (xy 48.528059 -330.774153)
			(xy 48.450443 -330.750608) (xy 48.375507 -330.719569) (xy 48.303975 -330.681334) (xy 48.236535 -330.636272)
			(xy 48.173836 -330.584817) (xy 48.116483 -330.527464) (xy 48.065028 -330.464765) (xy 48.019966 -330.397325)
			(xy 47.981731 -330.325793) (xy 47.950692 -330.250857) (xy 47.927147 -330.173241) (xy 47.911324 -330.09369)
			(xy 47.903374 -330.012971) (xy 36.12331 -330.012971) (xy 36.140713 -330.026113) (xy 36.204933 -330.084657)
			(xy 36.263477 -330.148877) (xy 36.315846 -330.218224) (xy 36.361593 -330.292108) (xy 36.400327 -330.369897)
			(xy 36.431719 -330.450929) (xy 36.4555 -330.534511) (xy 36.471468 -330.619931) (xy 36.479486 -330.70646)
			(xy 36.479988 -330.74991) (xy 36.479486 -330.79336) (xy 36.471468 -330.879889) (xy 36.4555 -330.965309)
			(xy 36.431719 -331.048891) (xy 36.400327 -331.129923) (xy 36.361593 -331.207712) (xy 36.315846 -331.281596)
			(xy 36.263477 -331.350943) (xy 36.204933 -331.415163) (xy 36.140713 -331.473707) (xy 36.071366 -331.526076)
			(xy 35.997482 -331.571823) (xy 35.919693 -331.610557) (xy 35.838661 -331.641949) (xy 35.755079 -331.66573)
			(xy 35.669659 -331.681698) (xy 35.58313 -331.689716) (xy 35.49623 -331.689716) (xy 35.409701 -331.681698)
			(xy 35.324281 -331.66573) (xy 35.240699 -331.641949) (xy 35.159667 -331.610557) (xy 35.081878 -331.571823)
			(xy 35.007994 -331.526076) (xy 34.938647 -331.473707) (xy 34.874427 -331.415163) (xy 34.815883 -331.350943)
			(xy 34.763514 -331.281596) (xy 34.717767 -331.207712) (xy 34.679033 -331.129923) (xy 34.647641 -331.048891)
			(xy 34.62386 -330.965309) (xy 34.607892 -330.879889) (xy 34.599874 -330.79336) (xy 31.398557 -330.79336)
			(xy 31.39658 -330.836318) (xy 31.384682 -330.922009) (xy 31.364962 -331.006245) (xy 31.337589 -331.088314)
			(xy 31.302793 -331.167521) (xy 31.260868 -331.243198) (xy 31.212169 -331.314703) (xy 31.157109 -331.381433)
			(xy 31.096151 -331.442823) (xy 31.029813 -331.498355) (xy 30.958653 -331.547558) (xy 30.883276 -331.590017)
			(xy 30.804316 -331.625373) (xy 30.722444 -331.653326) (xy 30.638349 -331.673641) (xy 30.552744 -331.686145)
			(xy 30.466352 -331.690734) (xy 30.379905 -331.687368) (xy 30.294131 -331.676075) (xy 30.209758 -331.656951)
			(xy 30.127498 -331.630158) (xy 30.08757 -331.61351) (xy 30.066403 -331.604941) (xy 30.021906 -331.594702)
			(xy 29.976295 -331.592576) (xy 29.931038 -331.598634) (xy 29.887591 -331.612679) (xy 29.847352 -331.634259)
			(xy 29.811616 -331.662681) (xy 29.781532 -331.69703) (xy 29.758068 -331.736201) (xy 29.74198 -331.778933)
			(xy 29.733784 -331.823852) (xy 29.73324 -331.846682) (xy 29.73324 -332.164211) (xy 39.178241 -332.164211)
			(xy 39.182128 -332.109847) (xy 39.193713 -332.056591) (xy 39.21276 -332.005525) (xy 39.238881 -331.95769)
			(xy 39.271544 -331.91406) (xy 39.310085 -331.875523) (xy 39.353718 -331.842863) (xy 39.401555 -331.816746)
			(xy 39.452622 -331.797704) (xy 39.50588 -331.786124) (xy 39.560243 -331.782242) (xy 39.614606 -331.786136)
			(xy 39.667861 -331.797729) (xy 39.718924 -331.816783) (xy 39.766755 -331.84291) (xy 39.788846 -331.858874)
			(xy 39.807858 -331.87247) (xy 39.849741 -331.893202) (xy 39.894709 -331.905928) (xy 39.941246 -331.910218)
			(xy 39.987783 -331.905928) (xy 40.032751 -331.893202) (xy 40.074634 -331.87247) (xy 40.093646 -331.858874)
			(xy 40.11575 -331.842942) (xy 40.163571 -331.816831) (xy 40.214622 -331.797792) (xy 40.267862 -331.786211)
			(xy 40.322209 -331.782325) (xy 40.376555 -331.786214) (xy 40.429795 -331.797797) (xy 40.480845 -331.816839)
			(xy 40.528665 -331.842952) (xy 40.572282 -331.875605) (xy 40.610808 -331.914133) (xy 40.643459 -331.957752)
			(xy 40.66957 -332.005573) (xy 40.688609 -332.056624) (xy 40.700189 -332.109864) (xy 40.704075 -332.164211)
			(xy 40.700186 -332.218557) (xy 40.688603 -332.271797) (xy 40.669561 -332.322847) (xy 40.643447 -332.370667)
			(xy 40.610794 -332.414283) (xy 40.572266 -332.452809) (xy 40.553706 -332.466702) (xy 55.332653 -332.466702)
			(xy 55.336541 -332.412341) (xy 55.348126 -332.359086) (xy 55.367174 -332.308022) (xy 55.393295 -332.260189)
			(xy 55.425958 -332.216561) (xy 55.464498 -332.178026) (xy 55.508131 -332.145368) (xy 55.555967 -332.119253)
			(xy 55.607033 -332.100212) (xy 55.66029 -332.088634) (xy 55.714652 -332.084753) (xy 55.769013 -332.088648)
			(xy 55.822266 -332.100242) (xy 55.873327 -332.119296) (xy 55.921156 -332.145424) (xy 55.943246 -332.161388)
			(xy 55.962258 -332.174984) (xy 56.004141 -332.195716) (xy 56.049109 -332.208442) (xy 56.095646 -332.212732)
			(xy 56.142183 -332.208442) (xy 56.187151 -332.195716) (xy 56.229034 -332.174984) (xy 56.248046 -332.161388)
			(xy 56.270137 -332.145437) (xy 56.317959 -332.119324) (xy 56.369011 -332.100283) (xy 56.422252 -332.088701)
			(xy 56.476601 -332.084814) (xy 56.530949 -332.088701) (xy 56.58419 -332.100284) (xy 56.635242 -332.119325)
			(xy 56.683064 -332.145438) (xy 56.726683 -332.178091) (xy 56.765211 -332.216619) (xy 56.797864 -332.260238)
			(xy 56.823976 -332.308061) (xy 56.843017 -332.359112) (xy 56.854599 -332.412354) (xy 56.858486 -332.466702)
			(xy 57.219505 -332.466702) (xy 57.223392 -332.412353) (xy 57.234974 -332.359109) (xy 57.254016 -332.308056)
			(xy 57.280129 -332.260233) (xy 57.312783 -332.216613) (xy 57.351312 -332.178083) (xy 57.394932 -332.14543)
			(xy 57.442756 -332.119316) (xy 57.493809 -332.100275) (xy 57.547052 -332.088692) (xy 57.601402 -332.084805)
			(xy 57.655751 -332.088693) (xy 57.708995 -332.100276) (xy 57.760047 -332.119318) (xy 57.807871 -332.145432)
			(xy 57.829958 -332.161388) (xy 57.84897 -332.174984) (xy 57.890853 -332.195716) (xy 57.935821 -332.208442)
			(xy 57.982358 -332.212732) (xy 58.028895 -332.208442) (xy 58.073863 -332.195716) (xy 58.115746 -332.174984)
			(xy 58.134758 -332.161388) (xy 58.156851 -332.14543) (xy 58.204679 -332.119303) (xy 58.255739 -332.100249)
			(xy 58.308991 -332.088657) (xy 58.36335 -332.084762) (xy 58.417711 -332.088643) (xy 58.470966 -332.100221)
			(xy 58.522031 -332.119262) (xy 58.569866 -332.145376) (xy 58.613497 -332.178033) (xy 58.652036 -332.216567)
			(xy 58.684698 -332.260195) (xy 58.710819 -332.308026) (xy 58.729865 -332.359089) (xy 58.741451 -332.412342)
			(xy 58.745338 -332.466702) (xy 59.46048 -332.466702) (xy 59.464368 -332.412347) (xy 59.475951 -332.359098)
			(xy 59.494996 -332.30804) (xy 59.521113 -332.260212) (xy 59.553771 -332.216588) (xy 59.592306 -332.178056)
			(xy 59.635932 -332.1454) (xy 59.683761 -332.119286) (xy 59.73482 -332.100245) (xy 59.78807 -332.088664)
			(xy 59.842426 -332.08478) (xy 59.896781 -332.088672) (xy 59.950029 -332.100259) (xy 60.001085 -332.119307)
			(xy 60.048912 -332.145428) (xy 60.071 -332.161388) (xy 60.090012 -332.174984) (xy 60.131895 -332.195716)
			(xy 60.176863 -332.208442) (xy 60.2234 -332.212732) (xy 60.269937 -332.208442) (xy 60.314905 -332.195716)
			(xy 60.356788 -332.174984) (xy 60.3758 -332.161388) (xy 60.397892 -332.145433) (xy 60.445717 -332.119313)
			(xy 60.496773 -332.100266) (xy 60.55002 -332.088678) (xy 60.604374 -332.084787) (xy 60.658729 -332.088671)
			(xy 60.711978 -332.100251) (xy 60.763036 -332.119292) (xy 60.810865 -332.145406) (xy 60.85449 -332.178061)
			(xy 60.893024 -332.216592) (xy 60.925682 -332.260216) (xy 60.951798 -332.308043) (xy 60.970842 -332.3591)
			(xy 60.982426 -332.412348) (xy 60.986313 -332.466702) (xy 61.36449 -332.466702) (xy 61.368377 -332.412349)
			(xy 61.37996 -332.359102) (xy 61.399003 -332.308046) (xy 61.425119 -332.26022) (xy 61.457776 -332.216597)
			(xy 61.496308 -332.178066) (xy 61.539932 -332.145412) (xy 61.587759 -332.119298) (xy 61.638816 -332.100256)
			(xy 61.692063 -332.088675) (xy 61.746417 -332.08479) (xy 61.80077 -332.08868) (xy 61.854016 -332.100266)
			(xy 61.905071 -332.119311) (xy 61.952896 -332.145429) (xy 61.974984 -332.161388) (xy 61.993996 -332.174984)
			(xy 62.035879 -332.195716) (xy 62.080847 -332.208442) (xy 62.127384 -332.212732) (xy 62.173921 -332.208442)
			(xy 62.218889 -332.195716) (xy 62.260772 -332.174984) (xy 62.279784 -332.161388) (xy 62.301876 -332.145432)
			(xy 62.349703 -332.119309) (xy 62.40076 -332.100259) (xy 62.454009 -332.08867) (xy 62.508365 -332.084777)
			(xy 62.562722 -332.08866) (xy 62.615973 -332.10024) (xy 62.667034 -332.11928) (xy 62.714865 -332.145395)
			(xy 62.758493 -332.17805) (xy 62.797029 -332.216583) (xy 62.829688 -332.260208) (xy 62.855806 -332.308036)
			(xy 62.874851 -332.359096) (xy 62.886435 -332.412346) (xy 62.890323 -332.466702) (xy 62.886435 -332.521059)
			(xy 62.87485 -332.574309) (xy 62.855804 -332.625368) (xy 62.829685 -332.673196) (xy 62.797025 -332.716821)
			(xy 62.758489 -332.755353) (xy 62.714861 -332.788008) (xy 62.66703 -332.814122) (xy 62.615969 -332.833162)
			(xy 62.562717 -332.844741) (xy 62.50836 -332.848623) (xy 62.454004 -332.844729) (xy 62.400755 -332.833139)
			(xy 62.349698 -332.814089) (xy 62.301872 -332.787965) (xy 62.279784 -332.772004) (xy 62.260772 -332.758408)
			(xy 62.218889 -332.737676) (xy 62.173921 -332.72495) (xy 62.127384 -332.72066) (xy 62.080847 -332.72495)
			(xy 62.035879 -332.737676) (xy 61.993996 -332.758408) (xy 61.974984 -332.772004) (xy 61.9529 -332.787968)
			(xy 61.905075 -332.814087) (xy 61.85402 -332.833133) (xy 61.800774 -332.84472) (xy 61.746421 -332.84861)
			(xy 61.692068 -332.844726) (xy 61.638821 -332.833145) (xy 61.587764 -332.814104) (xy 61.539936 -332.787991)
			(xy 61.496312 -332.755337) (xy 61.457779 -332.716806) (xy 61.425122 -332.673184) (xy 61.399005 -332.625358)
			(xy 61.379962 -332.574302) (xy 61.368378 -332.521056) (xy 61.36449 -332.466702) (xy 60.986313 -332.466702)
			(xy 60.982425 -332.521057) (xy 60.970841 -332.574305) (xy 60.951796 -332.625362) (xy 60.925679 -332.673189)
			(xy 60.893021 -332.716811) (xy 60.854487 -332.755342) (xy 60.810861 -332.787997) (xy 60.763032 -332.81411)
			(xy 60.711973 -332.83315) (xy 60.658724 -332.84473) (xy 60.60437 -332.848613) (xy 60.550015 -332.844721)
			(xy 60.496768 -332.833133) (xy 60.445713 -332.814085) (xy 60.397888 -332.787964) (xy 60.3758 -332.772004)
			(xy 60.356788 -332.758408) (xy 60.314905 -332.737676) (xy 60.269937 -332.72495) (xy 60.2234 -332.72066)
			(xy 60.176863 -332.72495) (xy 60.131895 -332.737676) (xy 60.090012 -332.758408) (xy 60.071 -332.772004)
			(xy 60.048916 -332.787969) (xy 60.00109 -332.814091) (xy 59.950033 -332.833139) (xy 59.896786 -332.844728)
			(xy 59.84243 -332.84862) (xy 59.788075 -332.844736) (xy 59.734825 -332.833156) (xy 59.683766 -332.814116)
			(xy 59.635936 -332.788002) (xy 59.592309 -332.755347) (xy 59.553774 -332.716816) (xy 59.521115 -332.673192)
			(xy 59.494998 -332.625364) (xy 59.475953 -332.574306) (xy 59.464368 -332.521058) (xy 59.46048 -332.466702)
			(xy 58.745338 -332.466702) (xy 58.74145 -332.521063) (xy 58.729864 -332.574316) (xy 58.710817 -332.625378)
			(xy 58.684696 -332.673209) (xy 58.652033 -332.716836) (xy 58.613493 -332.75537) (xy 58.569862 -332.788026)
			(xy 58.522026 -332.81414) (xy 58.470961 -332.83318) (xy 58.417706 -332.844758) (xy 58.363346 -332.848638)
			(xy 58.308986 -332.844743) (xy 58.255734 -332.833149) (xy 58.204675 -332.814095) (xy 58.156847 -332.787968)
			(xy 58.134758 -332.772004) (xy 58.115746 -332.758408) (xy 58.073863 -332.737676) (xy 58.028895 -332.72495)
			(xy 57.982358 -332.72066) (xy 57.935821 -332.72495) (xy 57.890853 -332.737676) (xy 57.84897 -332.758408)
			(xy 57.829958 -332.772004) (xy 57.807875 -332.787966) (xy 57.760052 -332.81408) (xy 57.708999 -332.833123)
			(xy 57.655756 -332.844706) (xy 57.601407 -332.848595) (xy 57.547057 -332.844708) (xy 57.493813 -332.833127)
			(xy 57.44276 -332.814086) (xy 57.394936 -332.787973) (xy 57.351316 -332.75532) (xy 57.312786 -332.716791)
			(xy 57.280132 -332.673171) (xy 57.254018 -332.625348) (xy 57.234976 -332.574295) (xy 57.223393 -332.521052)
			(xy 57.219505 -332.466702) (xy 56.858486 -332.466702) (xy 56.854598 -332.521051) (xy 56.843016 -332.574292)
			(xy 56.823974 -332.625344) (xy 56.797861 -332.673166) (xy 56.765208 -332.716784) (xy 56.726679 -332.755312)
			(xy 56.68306 -332.787965) (xy 56.635238 -332.814077) (xy 56.584186 -332.833118) (xy 56.530944 -332.844699)
			(xy 56.476596 -332.848586) (xy 56.422248 -332.844698) (xy 56.369006 -332.833115) (xy 56.317955 -332.814074)
			(xy 56.270133 -332.78796) (xy 56.248046 -332.772004) (xy 56.229034 -332.758408) (xy 56.187151 -332.737676)
			(xy 56.142183 -332.72495) (xy 56.095646 -332.72066) (xy 56.049109 -332.72495) (xy 56.004141 -332.737676)
			(xy 55.962258 -332.758408) (xy 55.943246 -332.772004) (xy 55.921161 -332.787973) (xy 55.873332 -332.814102)
			(xy 55.822271 -332.833157) (xy 55.769018 -332.844751) (xy 55.714657 -332.848647) (xy 55.660294 -332.844767)
			(xy 55.607038 -332.833189) (xy 55.555971 -332.814149) (xy 55.508135 -332.788034) (xy 55.464502 -332.755377)
			(xy 55.425961 -332.716843) (xy 55.393297 -332.673215) (xy 55.367176 -332.625382) (xy 55.348128 -332.574319)
			(xy 55.336541 -332.521064) (xy 55.332653 -332.466702) (xy 40.553706 -332.466702) (xy 40.528647 -332.48546)
			(xy 40.480825 -332.51157) (xy 40.429775 -332.530609) (xy 40.376534 -332.542189) (xy 40.322187 -332.546075)
			(xy 40.267841 -332.542186) (xy 40.214601 -332.530602) (xy 40.163552 -332.51156) (xy 40.115732 -332.485446)
			(xy 40.093646 -332.46949) (xy 40.074634 -332.455894) (xy 40.032751 -332.435162) (xy 39.987783 -332.422436)
			(xy 39.941246 -332.418146) (xy 39.894709 -332.422436) (xy 39.849741 -332.435162) (xy 39.807858 -332.455894)
			(xy 39.788846 -332.46949) (xy 39.766774 -332.485478) (xy 39.718944 -332.511609) (xy 39.667882 -332.530665)
			(xy 39.614628 -332.542261) (xy 39.560265 -332.546158) (xy 39.505901 -332.542279) (xy 39.452643 -332.530702)
			(xy 39.401574 -332.511663) (xy 39.353736 -332.485548) (xy 39.310101 -332.452891) (xy 39.271558 -332.414356)
			(xy 39.238893 -332.370728) (xy 39.212769 -332.322895) (xy 39.193719 -332.27183) (xy 39.182132 -332.218574)
			(xy 39.178241 -332.164211) (xy 29.73324 -332.164211) (xy 29.73324 -332.193138) (xy 29.733718 -332.21598)
			(xy 29.741878 -332.26093) (xy 29.757945 -332.303696) (xy 29.781402 -332.342898) (xy 29.811492 -332.377274)
			(xy 29.847245 -332.405713) (xy 29.887507 -332.4273) (xy 29.930982 -332.441337) (xy 29.976265 -332.447373)
			(xy 30.021899 -332.445213) (xy 30.06641 -332.434926) (xy 30.08757 -332.42631) (xy 30.127491 -332.409645)
			(xy 30.20975 -332.382851) (xy 30.294124 -332.363727) (xy 30.379897 -332.352433) (xy 30.466345 -332.349066)
			(xy 30.552736 -332.353654) (xy 30.638341 -332.366158) (xy 30.722436 -332.386472) (xy 30.804309 -332.414424)
			(xy 30.883269 -332.44978) (xy 30.958647 -332.492238) (xy 31.029806 -332.54144) (xy 31.096145 -332.596971)
			(xy 31.157103 -332.658361) (xy 31.212165 -332.725091) (xy 31.260864 -332.796596) (xy 31.302789 -332.872272)
			(xy 31.337586 -332.951479) (xy 31.36496 -333.033547) (xy 31.38468 -333.117783) (xy 31.39658 -333.203474)
			(xy 31.400557 -333.289896) (xy 31.398557 -333.33336) (xy 34.599874 -333.33336) (xy 34.599874 -333.24646)
			(xy 34.607892 -333.159931) (xy 34.62386 -333.074511) (xy 34.647641 -332.990929) (xy 34.679033 -332.909897)
			(xy 34.717767 -332.832108) (xy 34.763514 -332.758224) (xy 34.815883 -332.688877) (xy 34.874427 -332.624657)
			(xy 34.938647 -332.566113) (xy 35.007994 -332.513744) (xy 35.081878 -332.467997) (xy 35.159667 -332.429263)
			(xy 35.240699 -332.397871) (xy 35.324281 -332.37409) (xy 35.409701 -332.358122) (xy 35.49623 -332.350104)
			(xy 35.58313 -332.350104) (xy 35.669659 -332.358122) (xy 35.755079 -332.37409) (xy 35.838661 -332.397871)
			(xy 35.919693 -332.429263) (xy 35.997482 -332.467997) (xy 36.071366 -332.513744) (xy 36.140713 -332.566113)
			(xy 36.204933 -332.624657) (xy 36.263477 -332.688877) (xy 36.315846 -332.758224) (xy 36.361593 -332.832108)
			(xy 36.380856 -332.870794) (xy 64.789707 -332.870794) (xy 64.793595 -332.816444) (xy 64.805179 -332.7632)
			(xy 64.824222 -332.712147) (xy 64.850337 -332.664324) (xy 64.882992 -332.620704) (xy 64.921523 -332.582176)
			(xy 64.965145 -332.549523) (xy 65.01297 -332.523411) (xy 65.064024 -332.504372) (xy 65.117269 -332.492792)
			(xy 65.171619 -332.488907) (xy 65.225969 -332.492797) (xy 65.279212 -332.504383) (xy 65.330265 -332.523427)
			(xy 65.378087 -332.549544) (xy 65.400174 -332.565502) (xy 65.419186 -332.579098) (xy 65.461069 -332.59983)
			(xy 65.506037 -332.612556) (xy 65.552574 -332.616846) (xy 65.599111 -332.612556) (xy 65.644079 -332.59983)
			(xy 65.685962 -332.579098) (xy 65.704974 -332.565502) (xy 65.727053 -332.549526) (xy 65.774881 -332.5234)
			(xy 65.825941 -332.504347) (xy 65.879192 -332.492755) (xy 65.933551 -332.48886) (xy 65.987911 -332.492741)
			(xy 66.041166 -332.50432) (xy 66.09223 -332.52336) (xy 66.140064 -332.549474) (xy 66.183695 -332.58213)
			(xy 66.222234 -332.620663) (xy 66.254897 -332.664289) (xy 66.281018 -332.71212) (xy 66.300065 -332.763182)
			(xy 66.311651 -332.816434) (xy 66.31554 -332.870794) (xy 67.594099 -332.870794) (xy 67.597987 -332.816442)
			(xy 67.609571 -332.763197) (xy 67.628615 -332.712142) (xy 67.654732 -332.664317) (xy 67.687388 -332.620696)
			(xy 67.725921 -332.582167) (xy 67.769545 -332.549514) (xy 67.817372 -332.523401) (xy 67.868428 -332.504362)
			(xy 67.921675 -332.492782) (xy 67.976027 -332.488899) (xy 68.030379 -332.49279) (xy 68.083624 -332.504377)
			(xy 68.134678 -332.523424) (xy 68.182501 -332.549543) (xy 68.204588 -332.565502) (xy 68.2236 -332.579098)
			(xy 68.265483 -332.59983) (xy 68.310451 -332.612556) (xy 68.356988 -332.616846) (xy 68.403525 -332.612556)
			(xy 68.448493 -332.59983) (xy 68.490376 -332.579098) (xy 68.509388 -332.565502) (xy 68.531467 -332.549528)
			(xy 68.579294 -332.523404) (xy 68.630352 -332.504353) (xy 68.683602 -332.492762) (xy 68.737959 -332.488868)
			(xy 68.792317 -332.49275) (xy 68.845569 -332.504329) (xy 68.896632 -332.52337) (xy 68.944464 -332.549483)
			(xy 68.988093 -332.582139) (xy 69.02663 -332.620671) (xy 69.059291 -332.664296) (xy 69.085411 -332.712126)
			(xy 69.104457 -332.763186) (xy 69.116043 -332.816436) (xy 69.119932 -332.870794) (xy 69.116045 -332.925152)
			(xy 69.104461 -332.978403) (xy 69.085416 -333.029463) (xy 69.059298 -333.077293) (xy 69.026638 -333.12092)
			(xy 68.988102 -333.159453) (xy 68.944474 -333.19211) (xy 68.896643 -333.218225) (xy 68.845581 -333.237267)
			(xy 68.792329 -333.248848) (xy 68.737971 -333.252732) (xy 68.683614 -333.24884) (xy 68.630364 -333.237251)
			(xy 68.579305 -333.218201) (xy 68.531477 -333.192079) (xy 68.509388 -333.176118) (xy 68.490376 -333.162522)
			(xy 68.448493 -333.14179) (xy 68.403525 -333.129064) (xy 68.356988 -333.124774) (xy 68.310451 -333.129064)
			(xy 68.265483 -333.14179) (xy 68.2236 -333.162522) (xy 68.204588 -333.176118) (xy 68.182491 -333.192063)
			(xy 68.134667 -333.218181) (xy 68.083612 -333.237226) (xy 68.030367 -333.248812) (xy 67.976015 -333.252701)
			(xy 67.921663 -333.248816) (xy 67.868417 -333.237235) (xy 67.817361 -333.218194) (xy 67.769535 -333.19208)
			(xy 67.725912 -333.159425) (xy 67.687381 -333.120895) (xy 67.654725 -333.077273) (xy 67.62861 -333.029447)
			(xy 67.609568 -332.978392) (xy 67.597985 -332.925146) (xy 67.594099 -332.870794) (xy 66.31554 -332.870794)
			(xy 66.311653 -332.925154) (xy 66.300068 -332.978407) (xy 66.281023 -333.029469) (xy 66.254903 -333.0773)
			(xy 66.222242 -333.120928) (xy 66.183704 -333.159462) (xy 66.140075 -333.19212) (xy 66.092241 -333.218235)
			(xy 66.041177 -333.237277) (xy 65.987923 -333.248857) (xy 65.933563 -333.25274) (xy 65.879204 -333.248847)
			(xy 65.825952 -333.237256) (xy 65.774892 -333.218205) (xy 65.727063 -333.19208) (xy 65.704974 -333.176118)
			(xy 65.685962 -333.162522) (xy 65.644079 -333.14179) (xy 65.599111 -333.129064) (xy 65.552574 -333.124774)
			(xy 65.506037 -333.129064) (xy 65.461069 -333.14179) (xy 65.419186 -333.162522) (xy 65.400174 -333.176118)
			(xy 65.378077 -333.192062) (xy 65.330254 -333.218178) (xy 65.279201 -333.237221) (xy 65.225957 -333.248805)
			(xy 65.171607 -333.252693) (xy 65.117257 -333.248807) (xy 65.064013 -333.237225) (xy 65.012959 -333.218184)
			(xy 64.965135 -333.19207) (xy 64.921514 -333.159416) (xy 64.882985 -333.120887) (xy 64.850331 -333.077266)
			(xy 64.824217 -333.029442) (xy 64.805175 -332.978388) (xy 64.793594 -332.925144) (xy 64.789707 -332.870794)
			(xy 36.380856 -332.870794) (xy 36.400327 -332.909897) (xy 36.431719 -332.990929) (xy 36.4555 -333.074511)
			(xy 36.471468 -333.159931) (xy 36.479486 -333.24646) (xy 36.479988 -333.28991) (xy 36.479486 -333.33336)
			(xy 36.471468 -333.419889) (xy 36.4555 -333.505309) (xy 36.431719 -333.588891) (xy 36.400327 -333.669923)
			(xy 36.361593 -333.747712) (xy 36.315846 -333.821596) (xy 36.263477 -333.890943) (xy 36.204933 -333.955163)
			(xy 36.140713 -334.013707) (xy 36.071366 -334.066076) (xy 35.997482 -334.111823) (xy 35.919693 -334.150557)
			(xy 35.838661 -334.181949) (xy 35.755079 -334.20573) (xy 35.669659 -334.221698) (xy 35.58313 -334.229716)
			(xy 35.49623 -334.229716) (xy 35.409701 -334.221698) (xy 35.324281 -334.20573) (xy 35.240699 -334.181949)
			(xy 35.159667 -334.150557) (xy 35.081878 -334.111823) (xy 35.007994 -334.066076) (xy 34.938647 -334.013707)
			(xy 34.874427 -333.955163) (xy 34.815883 -333.890943) (xy 34.763514 -333.821596) (xy 34.717767 -333.747712)
			(xy 34.679033 -333.669923) (xy 34.647641 -333.588891) (xy 34.62386 -333.505309) (xy 34.607892 -333.419889)
			(xy 34.599874 -333.33336) (xy 31.398557 -333.33336) (xy 31.39658 -333.376318) (xy 31.384682 -333.462009)
			(xy 31.364962 -333.546245) (xy 31.337589 -333.628314) (xy 31.302793 -333.707521) (xy 31.260868 -333.783198)
			(xy 31.212169 -333.854703) (xy 31.157109 -333.921433) (xy 31.096151 -333.982823) (xy 31.029813 -334.038355)
			(xy 30.958653 -334.087558) (xy 30.883276 -334.130017) (xy 30.804316 -334.165373) (xy 30.722444 -334.193326)
			(xy 30.638349 -334.213641) (xy 30.552744 -334.226145) (xy 30.466352 -334.230734) (xy 30.379905 -334.227368)
			(xy 30.294131 -334.216075) (xy 30.209758 -334.196951) (xy 30.127498 -334.170158) (xy 30.08757 -334.15351)
			(xy 30.066403 -334.144941) (xy 30.021906 -334.134702) (xy 29.976295 -334.132576) (xy 29.931038 -334.138634)
			(xy 29.887591 -334.152679) (xy 29.847352 -334.174259) (xy 29.811616 -334.202681) (xy 29.781532 -334.23703)
			(xy 29.758068 -334.276201) (xy 29.74198 -334.318933) (xy 29.733784 -334.363852) (xy 29.73324 -334.386682)
			(xy 29.73324 -334.733138) (xy 29.733718 -334.75598) (xy 29.741878 -334.80093) (xy 29.75468 -334.835005)
			(xy 39.17825 -334.835005) (xy 39.182137 -334.780643) (xy 39.193723 -334.727387) (xy 39.21277 -334.676323)
			(xy 39.238891 -334.628489) (xy 39.271554 -334.584861) (xy 39.310094 -334.546325) (xy 39.353727 -334.513667)
			(xy 39.401564 -334.487551) (xy 39.45263 -334.46851) (xy 39.505887 -334.456931) (xy 39.560249 -334.45305)
			(xy 39.614611 -334.456945) (xy 39.667865 -334.468538) (xy 39.718926 -334.487592) (xy 39.766756 -334.51372)
			(xy 39.788846 -334.529684) (xy 39.807858 -334.54328) (xy 39.849741 -334.564012) (xy 39.894709 -334.576738)
			(xy 39.941246 -334.581028) (xy 39.987783 -334.576738) (xy 40.032751 -334.564012) (xy 40.074634 -334.54328)
			(xy 40.093646 -334.529684) (xy 40.115741 -334.513739) (xy 40.163562 -334.487626) (xy 40.214614 -334.468586)
			(xy 40.267855 -334.457004) (xy 40.322203 -334.453117) (xy 40.376551 -334.457005) (xy 40.429792 -334.468587)
			(xy 40.454811 -334.477919) (xy 55.289251 -334.477919) (xy 55.293136 -334.423559) (xy 55.304719 -334.370305)
			(xy 55.323763 -334.319241) (xy 55.34988 -334.271408) (xy 55.38254 -334.227779) (xy 55.421076 -334.189242)
			(xy 55.464705 -334.156582) (xy 55.512538 -334.130464) (xy 55.563601 -334.11142) (xy 55.616855 -334.099837)
			(xy 55.671216 -334.095951) (xy 55.725576 -334.099841) (xy 55.778829 -334.111429) (xy 55.82989 -334.130477)
			(xy 55.877721 -334.156599) (xy 55.899812 -334.17256) (xy 55.918824 -334.186156) (xy 55.960707 -334.206888)
			(xy 56.005675 -334.219614) (xy 56.052212 -334.223904) (xy 56.098749 -334.219614) (xy 56.143717 -334.206888)
			(xy 56.1856 -334.186156) (xy 56.204612 -334.17256) (xy 56.22673 -334.156644) (xy 56.274553 -334.13053)
			(xy 56.325605 -334.111487) (xy 56.378848 -334.099904) (xy 56.433198 -334.096016) (xy 56.487548 -334.099903)
			(xy 56.540791 -334.111486) (xy 56.591844 -334.130528) (xy 56.639667 -334.156642) (xy 56.683286 -334.189297)
			(xy 56.721815 -334.227827) (xy 56.754467 -334.271448) (xy 56.780579 -334.319272) (xy 56.799619 -334.370326)
			(xy 56.811199 -334.423569) (xy 56.815084 -334.477919) (xy 57.175943 -334.477919) (xy 57.179829 -334.423557)
			(xy 57.191412 -334.370302) (xy 57.210457 -334.319237) (xy 57.236576 -334.271402) (xy 57.269236 -334.227772)
			(xy 57.307774 -334.189234) (xy 57.351405 -334.156574) (xy 57.39924 -334.130456) (xy 57.450305 -334.111411)
			(xy 57.50356 -334.099829) (xy 57.557922 -334.095943) (xy 57.612284 -334.099835) (xy 57.665538 -334.111424)
			(xy 57.716601 -334.130474) (xy 57.764433 -334.156598) (xy 57.786524 -334.17256) (xy 57.805536 -334.186156)
			(xy 57.847419 -334.206888) (xy 57.892387 -334.219614) (xy 57.938924 -334.223904) (xy 57.985461 -334.219614)
			(xy 58.030429 -334.206888) (xy 58.072312 -334.186156) (xy 58.091324 -334.17256) (xy 58.113442 -334.156645)
			(xy 58.161264 -334.130533) (xy 58.212315 -334.111492) (xy 58.265557 -334.09991) (xy 58.319905 -334.096023)
			(xy 58.374253 -334.099911) (xy 58.427494 -334.111494) (xy 58.478545 -334.130537) (xy 58.526366 -334.15665)
			(xy 58.569985 -334.189304) (xy 58.608511 -334.227834) (xy 58.641163 -334.271454) (xy 58.667273 -334.319277)
			(xy 58.686313 -334.370329) (xy 58.697892 -334.423571) (xy 58.701777 -334.477919) (xy 59.417078 -334.477919)
			(xy 59.420963 -334.423565) (xy 59.432544 -334.370317) (xy 59.451585 -334.319259) (xy 59.477698 -334.271431)
			(xy 59.510353 -334.227806) (xy 59.548884 -334.189272) (xy 59.592506 -334.156614) (xy 59.640332 -334.130497)
			(xy 59.691389 -334.111452) (xy 59.744636 -334.099867) (xy 59.798989 -334.095978) (xy 59.853344 -334.099864)
			(xy 59.906591 -334.111446) (xy 59.957649 -334.130488) (xy 60.005476 -334.156603) (xy 60.027566 -334.17256)
			(xy 60.046578 -334.186156) (xy 60.088461 -334.206888) (xy 60.133429 -334.219614) (xy 60.179966 -334.223904)
			(xy 60.226503 -334.219614) (xy 60.271471 -334.206888) (xy 60.313354 -334.186156) (xy 60.332366 -334.17256)
			(xy 60.354485 -334.15664) (xy 60.402311 -334.130518) (xy 60.453368 -334.111469) (xy 60.506616 -334.099881)
			(xy 60.560972 -334.095989) (xy 60.615328 -334.099873) (xy 60.668578 -334.111453) (xy 60.719638 -334.130495)
			(xy 60.767468 -334.15661) (xy 60.811094 -334.189266) (xy 60.849628 -334.2278) (xy 60.882285 -334.271425)
			(xy 60.908401 -334.319254) (xy 60.927444 -334.370313) (xy 60.939026 -334.423563) (xy 60.942911 -334.477919)
			(xy 61.320928 -334.477919) (xy 61.324814 -334.423554) (xy 61.336398 -334.370295) (xy 61.355444 -334.319227)
			(xy 61.381565 -334.271389) (xy 61.414229 -334.227757) (xy 61.45277 -334.189217) (xy 61.496404 -334.156556)
			(xy 61.544243 -334.130437) (xy 61.595312 -334.111393) (xy 61.648572 -334.099811) (xy 61.702937 -334.095928)
			(xy 61.757302 -334.099822) (xy 61.81056 -334.111414) (xy 61.861625 -334.130468) (xy 61.909458 -334.156596)
			(xy 61.93155 -334.17256) (xy 61.950562 -334.186156) (xy 61.992445 -334.206888) (xy 62.037413 -334.219614)
			(xy 62.08395 -334.223904) (xy 62.130487 -334.219614) (xy 62.175455 -334.206888) (xy 62.217338 -334.186156)
			(xy 62.23635 -334.17256) (xy 62.258469 -334.156639) (xy 62.306296 -334.130514) (xy 62.357355 -334.111463)
			(xy 62.410605 -334.099873) (xy 62.464963 -334.095979) (xy 62.519321 -334.099862) (xy 62.572574 -334.111442)
			(xy 62.623636 -334.130483) (xy 62.671468 -334.156599) (xy 62.715096 -334.189256) (xy 62.753632 -334.22779)
			(xy 62.786292 -334.271417) (xy 62.812409 -334.319248) (xy 62.831453 -334.370309) (xy 62.843035 -334.423561)
			(xy 62.846921 -334.477919) (xy 62.84303 -334.532277) (xy 62.831442 -334.585528) (xy 62.812393 -334.636587)
			(xy 62.786271 -334.684415) (xy 62.753607 -334.728039) (xy 62.715067 -334.766569) (xy 62.671436 -334.799222)
			(xy 62.623601 -334.825332) (xy 62.572537 -334.844369) (xy 62.519283 -334.855944) (xy 62.464924 -334.859821)
			(xy 62.410567 -334.855922) (xy 62.357318 -334.844326) (xy 62.306261 -334.82527) (xy 62.258437 -334.79914)
			(xy 62.23635 -334.783176) (xy 62.217338 -334.76958) (xy 62.175455 -334.748848) (xy 62.130487 -334.736122)
			(xy 62.08395 -334.731832) (xy 62.037413 -334.736122) (xy 61.992445 -334.748848) (xy 61.950562 -334.76958)
			(xy 61.93155 -334.783176) (xy 61.909491 -334.799183) (xy 61.86166 -334.825316) (xy 61.810596 -334.844375)
			(xy 61.75734 -334.855973) (xy 61.702976 -334.859872) (xy 61.64861 -334.855994) (xy 61.595349 -334.844418)
			(xy 61.544278 -334.825379) (xy 61.496437 -334.799265) (xy 61.452799 -334.766608) (xy 61.414254 -334.728072)
			(xy 61.381586 -334.684443) (xy 61.35546 -334.636608) (xy 61.336409 -334.585542) (xy 61.324819 -334.532284)
			(xy 61.320928 -334.477919) (xy 60.942911 -334.477919) (xy 60.939021 -334.532275) (xy 60.927433 -334.585524)
			(xy 60.908385 -334.636581) (xy 60.882265 -334.684407) (xy 60.849603 -334.728029) (xy 60.811065 -334.766559)
			(xy 60.767435 -334.799211) (xy 60.719603 -334.825321) (xy 60.668541 -334.844358) (xy 60.61529 -334.855933)
			(xy 60.560933 -334.859811) (xy 60.506578 -334.855914) (xy 60.453331 -334.84432) (xy 60.402276 -334.825266)
			(xy 60.354453 -334.799139) (xy 60.332366 -334.783176) (xy 60.313354 -334.76958) (xy 60.271471 -334.748848)
			(xy 60.226503 -334.736122) (xy 60.179966 -334.731832) (xy 60.133429 -334.736122) (xy 60.088461 -334.748848)
			(xy 60.046578 -334.76958) (xy 60.027566 -334.783176) (xy 60.005509 -334.799176) (xy 59.957684 -334.825296)
			(xy 59.906628 -334.844343) (xy 59.853382 -334.85593) (xy 59.799028 -334.859822) (xy 59.744674 -334.855938)
			(xy 59.691425 -334.844359) (xy 59.640367 -334.825319) (xy 59.592538 -334.799206) (xy 59.548913 -334.766553)
			(xy 59.510378 -334.728023) (xy 59.477719 -334.684401) (xy 59.451601 -334.636576) (xy 59.432555 -334.58552)
			(xy 59.420968 -334.532273) (xy 59.417078 -334.477919) (xy 58.701777 -334.477919) (xy 58.697887 -334.532267)
			(xy 58.686302 -334.585508) (xy 58.667257 -334.636558) (xy 58.641142 -334.684379) (xy 58.608486 -334.727995)
			(xy 58.569955 -334.766521) (xy 58.526334 -334.79917) (xy 58.47851 -334.825279) (xy 58.427457 -334.844317)
			(xy 58.374215 -334.855894) (xy 58.319866 -334.859777) (xy 58.265519 -334.855885) (xy 58.212278 -334.844298)
			(xy 58.161229 -334.825252) (xy 58.113409 -334.799134) (xy 58.091324 -334.783176) (xy 58.072312 -334.76958)
			(xy 58.030429 -334.748848) (xy 57.985461 -334.736122) (xy 57.938924 -334.731832) (xy 57.892387 -334.736122)
			(xy 57.847419 -334.748848) (xy 57.805536 -334.76958) (xy 57.786524 -334.783176) (xy 57.764465 -334.799181)
			(xy 57.716636 -334.82531) (xy 57.665575 -334.844365) (xy 57.612322 -334.85596) (xy 57.557961 -334.859857)
			(xy 57.503598 -334.855977) (xy 57.450342 -334.8444) (xy 57.399275 -334.82536) (xy 57.351437 -334.799247)
			(xy 57.307803 -334.766591) (xy 57.269262 -334.728057) (xy 57.236596 -334.68443) (xy 57.210473 -334.636598)
			(xy 57.191423 -334.585535) (xy 57.179835 -334.532281) (xy 57.175943 -334.477919) (xy 56.815084 -334.477919)
			(xy 56.811194 -334.532269) (xy 56.799608 -334.585511) (xy 56.780563 -334.636563) (xy 56.754446 -334.684385)
			(xy 56.72179 -334.728002) (xy 56.683257 -334.766529) (xy 56.639634 -334.799179) (xy 56.591809 -334.825288)
			(xy 56.540754 -334.844325) (xy 56.48751 -334.855902) (xy 56.43316 -334.859784) (xy 56.37881 -334.855891)
			(xy 56.325568 -334.844302) (xy 56.274518 -334.825254) (xy 56.226698 -334.799135) (xy 56.204612 -334.783176)
			(xy 56.1856 -334.76958) (xy 56.143717 -334.748848) (xy 56.098749 -334.736122) (xy 56.052212 -334.731832)
			(xy 56.005675 -334.736122) (xy 55.960707 -334.748848) (xy 55.918824 -334.76958) (xy 55.899812 -334.783176)
			(xy 55.877754 -334.79918) (xy 55.829925 -334.825307) (xy 55.778866 -334.844361) (xy 55.725614 -334.855953)
			(xy 55.671254 -334.859849) (xy 55.616893 -334.855969) (xy 55.563638 -334.844391) (xy 55.512573 -334.825352)
			(xy 55.464737 -334.799239) (xy 55.421105 -334.766583) (xy 55.382565 -334.72805) (xy 55.349901 -334.684424)
			(xy 55.323779 -334.636594) (xy 55.30473 -334.585532) (xy 55.293142 -334.532279) (xy 55.289251 -334.477919)
			(xy 40.454811 -334.477919) (xy 40.480843 -334.487629) (xy 40.528664 -334.513742) (xy 40.572283 -334.546395)
			(xy 40.61081 -334.584923) (xy 40.643462 -334.628542) (xy 40.669574 -334.676364) (xy 40.688615 -334.727416)
			(xy 40.700196 -334.780657) (xy 40.704083 -334.835005) (xy 40.700195 -334.889352) (xy 40.688612 -334.942594)
			(xy 40.66957 -334.993645) (xy 40.658297 -335.01429) (xy 64.789712 -335.01429) (xy 64.7936 -334.959941)
			(xy 64.805184 -334.906698) (xy 64.824228 -334.855646) (xy 64.850343 -334.807824) (xy 64.882998 -334.764205)
			(xy 64.921529 -334.725677) (xy 64.965151 -334.693026) (xy 65.012975 -334.666914) (xy 65.064029 -334.647875)
			(xy 65.117273 -334.636296) (xy 65.171623 -334.632412) (xy 65.225972 -334.636302) (xy 65.279215 -334.647888)
			(xy 65.330266 -334.666933) (xy 65.378088 -334.69305) (xy 65.400174 -334.709008) (xy 65.419186 -334.722604)
			(xy 65.461069 -334.743336) (xy 65.506037 -334.756062) (xy 65.552574 -334.760352) (xy 65.599111 -334.756062)
			(xy 65.644079 -334.743336) (xy 65.685962 -334.722604) (xy 65.704974 -334.709008) (xy 65.727048 -334.693024)
			(xy 65.774876 -334.666897) (xy 65.825936 -334.647844) (xy 65.879188 -334.636251) (xy 65.933548 -334.632355)
			(xy 65.987908 -334.636236) (xy 66.041163 -334.647814) (xy 66.092229 -334.666854) (xy 66.140064 -334.692968)
			(xy 66.183696 -334.725624) (xy 66.222236 -334.764157) (xy 66.254899 -334.807784) (xy 66.28102 -334.855615)
			(xy 66.300069 -334.906677) (xy 66.311655 -334.95993) (xy 66.315545 -335.01429) (xy 67.594103 -335.01429)
			(xy 67.597992 -334.959939) (xy 67.609577 -334.906694) (xy 67.628621 -334.85564) (xy 67.654738 -334.807817)
			(xy 67.687394 -334.764196) (xy 67.725927 -334.725668) (xy 67.769551 -334.693016) (xy 67.817377 -334.666904)
			(xy 67.868433 -334.647865) (xy 67.921679 -334.636287) (xy 67.976031 -334.632403) (xy 68.030382 -334.636295)
			(xy 68.083626 -334.647883) (xy 68.134679 -334.66693) (xy 68.182501 -334.693049) (xy 68.204588 -334.709008)
			(xy 68.2236 -334.722604) (xy 68.265483 -334.743336) (xy 68.310451 -334.756062) (xy 68.356988 -334.760352)
			(xy 68.403525 -334.756062) (xy 68.448493 -334.743336) (xy 68.490376 -334.722604) (xy 68.509388 -334.709008)
			(xy 68.531461 -334.693025) (xy 68.579289 -334.666901) (xy 68.630347 -334.647849) (xy 68.683598 -334.636258)
			(xy 68.737956 -334.632363) (xy 68.792314 -334.636245) (xy 68.845567 -334.647824) (xy 68.89663 -334.666864)
			(xy 68.944464 -334.692977) (xy 68.988094 -334.725633) (xy 69.026632 -334.764166) (xy 69.059293 -334.807791)
			(xy 69.085414 -334.85562) (xy 69.104461 -334.906681) (xy 69.116047 -334.959932) (xy 69.119937 -335.01429)
			(xy 69.11605 -335.068649) (xy 69.104466 -335.121901) (xy 69.085422 -335.172962) (xy 69.059304 -335.220793)
			(xy 69.026644 -335.26442) (xy 68.988108 -335.302955) (xy 68.94448 -335.335612) (xy 68.896648 -335.361728)
			(xy 68.845586 -335.380771) (xy 68.792333 -335.392352) (xy 68.737975 -335.396237) (xy 68.683617 -335.392345)
			(xy 68.630366 -335.380757) (xy 68.579306 -335.361707) (xy 68.531478 -335.335585) (xy 68.509388 -335.319624)
			(xy 68.490376 -335.306028) (xy 68.448493 -335.285296) (xy 68.403525 -335.27257) (xy 68.356988 -335.26828)
			(xy 68.310451 -335.27257) (xy 68.265483 -335.285296) (xy 68.2236 -335.306028) (xy 68.204588 -335.319624)
			(xy 68.182485 -335.335561) (xy 68.134661 -335.361678) (xy 68.083608 -335.380723) (xy 68.030363 -335.392307)
			(xy 67.976012 -335.396197) (xy 67.92166 -335.392311) (xy 67.868415 -335.380729) (xy 67.81736 -335.361688)
			(xy 67.769534 -335.335574) (xy 67.725912 -335.302919) (xy 67.687382 -335.264389) (xy 67.654727 -335.220767)
			(xy 67.628613 -335.172942) (xy 67.609571 -335.121887) (xy 67.59799 -335.068642) (xy 67.594103 -335.01429)
			(xy 66.315545 -335.01429) (xy 66.311658 -335.068651) (xy 66.300074 -335.121905) (xy 66.281028 -335.172968)
			(xy 66.254909 -335.2208) (xy 66.222248 -335.264428) (xy 66.18371 -335.302964) (xy 66.14008 -335.335622)
			(xy 66.092246 -335.361738) (xy 66.041182 -335.380781) (xy 65.987927 -335.392361) (xy 65.933567 -335.396245)
			(xy 65.879207 -335.392352) (xy 65.825954 -335.380762) (xy 65.774893 -335.361711) (xy 65.727064 -335.335586)
			(xy 65.704974 -335.319624) (xy 65.685962 -335.306028) (xy 65.644079 -335.285296) (xy 65.599111 -335.27257)
			(xy 65.552574 -335.26828) (xy 65.506037 -335.27257) (xy 65.461069 -335.285296) (xy 65.419186 -335.306028)
			(xy 65.400174 -335.319624) (xy 65.378071 -335.33556) (xy 65.330249 -335.361675) (xy 65.279196 -335.380717)
			(xy 65.225953 -335.3923) (xy 65.171604 -335.396188) (xy 65.117254 -335.392301) (xy 65.064011 -335.380719)
			(xy 65.012958 -335.361678) (xy 64.965135 -335.335564) (xy 64.921515 -335.30291) (xy 64.882986 -335.264381)
			(xy 64.850333 -335.22076) (xy 64.82422 -335.172937) (xy 64.805179 -335.121883) (xy 64.793598 -335.06864)
			(xy 64.789712 -335.01429) (xy 40.658297 -335.01429) (xy 40.643457 -335.041466) (xy 40.610804 -335.085084)
			(xy 40.572275 -335.123611) (xy 40.528656 -335.156263) (xy 40.480834 -335.182375) (xy 40.429783 -335.201415)
			(xy 40.376541 -335.212996) (xy 40.322193 -335.216883) (xy 40.267846 -335.212995) (xy 40.214605 -335.201412)
			(xy 40.163554 -335.18237) (xy 40.115733 -335.156256) (xy 40.093646 -335.1403) (xy 40.074634 -335.126704)
			(xy 40.032751 -335.105972) (xy 39.987783 -335.093246) (xy 39.941246 -335.088956) (xy 39.894709 -335.093246)
			(xy 39.849741 -335.105972) (xy 39.807858 -335.126704) (xy 39.788846 -335.1403) (xy 39.766764 -335.156275)
			(xy 39.718935 -335.182404) (xy 39.667874 -335.201459) (xy 39.614621 -335.213054) (xy 39.560259 -335.21695)
			(xy 39.505896 -335.21307) (xy 39.452639 -335.201493) (xy 39.401572 -335.182453) (xy 39.353735 -335.156338)
			(xy 39.310102 -335.123681) (xy 39.27156 -335.085147) (xy 39.238896 -335.041519) (xy 39.212774 -334.993686)
			(xy 39.193725 -334.942622) (xy 39.182139 -334.889367) (xy 39.17825 -334.835005) (xy 29.75468 -334.835005)
			(xy 29.757945 -334.843696) (xy 29.781402 -334.882898) (xy 29.811492 -334.917274) (xy 29.847245 -334.945713)
			(xy 29.887507 -334.9673) (xy 29.930982 -334.981337) (xy 29.976265 -334.987373) (xy 30.021899 -334.985213)
			(xy 30.06641 -334.974926) (xy 30.08757 -334.96631) (xy 30.127491 -334.949645) (xy 30.20975 -334.922851)
			(xy 30.294124 -334.903727) (xy 30.379897 -334.892433) (xy 30.466345 -334.889066) (xy 30.552736 -334.893654)
			(xy 30.638341 -334.906158) (xy 30.722436 -334.926472) (xy 30.804309 -334.954424) (xy 30.883269 -334.98978)
			(xy 30.958647 -335.032238) (xy 31.029806 -335.08144) (xy 31.096145 -335.136971) (xy 31.157103 -335.198361)
			(xy 31.212165 -335.265091) (xy 31.260864 -335.336596) (xy 31.302789 -335.412272) (xy 31.337586 -335.491479)
			(xy 31.36496 -335.573547) (xy 31.38468 -335.657783) (xy 31.39658 -335.743474) (xy 31.400557 -335.829896)
			(xy 31.398557 -335.87336) (xy 34.599874 -335.87336) (xy 34.599874 -335.78646) (xy 34.607892 -335.699931)
			(xy 34.62386 -335.614511) (xy 34.647641 -335.530929) (xy 34.679033 -335.449897) (xy 34.717767 -335.372108)
			(xy 34.763514 -335.298224) (xy 34.815883 -335.228877) (xy 34.874427 -335.164657) (xy 34.938647 -335.106113)
			(xy 35.007994 -335.053744) (xy 35.081878 -335.007997) (xy 35.159667 -334.969263) (xy 35.240699 -334.937871)
			(xy 35.324281 -334.91409) (xy 35.409701 -334.898122) (xy 35.49623 -334.890104) (xy 35.58313 -334.890104)
			(xy 35.669659 -334.898122) (xy 35.755079 -334.91409) (xy 35.838661 -334.937871) (xy 35.919693 -334.969263)
			(xy 35.997482 -335.007997) (xy 36.071366 -335.053744) (xy 36.140713 -335.106113) (xy 36.204933 -335.164657)
			(xy 36.263477 -335.228877) (xy 36.315846 -335.298224) (xy 36.361593 -335.372108) (xy 36.400327 -335.449897)
			(xy 36.431719 -335.530929) (xy 36.4555 -335.614511) (xy 36.471468 -335.699931) (xy 36.479486 -335.78646)
			(xy 36.479988 -335.82991) (xy 36.479486 -335.87336) (xy 36.471468 -335.959889) (xy 36.4555 -336.045309)
			(xy 36.431719 -336.128891) (xy 36.400327 -336.209923) (xy 36.361593 -336.287712) (xy 36.315846 -336.361596)
			(xy 36.310703 -336.368406) (xy 55.289268 -336.368406) (xy 55.293155 -336.314048) (xy 55.304739 -336.260797)
			(xy 55.323784 -336.209737) (xy 55.349902 -336.161907) (xy 55.382562 -336.11828) (xy 55.421098 -336.079747)
			(xy 55.464726 -336.04709) (xy 55.512557 -336.020975) (xy 55.563619 -336.001933) (xy 55.616871 -335.990352)
			(xy 55.671229 -335.986468) (xy 55.725586 -335.99036) (xy 55.778836 -336.001949) (xy 55.829895 -336.020999)
			(xy 55.877723 -336.047121) (xy 55.899812 -336.063082) (xy 55.918824 -336.076678) (xy 55.960707 -336.09741)
			(xy 56.005675 -336.110136) (xy 56.052212 -336.114426) (xy 56.098749 -336.110136) (xy 56.143717 -336.09741)
			(xy 56.1856 -336.076678) (xy 56.204612 -336.063082) (xy 56.226709 -336.047137) (xy 56.274533 -336.021019)
			(xy 56.325588 -336.001974) (xy 56.378833 -335.990388) (xy 56.433185 -335.986499) (xy 56.487537 -335.990384)
			(xy 56.540783 -336.001965) (xy 56.591839 -336.021006) (xy 56.639665 -336.04712) (xy 56.683288 -336.079775)
			(xy 56.721819 -336.118305) (xy 56.754475 -336.161927) (xy 56.78059 -336.209753) (xy 56.799632 -336.260808)
			(xy 56.811215 -336.314054) (xy 56.815101 -336.368406) (xy 57.175961 -336.368406) (xy 57.179848 -336.314047)
			(xy 57.191433 -336.260794) (xy 57.210478 -336.209732) (xy 57.236597 -336.161901) (xy 57.269258 -336.118273)
			(xy 57.307796 -336.079739) (xy 57.351426 -336.047081) (xy 57.399259 -336.020966) (xy 57.450322 -336.001924)
			(xy 57.503576 -335.990344) (xy 57.557936 -335.986461) (xy 57.612295 -335.990354) (xy 57.665546 -336.001944)
			(xy 57.716606 -336.020996) (xy 57.764435 -336.04712) (xy 57.786524 -336.063082) (xy 57.805536 -336.076678)
			(xy 57.847419 -336.09741) (xy 57.892387 -336.110136) (xy 57.938924 -336.114426) (xy 57.985461 -336.110136)
			(xy 58.030429 -336.09741) (xy 58.072312 -336.076678) (xy 58.091324 -336.063082) (xy 58.113421 -336.047138)
			(xy 58.161244 -336.021022) (xy 58.212297 -336.001978) (xy 58.265541 -335.990394) (xy 58.319892 -335.986506)
			(xy 58.374242 -335.990392) (xy 58.427486 -336.001974) (xy 58.47854 -336.021015) (xy 58.526365 -336.047129)
			(xy 58.569986 -336.079782) (xy 58.608516 -336.118312) (xy 58.64117 -336.161933) (xy 58.667284 -336.209757)
			(xy 58.686326 -336.260811) (xy 58.697908 -336.314055) (xy 58.701794 -336.368406) (xy 59.417096 -336.368406)
			(xy 59.420982 -336.314055) (xy 59.432564 -336.260809) (xy 59.451606 -336.209755) (xy 59.47772 -336.161929)
			(xy 59.510375 -336.118308) (xy 59.548905 -336.079777) (xy 59.592527 -336.047122) (xy 59.640352 -336.021008)
			(xy 59.691406 -336.001965) (xy 59.744651 -335.990383) (xy 59.799003 -335.986496) (xy 59.853354 -335.990384)
			(xy 59.906599 -336.001967) (xy 59.957653 -336.02101) (xy 60.005478 -336.047125) (xy 60.027566 -336.063082)
			(xy 60.046578 -336.076678) (xy 60.088461 -336.09741) (xy 60.133429 -336.110136) (xy 60.179966 -336.114426)
			(xy 60.226503 -336.110136) (xy 60.271471 -336.09741) (xy 60.313354 -336.076678) (xy 60.332366 -336.063082)
			(xy 60.354464 -336.047133) (xy 60.402292 -336.021008) (xy 60.45335 -336.001956) (xy 60.506601 -335.990365)
			(xy 60.560959 -335.986471) (xy 60.615317 -335.990353) (xy 60.66857 -336.001933) (xy 60.719633 -336.020973)
			(xy 60.767466 -336.047088) (xy 60.811095 -336.079744) (xy 60.849632 -336.118278) (xy 60.882293 -336.161904)
			(xy 60.908412 -336.209735) (xy 60.927457 -336.260796) (xy 60.939042 -336.314048) (xy 60.942929 -336.368406)
			(xy 61.320946 -336.368406) (xy 61.324833 -336.314043) (xy 61.336419 -336.260787) (xy 61.355466 -336.209722)
			(xy 61.381587 -336.161888) (xy 61.414251 -336.118258) (xy 61.452792 -336.079722) (xy 61.496425 -336.047063)
			(xy 61.544262 -336.020947) (xy 61.59533 -336.001906) (xy 61.648587 -335.990327) (xy 61.70295 -335.986446)
			(xy 61.757313 -335.990341) (xy 61.810567 -336.001934) (xy 61.86163 -336.020989) (xy 61.90946 -336.047118)
			(xy 61.93155 -336.063082) (xy 61.950562 -336.076678) (xy 61.992445 -336.09741) (xy 62.037413 -336.110136)
			(xy 62.08395 -336.114426) (xy 62.130487 -336.110136) (xy 62.175455 -336.09741) (xy 62.217338 -336.076678)
			(xy 62.23635 -336.063082) (xy 62.258449 -336.047131) (xy 62.306277 -336.021004) (xy 62.357337 -336.00195)
			(xy 62.410589 -335.990357) (xy 62.46495 -335.986462) (xy 62.519311 -335.990343) (xy 62.572566 -336.001921)
			(xy 62.623631 -336.020962) (xy 62.671466 -336.047077) (xy 62.715098 -336.079734) (xy 62.753637 -336.118269)
			(xy 62.786299 -336.161896) (xy 62.81242 -336.209728) (xy 62.831466 -336.260791) (xy 62.843051 -336.314045)
			(xy 62.846938 -336.368406) (xy 62.843049 -336.422767) (xy 62.831463 -336.47602) (xy 62.812415 -336.527082)
			(xy 62.786293 -336.574914) (xy 62.753629 -336.61854) (xy 62.715089 -336.657074) (xy 62.671456 -336.68973)
			(xy 62.62362 -336.715843) (xy 62.572554 -336.734882) (xy 62.519299 -336.746459) (xy 62.464938 -336.750338)
			(xy 62.410578 -336.746441) (xy 62.357326 -336.734847) (xy 62.306266 -336.715791) (xy 62.258439 -336.689662)
			(xy 62.23635 -336.673698) (xy 62.217338 -336.660102) (xy 62.175455 -336.63937) (xy 62.130487 -336.626644)
			(xy 62.08395 -336.622354) (xy 62.037413 -336.626644) (xy 61.992445 -336.63937) (xy 61.950562 -336.660102)
			(xy 61.93155 -336.673698) (xy 61.90947 -336.689676) (xy 61.86164 -336.715806) (xy 61.810579 -336.734862)
			(xy 61.757325 -336.746457) (xy 61.702962 -336.750354) (xy 61.648599 -336.746475) (xy 61.595341 -336.734897)
			(xy 61.544273 -336.715858) (xy 61.496435 -336.689743) (xy 61.452801 -336.657086) (xy 61.414259 -336.618551)
			(xy 61.381594 -336.574923) (xy 61.355471 -336.527089) (xy 61.336422 -336.476025) (xy 61.324835 -336.422769)
			(xy 61.320946 -336.368406) (xy 60.942929 -336.368406) (xy 60.93904 -336.422764) (xy 60.927454 -336.476016)
			(xy 60.908407 -336.527076) (xy 60.882286 -336.574906) (xy 60.849625 -336.618531) (xy 60.811086 -336.657063)
			(xy 60.767456 -336.689719) (xy 60.719622 -336.715832) (xy 60.668559 -336.734871) (xy 60.615306 -336.746448)
			(xy 60.560947 -336.750329) (xy 60.506589 -336.746433) (xy 60.453339 -336.734841) (xy 60.402281 -336.715787)
			(xy 60.354454 -336.689661) (xy 60.332366 -336.673698) (xy 60.313354 -336.660102) (xy 60.271471 -336.63937)
			(xy 60.226503 -336.626644) (xy 60.179966 -336.622354) (xy 60.133429 -336.626644) (xy 60.088461 -336.63937)
			(xy 60.046578 -336.660102) (xy 60.027566 -336.673698) (xy 60.005488 -336.689669) (xy 59.957664 -336.715785)
			(xy 59.90661 -336.73483) (xy 59.853366 -336.746415) (xy 59.799015 -336.750304) (xy 59.744663 -336.746419)
			(xy 59.691418 -336.734838) (xy 59.640362 -336.715797) (xy 59.592537 -336.689684) (xy 59.548914 -336.657031)
			(xy 59.510383 -336.618502) (xy 59.477727 -336.574881) (xy 59.451611 -336.527056) (xy 59.432568 -336.476002)
			(xy 59.420984 -336.422757) (xy 59.417096 -336.368406) (xy 58.701794 -336.368406) (xy 58.697906 -336.422756)
			(xy 58.686322 -336.476) (xy 58.667279 -336.527054) (xy 58.641164 -336.574877) (xy 58.608508 -336.618497)
			(xy 58.569977 -336.657025) (xy 58.526355 -336.689678) (xy 58.47853 -336.71579) (xy 58.427475 -336.73483)
			(xy 58.37423 -336.74641) (xy 58.31988 -336.750294) (xy 58.265529 -336.746404) (xy 58.212286 -336.734818)
			(xy 58.161233 -336.715773) (xy 58.113411 -336.689656) (xy 58.091324 -336.673698) (xy 58.072312 -336.660102)
			(xy 58.030429 -336.63937) (xy 57.985461 -336.626644) (xy 57.938924 -336.622354) (xy 57.892387 -336.626644)
			(xy 57.847419 -336.63937) (xy 57.805536 -336.660102) (xy 57.786524 -336.673698) (xy 57.764445 -336.689673)
			(xy 57.716617 -336.715799) (xy 57.665558 -336.734852) (xy 57.612307 -336.746444) (xy 57.557948 -336.750339)
			(xy 57.503588 -336.746458) (xy 57.450334 -336.734879) (xy 57.39927 -336.715839) (xy 57.351436 -336.689725)
			(xy 57.307805 -336.657069) (xy 57.269266 -336.618536) (xy 57.236604 -336.57491) (xy 57.210483 -336.527079)
			(xy 57.191436 -336.476018) (xy 57.17985 -336.422765) (xy 57.175961 -336.368406) (xy 56.815101 -336.368406)
			(xy 56.811213 -336.422758) (xy 56.799629 -336.476003) (xy 56.780585 -336.527058) (xy 56.754468 -336.574883)
			(xy 56.721812 -336.618504) (xy 56.683279 -336.657033) (xy 56.639655 -336.689686) (xy 56.591828 -336.715799)
			(xy 56.540772 -336.734838) (xy 56.487525 -336.746418) (xy 56.433173 -336.750301) (xy 56.378821 -336.74641)
			(xy 56.325576 -336.734823) (xy 56.274522 -336.715776) (xy 56.226699 -336.689657) (xy 56.204612 -336.673698)
			(xy 56.1856 -336.660102) (xy 56.143717 -336.63937) (xy 56.098749 -336.626644) (xy 56.052212 -336.622354)
			(xy 56.005675 -336.626644) (xy 55.960707 -336.63937) (xy 55.918824 -336.660102) (xy 55.899812 -336.673698)
			(xy 55.877733 -336.689672) (xy 55.829906 -336.715796) (xy 55.778848 -336.734847) (xy 55.725598 -336.746438)
			(xy 55.671241 -336.750332) (xy 55.616883 -336.74645) (xy 55.563631 -336.734871) (xy 55.512568 -336.71583)
			(xy 55.464736 -336.689717) (xy 55.421107 -336.657061) (xy 55.38257 -336.618529) (xy 55.349909 -336.574904)
			(xy 55.323789 -336.527074) (xy 55.304743 -336.476014) (xy 55.293157 -336.422764) (xy 55.289268 -336.368406)
			(xy 36.310703 -336.368406) (xy 36.263477 -336.430943) (xy 36.204933 -336.495163) (xy 36.140713 -336.553707)
			(xy 36.071366 -336.606076) (xy 35.997482 -336.651823) (xy 35.919693 -336.690557) (xy 35.838661 -336.721949)
			(xy 35.755079 -336.74573) (xy 35.669659 -336.761698) (xy 35.58313 -336.769716) (xy 35.49623 -336.769716)
			(xy 35.409701 -336.761698) (xy 35.324281 -336.74573) (xy 35.240699 -336.721949) (xy 35.159667 -336.690557)
			(xy 35.081878 -336.651823) (xy 35.007994 -336.606076) (xy 34.938647 -336.553707) (xy 34.874427 -336.495163)
			(xy 34.815883 -336.430943) (xy 34.763514 -336.361596) (xy 34.717767 -336.287712) (xy 34.679033 -336.209923)
			(xy 34.647641 -336.128891) (xy 34.62386 -336.045309) (xy 34.607892 -335.959889) (xy 34.599874 -335.87336)
			(xy 31.398557 -335.87336) (xy 31.39658 -335.916318) (xy 31.384682 -336.002009) (xy 31.364962 -336.086245)
			(xy 31.337589 -336.168314) (xy 31.302793 -336.247521) (xy 31.260868 -336.323198) (xy 31.212169 -336.394703)
			(xy 31.157109 -336.461433) (xy 31.096151 -336.522823) (xy 31.029813 -336.578355) (xy 30.958653 -336.627558)
			(xy 30.883276 -336.670017) (xy 30.804316 -336.705373) (xy 30.722444 -336.733326) (xy 30.638349 -336.753641)
			(xy 30.552744 -336.766145) (xy 30.466352 -336.770734) (xy 30.379905 -336.767368) (xy 30.294131 -336.756075)
			(xy 30.209758 -336.736951) (xy 30.127498 -336.710158) (xy 30.08757 -336.69351) (xy 30.066403 -336.684941)
			(xy 30.021906 -336.674702) (xy 29.976295 -336.672576) (xy 29.931038 -336.678634) (xy 29.887591 -336.692679)
			(xy 29.847352 -336.714259) (xy 29.811616 -336.742681) (xy 29.781532 -336.77703) (xy 29.758068 -336.816201)
			(xy 29.74198 -336.858933) (xy 29.733784 -336.903852) (xy 29.73324 -336.926682) (xy 29.73324 -337.273138)
			(xy 29.733718 -337.29598) (xy 29.741878 -337.34093) (xy 29.757945 -337.383696) (xy 29.781402 -337.422898)
			(xy 29.811492 -337.457274) (xy 29.847245 -337.485713) (xy 29.887507 -337.5073) (xy 29.930982 -337.521337)
			(xy 29.976265 -337.527373) (xy 30.021899 -337.525213) (xy 30.06641 -337.514926) (xy 30.08757 -337.50631)
			(xy 30.127491 -337.489645) (xy 30.20975 -337.462851) (xy 30.294124 -337.443727) (xy 30.379897 -337.432433)
			(xy 30.466345 -337.429066) (xy 30.552736 -337.433654) (xy 30.638341 -337.446158) (xy 30.722436 -337.466472)
			(xy 30.804309 -337.494424) (xy 30.883269 -337.52978) (xy 30.958647 -337.572238) (xy 31.029806 -337.62144)
			(xy 31.096145 -337.676971) (xy 31.157103 -337.738361) (xy 31.212165 -337.805091) (xy 31.260864 -337.876596)
			(xy 31.302789 -337.952272) (xy 31.337586 -338.031479) (xy 31.36496 -338.113547) (xy 31.38468 -338.197783)
			(xy 31.39658 -338.283474) (xy 31.400557 -338.369896) (xy 31.398557 -338.41336) (xy 34.599874 -338.41336)
			(xy 34.599874 -338.32646) (xy 34.607892 -338.239931) (xy 34.62386 -338.154511) (xy 34.647641 -338.070929)
			(xy 34.679033 -337.989897) (xy 34.717767 -337.912108) (xy 34.763514 -337.838224) (xy 34.815883 -337.768877)
			(xy 34.874427 -337.704657) (xy 34.938647 -337.646113) (xy 35.007994 -337.593744) (xy 35.081878 -337.547997)
			(xy 35.159667 -337.509263) (xy 35.240699 -337.477871) (xy 35.324281 -337.45409) (xy 35.409701 -337.438122)
			(xy 35.49623 -337.430104) (xy 35.58313 -337.430104) (xy 35.669659 -337.438122) (xy 35.755079 -337.45409)
			(xy 35.838661 -337.477871) (xy 35.90436 -337.503323) (xy 39.178225 -337.503323) (xy 39.182111 -337.448957)
			(xy 39.193694 -337.395698) (xy 39.21274 -337.344629) (xy 39.238861 -337.296792) (xy 39.271524 -337.253159)
			(xy 39.310065 -337.214618) (xy 39.353699 -337.181956) (xy 39.401537 -337.155837) (xy 39.452606 -337.136792)
			(xy 39.505866 -337.12521) (xy 39.560231 -337.121325) (xy 39.614597 -337.125219) (xy 39.667854 -337.13681)
			(xy 39.71892 -337.155863) (xy 39.766754 -337.18199) (xy 39.788846 -337.197954) (xy 39.807858 -337.21155)
			(xy 39.849741 -337.232282) (xy 39.894709 -337.245008) (xy 39.941246 -337.249298) (xy 39.987783 -337.245008)
			(xy 40.032751 -337.232282) (xy 40.074634 -337.21155) (xy 40.093646 -337.197954) (xy 40.115769 -337.182049)
			(xy 40.163589 -337.155941) (xy 40.214638 -337.136904) (xy 40.267876 -337.125325) (xy 40.322221 -337.121441)
			(xy 40.376565 -337.125331) (xy 40.429802 -337.136915) (xy 40.480849 -337.155958) (xy 40.528666 -337.182072)
			(xy 40.572281 -337.214725) (xy 40.610804 -337.253252) (xy 40.643452 -337.29687) (xy 40.66956 -337.344691)
			(xy 40.688597 -337.39574) (xy 40.700175 -337.448978) (xy 40.704059 -337.503323) (xy 40.700168 -337.557667)
			(xy 40.688584 -337.610904) (xy 40.669541 -337.661951) (xy 40.643427 -337.709768) (xy 40.610774 -337.753382)
			(xy 40.572246 -337.791905) (xy 40.528628 -337.824553) (xy 40.480808 -337.850661) (xy 40.429759 -337.869697)
			(xy 40.37652 -337.881275) (xy 40.322175 -337.885159) (xy 40.267831 -337.881268) (xy 40.214594 -337.869684)
			(xy 40.163547 -337.85064) (xy 40.11573 -337.824526) (xy 40.093646 -337.80857) (xy 40.074634 -337.794974)
			(xy 40.032751 -337.774242) (xy 39.987783 -337.761516) (xy 39.941246 -337.757226) (xy 39.894709 -337.761516)
			(xy 39.849741 -337.774242) (xy 39.807858 -337.794974) (xy 39.788846 -337.80857) (xy 39.766792 -337.824585)
			(xy 39.718961 -337.850718) (xy 39.667898 -337.869777) (xy 39.614642 -337.881375) (xy 39.560277 -337.885275)
			(xy 39.505911 -337.881397) (xy 39.45265 -337.869821) (xy 39.401579 -337.850782) (xy 39.353737 -337.824668)
			(xy 39.310099 -337.792011) (xy 39.271554 -337.753476) (xy 39.238886 -337.709847) (xy 39.212759 -337.662012)
			(xy 39.193707 -337.610946) (xy 39.182117 -337.557688) (xy 39.178225 -337.503323) (xy 35.90436 -337.503323)
			(xy 35.919693 -337.509263) (xy 35.997482 -337.547997) (xy 36.071366 -337.593744) (xy 36.140713 -337.646113)
			(xy 36.204933 -337.704657) (xy 36.263477 -337.768877) (xy 36.315846 -337.838224) (xy 36.361593 -337.912108)
			(xy 36.400327 -337.989897) (xy 36.431719 -338.070929) (xy 36.4555 -338.154511) (xy 36.471468 -338.239931)
			(xy 36.479486 -338.32646) (xy 36.479988 -338.36991) (xy 36.479531 -338.40948) (xy 55.289304 -338.40948)
			(xy 55.293194 -338.355127) (xy 55.304781 -338.301882) (xy 55.323827 -338.250827) (xy 55.349946 -338.203003)
			(xy 55.382606 -338.159384) (xy 55.421141 -338.120856) (xy 55.464767 -338.088205) (xy 55.512596 -338.062096)
			(xy 55.563654 -338.043059) (xy 55.616902 -338.031483) (xy 55.671255 -338.027604) (xy 55.725607 -338.031499)
			(xy 55.778852 -338.04309) (xy 55.829904 -338.062142) (xy 55.877726 -338.088265) (xy 55.899812 -338.104226)
			(xy 55.918824 -338.117822) (xy 55.960707 -338.138554) (xy 56.005675 -338.15128) (xy 56.052212 -338.15557)
			(xy 56.098749 -338.15128) (xy 56.143717 -338.138554) (xy 56.1856 -338.117822) (xy 56.204612 -338.104226)
			(xy 56.226668 -338.088221) (xy 56.274495 -338.062098) (xy 56.325552 -338.043047) (xy 56.378802 -338.031457)
			(xy 56.433158 -338.027563) (xy 56.487516 -338.031445) (xy 56.540768 -338.043024) (xy 56.59183 -338.062063)
			(xy 56.639662 -338.088176) (xy 56.683291 -338.120831) (xy 56.721829 -338.159362) (xy 56.75449 -338.202986)
			(xy 56.780611 -338.250814) (xy 56.799659 -338.301873) (xy 56.811246 -338.355123) (xy 56.815137 -338.40948)
			(xy 57.175996 -338.40948) (xy 57.179887 -338.355125) (xy 57.191474 -338.301878) (xy 57.210521 -338.250823)
			(xy 57.236641 -338.202997) (xy 57.269302 -338.159377) (xy 57.307839 -338.120848) (xy 57.351467 -338.088197)
			(xy 57.399298 -338.062087) (xy 57.450358 -338.043051) (xy 57.503607 -338.031475) (xy 57.557962 -338.027596)
			(xy 57.612316 -338.031493) (xy 57.665562 -338.043086) (xy 57.716615 -338.062139) (xy 57.764438 -338.088264)
			(xy 57.786524 -338.104226) (xy 57.805536 -338.117822) (xy 57.847419 -338.138554) (xy 57.892387 -338.15128)
			(xy 57.938924 -338.15557) (xy 57.985461 -338.15128) (xy 58.030429 -338.138554) (xy 58.072312 -338.117822)
			(xy 58.091324 -338.104226) (xy 58.11338 -338.088222) (xy 58.161206 -338.062101) (xy 58.212262 -338.043052)
			(xy 58.26551 -338.031463) (xy 58.319865 -338.027571) (xy 58.374221 -338.031453) (xy 58.427471 -338.043032)
			(xy 58.478531 -338.062072) (xy 58.526362 -338.088185) (xy 58.569989 -338.120839) (xy 58.608525 -338.159369)
			(xy 58.641186 -338.202992) (xy 58.667305 -338.250819) (xy 58.686352 -338.301876) (xy 58.697939 -338.355124)
			(xy 58.701829 -338.40948) (xy 59.417131 -338.40948) (xy 59.421021 -338.355133) (xy 59.432606 -338.301894)
			(xy 59.451649 -338.250845) (xy 59.477764 -338.203026) (xy 59.510419 -338.159411) (xy 59.548948 -338.120886)
			(xy 59.592568 -338.088237) (xy 59.64039 -338.062129) (xy 59.691441 -338.043092) (xy 59.744682 -338.031514)
			(xy 59.799029 -338.027631) (xy 59.853375 -338.031522) (xy 59.906614 -338.043108) (xy 59.957663 -338.062153)
			(xy 60.005481 -338.088269) (xy 60.027566 -338.104226) (xy 60.046578 -338.117822) (xy 60.088461 -338.138554)
			(xy 60.133429 -338.15128) (xy 60.179966 -338.15557) (xy 60.226503 -338.15128) (xy 60.271471 -338.138554)
			(xy 60.313354 -338.117822) (xy 60.332366 -338.104226) (xy 60.354423 -338.088217) (xy 60.402253 -338.062087)
			(xy 60.453315 -338.04303) (xy 60.506569 -338.031434) (xy 60.560932 -338.027536) (xy 60.615296 -338.031415)
			(xy 60.668555 -338.042991) (xy 60.719624 -338.06203) (xy 60.767463 -338.088144) (xy 60.811098 -338.1208)
			(xy 60.849642 -338.159335) (xy 60.882308 -338.202963) (xy 60.908433 -338.250796) (xy 60.927484 -338.30186)
			(xy 60.939073 -338.355116) (xy 60.942964 -338.40948) (xy 61.320981 -338.40948) (xy 61.324872 -338.355122)
			(xy 61.33646 -338.301871) (xy 61.355509 -338.250812) (xy 61.381631 -338.202984) (xy 61.414295 -338.159361)
			(xy 61.452835 -338.120831) (xy 61.496466 -338.088179) (xy 61.544301 -338.062068) (xy 61.595365 -338.043032)
			(xy 61.648618 -338.031458) (xy 61.702977 -338.027581) (xy 61.757334 -338.03148) (xy 61.810583 -338.043076)
			(xy 61.861639 -338.062132) (xy 61.909463 -338.088262) (xy 61.93155 -338.104226) (xy 61.950562 -338.117822)
			(xy 61.992445 -338.138554) (xy 62.037413 -338.15128) (xy 62.08395 -338.15557) (xy 62.130487 -338.15128)
			(xy 62.175455 -338.138554) (xy 62.217338 -338.117822) (xy 62.23635 -338.104226) (xy 62.258407 -338.088216)
			(xy 62.306238 -338.062083) (xy 62.357302 -338.043023) (xy 62.410558 -338.031426) (xy 62.464923 -338.027526)
			(xy 62.519289 -338.031404) (xy 62.57255 -338.04298) (xy 62.623622 -338.062019) (xy 62.671463 -338.088133)
			(xy 62.715101 -338.12079) (xy 62.753646 -338.159326) (xy 62.786315 -338.202955) (xy 62.812441 -338.25079)
			(xy 62.831492 -338.301856) (xy 62.843082 -338.355114) (xy 62.846974 -338.40948) (xy 62.843088 -338.463845)
			(xy 62.831504 -338.517105) (xy 62.812458 -338.568173) (xy 62.786337 -338.616011) (xy 62.753673 -338.659644)
			(xy 62.715132 -338.698183) (xy 62.671498 -338.730845) (xy 62.623659 -338.756964) (xy 62.57259 -338.776008)
			(xy 62.51933 -338.78759) (xy 62.464964 -338.791474) (xy 62.410599 -338.78758) (xy 62.357341 -338.775988)
			(xy 62.306276 -338.756934) (xy 62.258442 -338.730806) (xy 62.23635 -338.714842) (xy 62.217338 -338.701246)
			(xy 62.175455 -338.680514) (xy 62.130487 -338.667788) (xy 62.08395 -338.663498) (xy 62.037413 -338.667788)
			(xy 61.992445 -338.680514) (xy 61.950562 -338.701246) (xy 61.93155 -338.714842) (xy 61.909429 -338.73076)
			(xy 61.861602 -338.756885) (xy 61.810544 -338.775936) (xy 61.757294 -338.787526) (xy 61.702936 -338.791419)
			(xy 61.648578 -338.787536) (xy 61.595326 -338.775956) (xy 61.544264 -338.756915) (xy 61.496432 -338.730799)
			(xy 61.452804 -338.698142) (xy 61.414268 -338.659608) (xy 61.381609 -338.615981) (xy 61.355492 -338.56815)
			(xy 61.336448 -338.517089) (xy 61.324866 -338.463838) (xy 61.320981 -338.40948) (xy 60.942964 -338.40948)
			(xy 60.939079 -338.463843) (xy 60.927495 -338.5171) (xy 60.90845 -338.568167) (xy 60.88233 -338.616003)
			(xy 60.849668 -338.659634) (xy 60.811129 -338.698173) (xy 60.767497 -338.730834) (xy 60.719661 -338.756953)
			(xy 60.668594 -338.775997) (xy 60.615337 -338.787579) (xy 60.560973 -338.791464) (xy 60.50661 -338.787572)
			(xy 60.453354 -338.775982) (xy 60.40229 -338.75693) (xy 60.354457 -338.730805) (xy 60.332366 -338.714842)
			(xy 60.313354 -338.701246) (xy 60.271471 -338.680514) (xy 60.226503 -338.667788) (xy 60.179966 -338.663498)
			(xy 60.133429 -338.667788) (xy 60.088461 -338.680514) (xy 60.046578 -338.701246) (xy 60.027566 -338.714842)
			(xy 60.005447 -338.730753) (xy 59.957626 -338.756864) (xy 59.906575 -338.775903) (xy 59.853335 -338.787484)
			(xy 59.798988 -338.791369) (xy 59.744642 -338.78748) (xy 59.691402 -338.775897) (xy 59.640353 -338.756854)
			(xy 59.592534 -338.730741) (xy 59.548917 -338.698087) (xy 59.510392 -338.659559) (xy 59.477742 -338.615939)
			(xy 59.451632 -338.568118) (xy 59.432594 -338.517067) (xy 59.421015 -338.463826) (xy 59.417131 -338.40948)
			(xy 58.701829 -338.40948) (xy 58.697945 -338.463835) (xy 58.686364 -338.517085) (xy 58.667322 -338.568144)
			(xy 58.641208 -338.615974) (xy 58.608552 -338.6596) (xy 58.57002 -338.698135) (xy 58.526396 -338.730793)
			(xy 58.478568 -338.756911) (xy 58.42751 -338.775956) (xy 58.374261 -338.787541) (xy 58.319906 -338.791429)
			(xy 58.26555 -338.787543) (xy 58.212301 -338.775959) (xy 58.161243 -338.756916) (xy 58.113414 -338.7308)
			(xy 58.091324 -338.714842) (xy 58.072312 -338.701246) (xy 58.030429 -338.680514) (xy 57.985461 -338.667788)
			(xy 57.938924 -338.663498) (xy 57.892387 -338.667788) (xy 57.847419 -338.680514) (xy 57.805536 -338.701246)
			(xy 57.786524 -338.714842) (xy 57.764403 -338.730758) (xy 57.716578 -338.756878) (xy 57.665522 -338.775926)
			(xy 57.612275 -338.787513) (xy 57.557921 -338.791404) (xy 57.503567 -338.787519) (xy 57.450318 -338.775938)
			(xy 57.39926 -338.756896) (xy 57.351432 -338.730781) (xy 57.307808 -338.698125) (xy 57.269275 -338.659593)
			(xy 57.236619 -338.615968) (xy 57.210504 -338.56814) (xy 57.191462 -338.517082) (xy 57.179881 -338.463834)
			(xy 57.175996 -338.40948) (xy 56.815137 -338.40948) (xy 56.811252 -338.463837) (xy 56.79967 -338.517088)
			(xy 56.780628 -338.568149) (xy 56.754512 -338.61598) (xy 56.721855 -338.659607) (xy 56.683322 -338.698143)
			(xy 56.639696 -338.730802) (xy 56.591867 -338.75692) (xy 56.540807 -338.775965) (xy 56.487556 -338.787549)
			(xy 56.433199 -338.791437) (xy 56.378842 -338.787549) (xy 56.325592 -338.775964) (xy 56.274532 -338.756919)
			(xy 56.226702 -338.730801) (xy 56.204612 -338.714842) (xy 56.1856 -338.701246) (xy 56.143717 -338.680514)
			(xy 56.098749 -338.667788) (xy 56.052212 -338.663498) (xy 56.005675 -338.667788) (xy 55.960707 -338.680514)
			(xy 55.918824 -338.701246) (xy 55.899812 -338.714842) (xy 55.877692 -338.730757) (xy 55.829867 -338.756875)
			(xy 55.778813 -338.775921) (xy 55.725567 -338.787507) (xy 55.671214 -338.791396) (xy 55.616862 -338.787511)
			(xy 55.563615 -338.775929) (xy 55.512559 -338.756887) (xy 55.464733 -338.730773) (xy 55.42111 -338.698117)
			(xy 55.382579 -338.659586) (xy 55.349924 -338.615962) (xy 55.32381 -338.568136) (xy 55.304769 -338.517079)
			(xy 55.293188 -338.463832) (xy 55.289304 -338.40948) (xy 36.479531 -338.40948) (xy 36.479486 -338.41336)
			(xy 36.471468 -338.499889) (xy 36.4555 -338.585309) (xy 36.431719 -338.668891) (xy 36.400327 -338.749923)
			(xy 36.361593 -338.827712) (xy 36.315846 -338.901596) (xy 36.263477 -338.970943) (xy 36.204933 -339.035163)
			(xy 36.140713 -339.093707) (xy 36.071366 -339.146076) (xy 35.997482 -339.191823) (xy 35.919693 -339.230557)
			(xy 35.838661 -339.261949) (xy 35.755079 -339.28573) (xy 35.669659 -339.301698) (xy 35.58313 -339.309716)
			(xy 35.49623 -339.309716) (xy 35.409701 -339.301698) (xy 35.324281 -339.28573) (xy 35.240699 -339.261949)
			(xy 35.159667 -339.230557) (xy 35.081878 -339.191823) (xy 35.007994 -339.146076) (xy 34.938647 -339.093707)
			(xy 34.874427 -339.035163) (xy 34.815883 -338.970943) (xy 34.763514 -338.901596) (xy 34.717767 -338.827712)
			(xy 34.679033 -338.749923) (xy 34.647641 -338.668891) (xy 34.62386 -338.585309) (xy 34.607892 -338.499889)
			(xy 34.599874 -338.41336) (xy 31.398557 -338.41336) (xy 31.39658 -338.456318) (xy 31.384682 -338.542009)
			(xy 31.364962 -338.626245) (xy 31.337589 -338.708314) (xy 31.302793 -338.787521) (xy 31.260868 -338.863198)
			(xy 31.212169 -338.934703) (xy 31.157109 -339.001433) (xy 31.096151 -339.062823) (xy 31.029813 -339.118355)
			(xy 30.958653 -339.167558) (xy 30.883276 -339.210017) (xy 30.804316 -339.245373) (xy 30.722444 -339.273326)
			(xy 30.638349 -339.293641) (xy 30.552744 -339.306145) (xy 30.466352 -339.310734) (xy 30.379905 -339.307368)
			(xy 30.294131 -339.296075) (xy 30.209758 -339.276951) (xy 30.127498 -339.250158) (xy 30.08757 -339.23351)
			(xy 30.066403 -339.224941) (xy 30.021906 -339.214702) (xy 29.976295 -339.212576) (xy 29.931038 -339.218634)
			(xy 29.887591 -339.232679) (xy 29.847352 -339.254259) (xy 29.811616 -339.282681) (xy 29.781532 -339.31703)
			(xy 29.758068 -339.356201) (xy 29.74198 -339.398933) (xy 29.733784 -339.443852) (xy 29.73324 -339.466682)
			(xy 29.73324 -339.813138) (xy 29.733718 -339.83598) (xy 29.740788 -339.874924) (xy 39.178224 -339.874924)
			(xy 39.182109 -339.820558) (xy 39.193693 -339.767298) (xy 39.212738 -339.71623) (xy 39.238859 -339.668392)
			(xy 39.271522 -339.624758) (xy 39.310063 -339.586218) (xy 39.353697 -339.553556) (xy 39.401535 -339.527436)
			(xy 39.452604 -339.508391) (xy 39.505864 -339.496808) (xy 39.56023 -339.492924) (xy 39.614596 -339.496817)
			(xy 39.667854 -339.508408) (xy 39.71892 -339.527461) (xy 39.766754 -339.553588) (xy 39.788846 -339.569552)
			(xy 39.807858 -339.583148) (xy 39.849741 -339.60388) (xy 39.894709 -339.616606) (xy 39.941246 -339.620896)
			(xy 39.987783 -339.616606) (xy 40.032751 -339.60388) (xy 40.074634 -339.583148) (xy 40.093646 -339.569552)
			(xy 40.115771 -339.55365) (xy 40.163591 -339.527542) (xy 40.214639 -339.508505) (xy 40.267878 -339.496927)
			(xy 40.322222 -339.493043) (xy 40.376566 -339.496933) (xy 40.429803 -339.508517) (xy 40.48085 -339.52756)
			(xy 40.528667 -339.553674) (xy 40.57228 -339.586327) (xy 40.610803 -339.624854) (xy 40.643451 -339.668472)
			(xy 40.669559 -339.716292) (xy 40.688596 -339.767341) (xy 40.700174 -339.82058) (xy 40.704057 -339.874924)
			(xy 40.700167 -339.929268) (xy 40.688582 -339.982505) (xy 40.669539 -340.033551) (xy 40.643425 -340.081368)
			(xy 40.610772 -340.124982) (xy 40.572244 -340.163505) (xy 40.528626 -340.196152) (xy 40.480806 -340.22226)
			(xy 40.429757 -340.241296) (xy 40.376518 -340.252874) (xy 40.322174 -340.256757) (xy 40.26783 -340.252866)
			(xy 40.214593 -340.241282) (xy 40.163547 -340.222238) (xy 40.11573 -340.196124) (xy 40.093646 -340.180168)
			(xy 40.074634 -340.166572) (xy 40.032751 -340.14584) (xy 39.987783 -340.133114) (xy 39.941246 -340.128824)
			(xy 39.894709 -340.133114) (xy 39.849741 -340.14584) (xy 39.807858 -340.166572) (xy 39.788846 -340.180168)
			(xy 39.766794 -340.196186) (xy 39.718963 -340.222319) (xy 39.6679 -340.241379) (xy 39.614643 -340.252976)
			(xy 39.560278 -340.256876) (xy 39.505912 -340.252999) (xy 39.45265 -340.241423) (xy 39.401579 -340.222384)
			(xy 39.353737 -340.19627) (xy 39.310099 -340.163613) (xy 39.271554 -340.125078) (xy 39.238885 -340.081449)
			(xy 39.212758 -340.033614) (xy 39.193706 -339.982548) (xy 39.182116 -339.92929) (xy 39.178224 -339.874924)
			(xy 29.740788 -339.874924) (xy 29.741878 -339.88093) (xy 29.757945 -339.923696) (xy 29.781402 -339.962898)
			(xy 29.811492 -339.997274) (xy 29.847245 -340.025713) (xy 29.887507 -340.0473) (xy 29.930982 -340.061337)
			(xy 29.976265 -340.067373) (xy 30.021899 -340.065213) (xy 30.06641 -340.054926) (xy 30.08757 -340.04631)
			(xy 30.127491 -340.029645) (xy 30.20975 -340.002851) (xy 30.294124 -339.983727) (xy 30.379897 -339.972433)
			(xy 30.466345 -339.969066) (xy 30.552736 -339.973654) (xy 30.638341 -339.986158) (xy 30.722436 -340.006472)
			(xy 30.804309 -340.034424) (xy 30.883269 -340.06978) (xy 30.958647 -340.112238) (xy 31.029806 -340.16144)
			(xy 31.096145 -340.216971) (xy 31.157103 -340.278361) (xy 31.212165 -340.345091) (xy 31.260864 -340.416596)
			(xy 31.302789 -340.492272) (xy 31.337586 -340.571479) (xy 31.36496 -340.653547) (xy 31.38468 -340.737783)
			(xy 31.39658 -340.823474) (xy 31.400557 -340.909896) (xy 31.398557 -340.95336) (xy 34.599874 -340.95336)
			(xy 34.599874 -340.86646) (xy 34.607892 -340.779931) (xy 34.62386 -340.694511) (xy 34.647641 -340.610929)
			(xy 34.679033 -340.529897) (xy 34.717767 -340.452108) (xy 34.763514 -340.378224) (xy 34.815883 -340.308877)
			(xy 34.874427 -340.244657) (xy 34.938647 -340.186113) (xy 35.007994 -340.133744) (xy 35.081878 -340.087997)
			(xy 35.159667 -340.049263) (xy 35.240699 -340.017871) (xy 35.324281 -339.99409) (xy 35.409701 -339.978122)
			(xy 35.49623 -339.970104) (xy 35.58313 -339.970104) (xy 35.669659 -339.978122) (xy 35.755079 -339.99409)
			(xy 35.838661 -340.017871) (xy 35.919693 -340.049263) (xy 35.997482 -340.087997) (xy 36.071366 -340.133744)
			(xy 36.140713 -340.186113) (xy 36.204933 -340.244657) (xy 36.263477 -340.308877) (xy 36.271442 -340.319424)
			(xy 55.289244 -340.319424) (xy 55.293129 -340.265063) (xy 55.304711 -340.211808) (xy 55.323755 -340.160743)
			(xy 55.349872 -340.112909) (xy 55.382532 -340.069278) (xy 55.421068 -340.03074) (xy 55.464698 -339.998079)
			(xy 55.512531 -339.97196) (xy 55.563595 -339.952915) (xy 55.61685 -339.941331) (xy 55.671211 -339.937444)
			(xy 55.725572 -339.941334) (xy 55.778826 -339.952921) (xy 55.829889 -339.971969) (xy 55.877721 -339.998091)
			(xy 55.899812 -340.014052) (xy 55.918824 -340.027648) (xy 55.960707 -340.04838) (xy 56.005675 -340.061106)
			(xy 56.052212 -340.065396) (xy 56.098749 -340.061106) (xy 56.143717 -340.04838) (xy 56.1856 -340.027648)
			(xy 56.204612 -340.014052) (xy 56.226737 -339.998147) (xy 56.27456 -339.972033) (xy 56.325612 -339.952992)
			(xy 56.378854 -339.94141) (xy 56.433203 -339.937523) (xy 56.487551 -339.94141) (xy 56.540794 -339.952993)
			(xy 56.591845 -339.972036) (xy 56.639667 -339.99815) (xy 56.683286 -340.030805) (xy 56.721813 -340.069334)
			(xy 56.754464 -340.112955) (xy 56.780575 -340.160779) (xy 56.799614 -340.211832) (xy 56.811193 -340.265075)
			(xy 56.815077 -340.319424) (xy 57.175937 -340.319424) (xy 57.179822 -340.265061) (xy 57.191405 -340.211804)
			(xy 57.210449 -340.160738) (xy 57.236568 -340.112903) (xy 57.269228 -340.069271) (xy 57.307767 -340.030733)
			(xy 57.351397 -339.998071) (xy 57.399233 -339.971952) (xy 57.450298 -339.952906) (xy 57.503555 -339.941323)
			(xy 57.557918 -339.937437) (xy 57.61228 -339.941328) (xy 57.665536 -339.952916) (xy 57.7166 -339.971966)
			(xy 57.764432 -339.99809) (xy 57.786524 -340.014052) (xy 57.805536 -340.027648) (xy 57.847419 -340.04838)
			(xy 57.892387 -340.061106) (xy 57.938924 -340.065396) (xy 57.985461 -340.061106) (xy 58.030429 -340.04838)
			(xy 58.072312 -340.027648) (xy 58.091324 -340.014052) (xy 58.113449 -339.998148) (xy 58.161271 -339.972036)
			(xy 58.212321 -339.952996) (xy 58.265562 -339.941416) (xy 58.31991 -339.93753) (xy 58.374257 -339.941418)
			(xy 58.427497 -339.953002) (xy 58.478547 -339.972044) (xy 58.526367 -339.998158) (xy 58.569984 -340.030812)
			(xy 58.60851 -340.069341) (xy 58.64116 -340.112961) (xy 58.66727 -340.160784) (xy 58.686308 -340.211835)
			(xy 58.697886 -340.265077) (xy 58.70177 -340.319424) (xy 59.417072 -340.319424) (xy 59.420956 -340.265069)
			(xy 59.432536 -340.21182) (xy 59.451577 -340.160761) (xy 59.47769 -340.112932) (xy 59.510345 -340.069305)
			(xy 59.548876 -340.030771) (xy 59.592499 -339.998112) (xy 59.640325 -339.971993) (xy 59.691382 -339.952947)
			(xy 59.74463 -339.941362) (xy 59.798985 -339.937472) (xy 59.85334 -339.941357) (xy 59.906588 -339.952939)
			(xy 59.957647 -339.971981) (xy 60.005476 -339.998095) (xy 60.027566 -340.014052) (xy 60.046578 -340.027648)
			(xy 60.088461 -340.04838) (xy 60.133429 -340.061106) (xy 60.179966 -340.065396) (xy 60.226503 -340.061106)
			(xy 60.271471 -340.04838) (xy 60.313354 -340.027648) (xy 60.332366 -340.014052) (xy 60.354492 -339.998143)
			(xy 60.402318 -339.972022) (xy 60.453374 -339.952974) (xy 60.506622 -339.941386) (xy 60.560977 -339.937495)
			(xy 60.615332 -339.94138) (xy 60.668581 -339.952961) (xy 60.71964 -339.972003) (xy 60.767468 -339.998118)
			(xy 60.811093 -340.030774) (xy 60.849626 -340.069307) (xy 60.882282 -340.112932) (xy 60.908398 -340.160761)
			(xy 60.927439 -340.21182) (xy 60.93902 -340.265069) (xy 60.942905 -340.319424) (xy 61.320921 -340.319424)
			(xy 61.324807 -340.265057) (xy 61.33639 -340.211797) (xy 61.355437 -340.160728) (xy 61.381557 -340.11289)
			(xy 61.414221 -340.069256) (xy 61.452762 -340.030715) (xy 61.496397 -339.998053) (xy 61.544236 -339.971933)
			(xy 61.595306 -339.952888) (xy 61.648566 -339.941306) (xy 61.702932 -339.937421) (xy 61.757298 -339.941315)
			(xy 61.810557 -339.952906) (xy 61.861623 -339.97196) (xy 61.909458 -339.998088) (xy 61.93155 -340.014052)
			(xy 61.950562 -340.027648) (xy 61.992445 -340.04838) (xy 62.037413 -340.061106) (xy 62.08395 -340.065396)
			(xy 62.130487 -340.061106) (xy 62.175455 -340.04838) (xy 62.217338 -340.027648) (xy 62.23635 -340.014052)
			(xy 62.258477 -339.998142) (xy 62.306303 -339.972018) (xy 62.357361 -339.952968) (xy 62.410611 -339.941378)
			(xy 62.464968 -339.937486) (xy 62.519325 -339.941369) (xy 62.572576 -339.952949) (xy 62.623637 -339.971991)
			(xy 62.671469 -339.998107) (xy 62.715096 -340.030764) (xy 62.753631 -340.069298) (xy 62.786289 -340.112924)
			(xy 62.812405 -340.160755) (xy 62.831448 -340.211815) (xy 62.84303 -340.265067) (xy 62.846914 -340.319424)
			(xy 62.843023 -340.373781) (xy 62.831435 -340.427031) (xy 62.812385 -340.478089) (xy 62.786263 -340.525916)
			(xy 62.753599 -340.569538) (xy 62.715059 -340.608068) (xy 62.671428 -340.640719) (xy 62.623594 -340.666829)
			(xy 62.57253 -340.685864) (xy 62.519278 -340.697438) (xy 62.46492 -340.701314) (xy 62.410563 -340.697415)
			(xy 62.357315 -340.685819) (xy 62.30626 -340.666762) (xy 62.258436 -340.640632) (xy 62.23635 -340.624668)
			(xy 62.217338 -340.611072) (xy 62.175455 -340.59034) (xy 62.130487 -340.577614) (xy 62.08395 -340.573324)
			(xy 62.037413 -340.577614) (xy 61.992445 -340.59034) (xy 61.950562 -340.611072) (xy 61.93155 -340.624668)
			(xy 61.909498 -340.640686) (xy 61.861667 -340.66682) (xy 61.810603 -340.68588) (xy 61.757346 -340.697478)
			(xy 61.702981 -340.701379) (xy 61.648613 -340.697501) (xy 61.595352 -340.685925) (xy 61.54428 -340.666887)
			(xy 61.496437 -340.640773) (xy 61.452799 -340.608116) (xy 61.414252 -340.56958) (xy 61.381583 -340.525951)
			(xy 61.355457 -340.478115) (xy 61.336404 -340.427049) (xy 61.324814 -340.37379) (xy 61.320921 -340.319424)
			(xy 60.942905 -340.319424) (xy 60.939014 -340.373779) (xy 60.927426 -340.427026) (xy 60.908378 -340.478083)
			(xy 60.882257 -340.525908) (xy 60.849595 -340.569529) (xy 60.811057 -340.608057) (xy 60.767428 -340.640708)
			(xy 60.719596 -340.666817) (xy 60.668535 -340.685853) (xy 60.615284 -340.697427) (xy 60.560929 -340.701305)
			(xy 60.506574 -340.697407) (xy 60.453328 -340.685813) (xy 60.402274 -340.666758) (xy 60.354452 -340.640631)
			(xy 60.332366 -340.624668) (xy 60.313354 -340.611072) (xy 60.271471 -340.59034) (xy 60.226503 -340.577614)
			(xy 60.179966 -340.573324) (xy 60.133429 -340.577614) (xy 60.088461 -340.59034) (xy 60.046578 -340.611072)
			(xy 60.027566 -340.624668) (xy 60.005516 -340.640679) (xy 59.957691 -340.6668) (xy 59.906635 -340.685848)
			(xy 59.853387 -340.697436) (xy 59.799033 -340.701328) (xy 59.744678 -340.697445) (xy 59.691428 -340.685866)
			(xy 59.640369 -340.666827) (xy 59.592539 -340.640714) (xy 59.548912 -340.608061) (xy 59.510376 -340.569531)
			(xy 59.477716 -340.525909) (xy 59.451597 -340.478083) (xy 59.43255 -340.427026) (xy 59.420963 -340.373779)
			(xy 59.417072 -340.319424) (xy 58.70177 -340.319424) (xy 58.69788 -340.373771) (xy 58.686294 -340.427011)
			(xy 58.66725 -340.47806) (xy 58.641134 -340.525879) (xy 58.608478 -340.569495) (xy 58.569948 -340.608019)
			(xy 58.526327 -340.640668) (xy 58.478503 -340.666776) (xy 58.427451 -340.685812) (xy 58.374209 -340.697389)
			(xy 58.319862 -340.70127) (xy 58.265515 -340.697378) (xy 58.212275 -340.68579) (xy 58.161227 -340.666744)
			(xy 58.113409 -340.640626) (xy 58.091324 -340.624668) (xy 58.072312 -340.611072) (xy 58.030429 -340.59034)
			(xy 57.985461 -340.577614) (xy 57.938924 -340.573324) (xy 57.892387 -340.577614) (xy 57.847419 -340.59034)
			(xy 57.805536 -340.611072) (xy 57.786524 -340.624668) (xy 57.764473 -340.640684) (xy 57.716643 -340.666814)
			(xy 57.665582 -340.68587) (xy 57.612328 -340.697465) (xy 57.557966 -340.701363) (xy 57.503602 -340.697484)
			(xy 57.450344 -340.685907) (xy 57.399276 -340.666868) (xy 57.351438 -340.640755) (xy 57.307803 -340.608099)
			(xy 57.26926 -340.569565) (xy 57.236594 -340.525938) (xy 57.210469 -340.478105) (xy 57.191418 -340.427042)
			(xy 57.179829 -340.373787) (xy 57.175937 -340.319424) (xy 56.815077 -340.319424) (xy 56.811187 -340.373772)
			(xy 56.799601 -340.427014) (xy 56.780555 -340.478065) (xy 56.754438 -340.525885) (xy 56.721782 -340.569502)
			(xy 56.68325 -340.608027) (xy 56.639627 -340.640676) (xy 56.591802 -340.666784) (xy 56.540748 -340.68582)
			(xy 56.487504 -340.697397) (xy 56.433155 -340.701277) (xy 56.378807 -340.697384) (xy 56.325566 -340.685795)
			(xy 56.274516 -340.666747) (xy 56.226697 -340.640627) (xy 56.204612 -340.624668) (xy 56.1856 -340.611072)
			(xy 56.143717 -340.59034) (xy 56.098749 -340.577614) (xy 56.052212 -340.573324) (xy 56.005675 -340.577614)
			(xy 55.960707 -340.59034) (xy 55.918824 -340.611072) (xy 55.899812 -340.624668) (xy 55.877761 -340.640683)
			(xy 55.829932 -340.666811) (xy 55.778872 -340.685865) (xy 55.725619 -340.697459) (xy 55.671259 -340.701356)
			(xy 55.616897 -340.697476) (xy 55.563641 -340.685899) (xy 55.512575 -340.66686) (xy 55.464738 -340.640747)
			(xy 55.421105 -340.608091) (xy 55.382563 -340.569558) (xy 55.349898 -340.525932) (xy 55.323775 -340.478101)
			(xy 55.304725 -340.427038) (xy 55.293136 -340.373785) (xy 55.289244 -340.319424) (xy 36.271442 -340.319424)
			(xy 36.315846 -340.378224) (xy 36.361593 -340.452108) (xy 36.400327 -340.529897) (xy 36.431719 -340.610929)
			(xy 36.4555 -340.694511) (xy 36.471468 -340.779931) (xy 36.479486 -340.86646) (xy 36.479988 -340.90991)
			(xy 36.479486 -340.95336) (xy 36.471468 -341.039889) (xy 36.4555 -341.125309) (xy 36.431719 -341.208891)
			(xy 36.400327 -341.289923) (xy 36.361593 -341.367712) (xy 36.315846 -341.441596) (xy 36.263477 -341.510943)
			(xy 36.204933 -341.575163) (xy 36.140713 -341.633707) (xy 36.071366 -341.686076) (xy 35.997482 -341.731823)
			(xy 35.919693 -341.770557) (xy 35.838661 -341.801949) (xy 35.755079 -341.82573) (xy 35.69042 -341.837817)
			(xy 39.178233 -341.837817) (xy 39.18212 -341.783452) (xy 39.193704 -341.730194) (xy 39.21275 -341.679127)
			(xy 39.238871 -341.631291) (xy 39.271534 -341.587659) (xy 39.310075 -341.549121) (xy 39.353708 -341.51646)
			(xy 39.401546 -341.490342) (xy 39.452614 -341.471298) (xy 39.505873 -341.459717) (xy 39.560237 -341.455833)
			(xy 39.614601 -341.459727) (xy 39.667858 -341.471319) (xy 39.718922 -341.490373) (xy 39.766755 -341.5165)
			(xy 39.788846 -341.532464) (xy 39.807858 -341.54606) (xy 39.849741 -341.566792) (xy 39.894709 -341.579518)
			(xy 39.941246 -341.583808) (xy 39.987783 -341.579518) (xy 40.032751 -341.566792) (xy 40.074634 -341.54606)
			(xy 40.093646 -341.532464) (xy 40.115759 -341.516546) (xy 40.16358 -341.490436) (xy 40.21463 -341.471398)
			(xy 40.267869 -341.459818) (xy 40.322215 -341.455933) (xy 40.37656 -341.459822) (xy 40.429799 -341.471406)
			(xy 40.480847 -341.490448) (xy 40.528666 -341.516562) (xy 40.572281 -341.549215) (xy 40.610806 -341.587743)
			(xy 40.643455 -341.631361) (xy 40.669565 -341.679182) (xy 40.688603 -341.730232) (xy 40.700182 -341.783471)
			(xy 40.704067 -341.837817) (xy 40.700177 -341.892162) (xy 40.688593 -341.945401) (xy 40.669551 -341.996449)
			(xy 40.643437 -342.044267) (xy 40.610784 -342.087883) (xy 40.572256 -342.126407) (xy 40.528637 -342.159056)
			(xy 40.480817 -342.185166) (xy 40.429767 -342.204203) (xy 40.376527 -342.215782) (xy 40.322181 -342.219667)
			(xy 40.267836 -342.215777) (xy 40.214598 -342.204193) (xy 40.163549 -342.18515) (xy 40.115731 -342.159036)
			(xy 40.093646 -342.14308) (xy 40.074634 -342.129484) (xy 40.032751 -342.108752) (xy 39.987783 -342.096026)
			(xy 39.941246 -342.091736) (xy 39.894709 -342.096026) (xy 39.849741 -342.108752) (xy 39.807858 -342.129484)
			(xy 39.788846 -342.14308) (xy 39.766783 -342.159082) (xy 39.718953 -342.185213) (xy 39.66789 -342.204271)
			(xy 39.614635 -342.215868) (xy 39.560271 -342.219766) (xy 39.505906 -342.215888) (xy 39.452646 -342.204311)
			(xy 39.401577 -342.185272) (xy 39.353736 -342.159158) (xy 39.3101 -342.126501) (xy 39.271556 -342.087966)
			(xy 39.238889 -342.044337) (xy 39.212764 -341.996503) (xy 39.193713 -341.945438) (xy 39.182124 -341.892181)
			(xy 39.178233 -341.837817) (xy 35.69042 -341.837817) (xy 35.669659 -341.841698) (xy 35.58313 -341.849716)
			(xy 35.49623 -341.849716) (xy 35.409701 -341.841698) (xy 35.324281 -341.82573) (xy 35.240699 -341.801949)
			(xy 35.159667 -341.770557) (xy 35.081878 -341.731823) (xy 35.007994 -341.686076) (xy 34.938647 -341.633707)
			(xy 34.874427 -341.575163) (xy 34.815883 -341.510943) (xy 34.763514 -341.441596) (xy 34.717767 -341.367712)
			(xy 34.679033 -341.289923) (xy 34.647641 -341.208891) (xy 34.62386 -341.125309) (xy 34.607892 -341.039889)
			(xy 34.599874 -340.95336) (xy 31.398557 -340.95336) (xy 31.39658 -340.996318) (xy 31.384682 -341.082009)
			(xy 31.364962 -341.166245) (xy 31.337589 -341.248314) (xy 31.302793 -341.327521) (xy 31.260868 -341.403198)
			(xy 31.212169 -341.474703) (xy 31.157109 -341.541433) (xy 31.096151 -341.602823) (xy 31.029813 -341.658355)
			(xy 30.958653 -341.707558) (xy 30.883276 -341.750017) (xy 30.804316 -341.785373) (xy 30.722444 -341.813326)
			(xy 30.638349 -341.833641) (xy 30.552744 -341.846145) (xy 30.466352 -341.850734) (xy 30.379905 -341.847368)
			(xy 30.294131 -341.836075) (xy 30.209758 -341.816951) (xy 30.127498 -341.790158) (xy 30.08757 -341.77351)
			(xy 30.066403 -341.764941) (xy 30.021906 -341.754702) (xy 29.976295 -341.752576) (xy 29.931038 -341.758634)
			(xy 29.887591 -341.772679) (xy 29.847352 -341.794259) (xy 29.811616 -341.822681) (xy 29.781532 -341.85703)
			(xy 29.758068 -341.896201) (xy 29.74198 -341.938933) (xy 29.733784 -341.983852) (xy 29.73324 -342.006682)
			(xy 29.73324 -342.353138) (xy 29.733718 -342.37598) (xy 29.741878 -342.42093) (xy 29.757945 -342.463696)
			(xy 29.781402 -342.502898) (xy 29.811492 -342.537274) (xy 29.847245 -342.565713) (xy 29.887507 -342.5873)
			(xy 29.930982 -342.601337) (xy 29.976265 -342.607373) (xy 30.021899 -342.605213) (xy 30.06641 -342.594926)
			(xy 30.08757 -342.58631) (xy 30.127491 -342.569645) (xy 30.20975 -342.542851) (xy 30.294124 -342.523727)
			(xy 30.379897 -342.512433) (xy 30.466345 -342.509066) (xy 30.552736 -342.513654) (xy 30.638341 -342.526158)
			(xy 30.722436 -342.546472) (xy 30.804309 -342.574424) (xy 30.883269 -342.60978) (xy 30.958647 -342.652238)
			(xy 31.029806 -342.70144) (xy 31.096145 -342.756971) (xy 31.157103 -342.818361) (xy 31.212165 -342.885091)
			(xy 31.260864 -342.956596) (xy 31.302789 -343.032272) (xy 31.337586 -343.111479) (xy 31.36496 -343.193547)
			(xy 31.38468 -343.277783) (xy 31.39658 -343.363474) (xy 31.400557 -343.449896) (xy 31.398557 -343.49336)
			(xy 34.599874 -343.49336) (xy 34.599874 -343.40646) (xy 34.607892 -343.319931) (xy 34.62386 -343.234511)
			(xy 34.647641 -343.150929) (xy 34.679033 -343.069897) (xy 34.717767 -342.992108) (xy 34.763514 -342.918224)
			(xy 34.815883 -342.848877) (xy 34.874427 -342.784657) (xy 34.938647 -342.726113) (xy 35.007994 -342.673744)
			(xy 35.081878 -342.627997) (xy 35.159667 -342.589263) (xy 35.240699 -342.557871) (xy 35.324281 -342.53409)
			(xy 35.409701 -342.518122) (xy 35.49623 -342.510104) (xy 35.58313 -342.510104) (xy 35.669659 -342.518122)
			(xy 35.755079 -342.53409) (xy 35.838661 -342.557871) (xy 35.919693 -342.589263) (xy 35.997482 -342.627997)
			(xy 36.071366 -342.673744) (xy 36.140713 -342.726113) (xy 36.204933 -342.784657) (xy 36.263477 -342.848877)
			(xy 36.315846 -342.918224) (xy 36.361593 -342.992108) (xy 36.400327 -343.069897) (xy 36.431719 -343.150929)
			(xy 36.4555 -343.234511) (xy 36.471468 -343.319931) (xy 36.479486 -343.40646) (xy 36.479988 -343.44991)
			(xy 36.479486 -343.49336) (xy 36.471468 -343.579889) (xy 36.4555 -343.665309) (xy 36.431719 -343.748891)
			(xy 36.400327 -343.829923) (xy 36.361593 -343.907712) (xy 36.316021 -343.981313) (xy 39.178238 -343.981313)
			(xy 39.182125 -343.926949) (xy 39.193709 -343.873692) (xy 39.212756 -343.822626) (xy 39.238877 -343.77479)
			(xy 39.27154 -343.73116) (xy 39.310081 -343.692622) (xy 39.353714 -343.659962) (xy 39.401551 -343.633845)
			(xy 39.452619 -343.614802) (xy 39.505877 -343.603221) (xy 39.560241 -343.599338) (xy 39.614604 -343.603233)
			(xy 39.66786 -343.614825) (xy 39.718923 -343.633879) (xy 39.766755 -343.660006) (xy 39.788846 -343.67597)
			(xy 39.807858 -343.689566) (xy 39.849741 -343.710298) (xy 39.894709 -343.723024) (xy 39.941246 -343.727314)
			(xy 39.987783 -343.723024) (xy 40.032751 -343.710298) (xy 40.074634 -343.689566) (xy 40.093646 -343.67597)
			(xy 40.115754 -343.660044) (xy 40.163575 -343.633933) (xy 40.214625 -343.614894) (xy 40.267865 -343.603314)
			(xy 40.322211 -343.599429) (xy 40.376557 -343.603317) (xy 40.429797 -343.6149) (xy 40.480846 -343.633943)
			(xy 40.528665 -343.660056) (xy 40.572282 -343.692709) (xy 40.610807 -343.731237) (xy 40.643457 -343.774855)
			(xy 40.669568 -343.822676) (xy 40.688606 -343.873727) (xy 40.700186 -343.926967) (xy 40.704071 -343.981313)
			(xy 40.700183 -344.035659) (xy 40.688599 -344.088899) (xy 40.669557 -344.139948) (xy 40.643443 -344.187767)
			(xy 40.61079 -344.231383) (xy 40.572262 -344.269908) (xy 40.528643 -344.302558) (xy 40.480822 -344.328668)
			(xy 40.429771 -344.347707) (xy 40.376531 -344.359287) (xy 40.322185 -344.363171) (xy 40.267839 -344.359282)
			(xy 40.2146 -344.347699) (xy 40.163551 -344.328656) (xy 40.115732 -344.302542) (xy 40.093646 -344.286586)
			(xy 40.074634 -344.27299) (xy 40.032751 -344.252258) (xy 39.987783 -344.239532) (xy 39.941246 -344.235242)
			(xy 39.894709 -344.239532) (xy 39.849741 -344.252258) (xy 39.807858 -344.27299) (xy 39.788846 -344.286586)
			(xy 39.766777 -344.30258) (xy 39.718947 -344.32871) (xy 39.667885 -344.347768) (xy 39.61463 -344.359364)
			(xy 39.560267 -344.363262) (xy 39.505903 -344.359383) (xy 39.452644 -344.347806) (xy 39.401575 -344.328766)
			(xy 39.353736 -344.302652) (xy 39.310101 -344.269995) (xy 39.271557 -344.23146) (xy 39.238891 -344.187832)
			(xy 39.212767 -344.139998) (xy 39.193717 -344.088933) (xy 39.182129 -344.035677) (xy 39.178238 -343.981313)
			(xy 36.316021 -343.981313) (xy 36.315846 -343.981596) (xy 36.263477 -344.050943) (xy 36.204933 -344.115163)
			(xy 36.140713 -344.173707) (xy 36.071366 -344.226076) (xy 35.997482 -344.271823) (xy 35.919693 -344.310557)
			(xy 35.838661 -344.341949) (xy 35.755079 -344.36573) (xy 35.669659 -344.381698) (xy 35.58313 -344.389716)
			(xy 35.49623 -344.389716) (xy 35.409701 -344.381698) (xy 35.324281 -344.36573) (xy 35.240699 -344.341949)
			(xy 35.159667 -344.310557) (xy 35.081878 -344.271823) (xy 35.007994 -344.226076) (xy 34.938647 -344.173707)
			(xy 34.874427 -344.115163) (xy 34.815883 -344.050943) (xy 34.763514 -343.981596) (xy 34.717767 -343.907712)
			(xy 34.679033 -343.829923) (xy 34.647641 -343.748891) (xy 34.62386 -343.665309) (xy 34.607892 -343.579889)
			(xy 34.599874 -343.49336) (xy 31.398557 -343.49336) (xy 31.39658 -343.536318) (xy 31.384682 -343.622009)
			(xy 31.364962 -343.706245) (xy 31.337589 -343.788314) (xy 31.302793 -343.867521) (xy 31.260868 -343.943198)
			(xy 31.212169 -344.014703) (xy 31.157109 -344.081433) (xy 31.096151 -344.142823) (xy 31.029813 -344.198355)
			(xy 30.958653 -344.247558) (xy 30.883276 -344.290017) (xy 30.804316 -344.325373) (xy 30.722444 -344.353326)
			(xy 30.638349 -344.373641) (xy 30.552744 -344.386145) (xy 30.466352 -344.390734) (xy 30.379905 -344.387368)
			(xy 30.294131 -344.376075) (xy 30.209758 -344.356951) (xy 30.127498 -344.330158) (xy 30.08757 -344.31351)
			(xy 30.066403 -344.304941) (xy 30.021906 -344.294702) (xy 29.976295 -344.292576) (xy 29.931038 -344.298634)
			(xy 29.887591 -344.312679) (xy 29.847352 -344.334259) (xy 29.811616 -344.362681) (xy 29.781532 -344.39703)
			(xy 29.758068 -344.436201) (xy 29.74198 -344.478933) (xy 29.733784 -344.523852) (xy 29.73324 -344.546682)
			(xy 29.73324 -344.893138) (xy 29.733718 -344.91598) (xy 29.741878 -344.96093) (xy 29.757945 -345.003696)
			(xy 29.781402 -345.042898) (xy 29.811492 -345.077274) (xy 29.847245 -345.105713) (xy 29.887507 -345.1273)
			(xy 29.930982 -345.141337) (xy 29.976265 -345.147373) (xy 30.021899 -345.145213) (xy 30.06641 -345.134926)
			(xy 30.08757 -345.12631) (xy 30.127491 -345.109645) (xy 30.20975 -345.082851) (xy 30.294124 -345.063727)
			(xy 30.379897 -345.052433) (xy 30.466345 -345.049066) (xy 30.552736 -345.053654) (xy 30.638341 -345.066158)
			(xy 30.722436 -345.086472) (xy 30.804309 -345.114424) (xy 30.883269 -345.14978) (xy 30.958647 -345.192238)
			(xy 31.029806 -345.24144) (xy 31.096145 -345.296971) (xy 31.157103 -345.358361) (xy 31.212165 -345.425091)
			(xy 31.260864 -345.496596) (xy 31.302789 -345.572272) (xy 31.337586 -345.651479) (xy 31.36496 -345.733547)
			(xy 31.38468 -345.817783) (xy 31.39658 -345.903474) (xy 31.400557 -345.989896) (xy 31.398557 -346.03336)
			(xy 34.599874 -346.03336) (xy 34.599874 -345.94646) (xy 34.607892 -345.859931) (xy 34.62386 -345.774511)
			(xy 34.647641 -345.690929) (xy 34.679033 -345.609897) (xy 34.717767 -345.532108) (xy 34.763514 -345.458224)
			(xy 34.815883 -345.388877) (xy 34.874427 -345.324657) (xy 34.938647 -345.266113) (xy 35.007994 -345.213744)
			(xy 35.081878 -345.167997) (xy 35.159667 -345.129263) (xy 35.240699 -345.097871) (xy 35.324281 -345.07409)
			(xy 35.409701 -345.058122) (xy 35.49623 -345.050104) (xy 35.58313 -345.050104) (xy 35.669659 -345.058122)
			(xy 35.755079 -345.07409) (xy 35.838661 -345.097871) (xy 35.919693 -345.129263) (xy 35.997482 -345.167997)
			(xy 36.071366 -345.213744) (xy 36.140713 -345.266113) (xy 36.204933 -345.324657) (xy 36.263477 -345.388877)
			(xy 36.315846 -345.458224) (xy 36.361593 -345.532108) (xy 36.400327 -345.609897) (xy 36.431719 -345.690929)
			(xy 36.4555 -345.774511) (xy 36.471468 -345.859931) (xy 36.479486 -345.94646) (xy 36.479988 -345.98991)
			(xy 36.479486 -346.03336) (xy 36.471468 -346.119889) (xy 36.4555 -346.205309) (xy 36.431719 -346.288891)
			(xy 36.400327 -346.369923) (xy 36.361593 -346.447712) (xy 36.315846 -346.521596) (xy 36.263477 -346.590943)
			(xy 36.204933 -346.655163) (xy 36.140713 -346.713707) (xy 36.071366 -346.766076) (xy 35.997482 -346.811823)
			(xy 35.919693 -346.850557) (xy 35.838661 -346.881949) (xy 35.755079 -346.90573) (xy 35.669659 -346.921698)
			(xy 35.58313 -346.929716) (xy 35.49623 -346.929716) (xy 35.409701 -346.921698) (xy 35.324281 -346.90573)
			(xy 35.240699 -346.881949) (xy 35.159667 -346.850557) (xy 35.081878 -346.811823) (xy 35.007994 -346.766076)
			(xy 34.938647 -346.713707) (xy 34.874427 -346.655163) (xy 34.815883 -346.590943) (xy 34.763514 -346.521596)
			(xy 34.717767 -346.447712) (xy 34.679033 -346.369923) (xy 34.647641 -346.288891) (xy 34.62386 -346.205309)
			(xy 34.607892 -346.119889) (xy 34.599874 -346.03336) (xy 31.398557 -346.03336) (xy 31.39658 -346.076318)
			(xy 31.384682 -346.162009) (xy 31.364962 -346.246245) (xy 31.337589 -346.328314) (xy 31.302793 -346.407521)
			(xy 31.260868 -346.483198) (xy 31.212169 -346.554703) (xy 31.157109 -346.621433) (xy 31.096151 -346.682823)
			(xy 31.029813 -346.738355) (xy 30.958653 -346.787558) (xy 30.883276 -346.830017) (xy 30.804316 -346.865373)
			(xy 30.722444 -346.893326) (xy 30.638349 -346.913641) (xy 30.552744 -346.926145) (xy 30.466352 -346.930734)
			(xy 30.379905 -346.927368) (xy 30.294131 -346.916075) (xy 30.209758 -346.896951) (xy 30.127498 -346.870158)
			(xy 30.08757 -346.85351) (xy 30.066403 -346.844941) (xy 30.021906 -346.834702) (xy 29.976295 -346.832576)
			(xy 29.931038 -346.838634) (xy 29.887591 -346.852679) (xy 29.847352 -346.874259) (xy 29.811616 -346.902681)
			(xy 29.781532 -346.93703) (xy 29.758068 -346.976201) (xy 29.74198 -347.018933) (xy 29.733784 -347.063852)
			(xy 29.73324 -347.086682) (xy 29.73324 -347.433138) (xy 29.733718 -347.45598) (xy 29.741878 -347.50093)
			(xy 29.757945 -347.543696) (xy 29.781402 -347.582898) (xy 29.811492 -347.617274) (xy 29.847245 -347.645713)
			(xy 29.887507 -347.6673) (xy 29.930982 -347.681337) (xy 29.976265 -347.687373) (xy 30.021899 -347.685213)
			(xy 30.06641 -347.674926) (xy 30.08757 -347.66631) (xy 30.128535 -347.649218) (xy 30.213007 -347.621928)
			(xy 30.299674 -347.60272) (xy 30.387766 -347.591765) (xy 30.476498 -347.589161) (xy 30.565081 -347.594932)
			(xy 30.652725 -347.609024) (xy 30.738652 -347.631314) (xy 30.822095 -347.661602) (xy 30.902312 -347.69962)
			(xy 30.97859 -347.745028) (xy 31.050249 -347.797422) (xy 31.116651 -347.856337) (xy 31.177205 -347.921247)
			(xy 31.204662 -347.956124) (xy 31.239714 -348.004892) (xy 31.263716 -348.041442) (xy 31.305601 -348.118205)
			(xy 31.340177 -348.198526) (xy 31.367144 -348.28171) (xy 31.386271 -348.36704) (xy 31.397391 -348.453777)
			(xy 31.400409 -348.541171) (xy 31.398524 -348.57336) (xy 34.599874 -348.57336) (xy 34.599874 -348.48646)
			(xy 34.607892 -348.399931) (xy 34.62386 -348.314511) (xy 34.647641 -348.230929) (xy 34.679033 -348.149897)
			(xy 34.717767 -348.072108) (xy 34.763514 -347.998224) (xy 34.815883 -347.928877) (xy 34.874427 -347.864657)
			(xy 34.938647 -347.806113) (xy 35.007994 -347.753744) (xy 35.081878 -347.707997) (xy 35.159667 -347.669263)
			(xy 35.240699 -347.637871) (xy 35.324281 -347.61409) (xy 35.409701 -347.598122) (xy 35.49623 -347.590104)
			(xy 35.58313 -347.590104) (xy 35.669659 -347.598122) (xy 35.755079 -347.61409) (xy 35.838661 -347.637871)
			(xy 35.919693 -347.669263) (xy 35.997482 -347.707997) (xy 36.071366 -347.753744) (xy 36.140713 -347.806113)
			(xy 36.204933 -347.864657) (xy 36.263477 -347.928877) (xy 36.315846 -347.998224) (xy 36.361593 -348.072108)
			(xy 36.400327 -348.149897) (xy 36.431719 -348.230929) (xy 36.4555 -348.314511) (xy 36.471468 -348.399931)
			(xy 36.479486 -348.48646) (xy 36.479988 -348.52991) (xy 36.479486 -348.57336) (xy 36.471468 -348.659889)
			(xy 36.4555 -348.745309) (xy 36.431719 -348.828891) (xy 36.400327 -348.909923) (xy 36.361593 -348.987712)
			(xy 36.315846 -349.061596) (xy 36.263477 -349.130943) (xy 36.204933 -349.195163) (xy 36.140713 -349.253707)
			(xy 36.071366 -349.306076) (xy 35.997482 -349.351823) (xy 35.919693 -349.390557) (xy 35.838661 -349.421949)
			(xy 35.755079 -349.44573) (xy 35.669659 -349.461698) (xy 35.58313 -349.469716) (xy 35.49623 -349.469716)
			(xy 35.409701 -349.461698) (xy 35.324281 -349.44573) (xy 35.240699 -349.421949) (xy 35.159667 -349.390557)
			(xy 35.081878 -349.351823) (xy 35.007994 -349.306076) (xy 34.938647 -349.253707) (xy 34.874427 -349.195163)
			(xy 34.815883 -349.130943) (xy 34.763514 -349.061596) (xy 34.717767 -348.987712) (xy 34.679033 -348.909923)
			(xy 34.647641 -348.828891) (xy 34.62386 -348.745309) (xy 34.607892 -348.659889) (xy 34.599874 -348.57336)
			(xy 31.398524 -348.57336) (xy 31.395298 -348.628468) (xy 31.382102 -348.714914) (xy 31.360937 -348.79976)
			(xy 31.331983 -348.882275) (xy 31.295493 -348.961744) (xy 31.25178 -349.037481) (xy 31.201224 -349.108832)
			(xy 31.14426 -349.17518) (xy 31.081381 -349.235952) (xy 31.01313 -349.290621) (xy 30.940098 -349.338717)
			(xy 30.862915 -349.379823) (xy 30.782249 -349.413585) (xy 30.698795 -349.439709) (xy 30.613277 -349.457971)
			(xy 30.569916 -349.463614) (xy 30.526228 -349.468948) (xy 30.494986 -349.499936) (xy 30.483538 -349.512078)
			(xy 30.46685 -349.540964) (xy 30.458207 -349.573186) (xy 30.458198 -349.606546) (xy 30.466824 -349.638773)
			(xy 30.483497 -349.667668) (xy 30.494986 -349.679768) (xy 30.648148 -349.832676) (xy 43.051984 -349.832676)
		)
		(stroke
			(width 0)
			(type solid)
		)
		(fill yes)
		(layer "In5.Cu")
		(net "GND")
	)
	(gr_poly
		(pts
			(xy 2.58064 -190.6016) (xy 2.584575 -190.62469) (xy 2.599759 -190.668994) (xy 2.622805 -190.709766)
			(xy 2.65293 -190.745625) (xy 2.689116 -190.775357) (xy 2.730137 -190.797956) (xy 2.774604 -190.812656)
			(xy 2.821011 -190.818959) (xy 2.867788 -190.816653) (xy 2.913351 -190.805815) (xy 2.956156 -190.786813)
			(xy 2.994756 -190.760289) (xy 3.011678 -190.744094) (xy 3.617468 -190.138304) (xy 4.424172 -190.138304)
			(xy 6.042914 -188.519562) (xy 6.05864 -188.503119) (xy 6.084565 -188.465735) (xy 6.10342 -188.424332)
			(xy 6.114603 -188.380234) (xy 6.117756 -188.33485) (xy 6.112779 -188.289629) (xy 6.099832 -188.246017)
			(xy 6.079327 -188.205406) (xy 6.051919 -188.169095) (xy 6.035548 -188.153294) (xy 6.007207 -188.128304)
			(xy 5.956052 -188.072692) (xy 5.911851 -188.011407) (xy 5.875226 -187.945314) (xy 5.846695 -187.875346)
			(xy 5.826659 -187.802489) (xy 5.815401 -187.727771) (xy 5.81308 -187.652244) (xy 5.815838 -187.61456)
			(xy 5.819523 -187.57859) (xy 5.834015 -187.507747) (xy 5.856456 -187.439007) (xy 5.886557 -187.373259)
			(xy 5.923927 -187.311354) (xy 5.968084 -187.254092) (xy 6.018456 -187.202214) (xy 6.074393 -187.15639)
			(xy 6.13517 -187.117212) (xy 6.200002 -187.085189) (xy 6.268051 -187.060733) (xy 6.338437 -187.04416)
			(xy 6.410249 -187.035686) (xy 6.482558 -187.03542) (xy 6.554431 -187.043365) (xy 6.624936 -187.059419)
			(xy 6.693164 -187.083374) (xy 6.72592 -187.098686) (xy 6.757257 -187.114363) (xy 6.816593 -187.151637)
			(xy 6.871465 -187.195218) (xy 6.921205 -187.244575) (xy 6.965209 -187.299108) (xy 7.002941 -187.358155)
			(xy 7.033942 -187.420997) (xy 7.057837 -187.48687) (xy 7.074333 -187.554973) (xy 7.079234 -187.589668)
			(xy 7.082464 -187.611212) (xy 7.095321 -187.652832) (xy 7.115089 -187.691649) (xy 7.141189 -187.726525)
			(xy 7.172855 -187.756438) (xy 7.20916 -187.780511) (xy 7.249039 -187.798038) (xy 7.291323 -187.808507)
			(xy 7.334773 -187.811609) (xy 7.378115 -187.807254) (xy 7.42008 -187.795569) (xy 7.459436 -187.776898)
			(xy 7.49503 -187.751787) (xy 7.51078 -187.736734) (xy 7.82701 -187.420504) (xy 9.163304 -187.420504)
			(xy 9.4361 -187.147708) (xy 9.4361 -168.891966) (xy 10.753344 -167.574468) (xy 18.900648 -159.427164)
			(xy 18.900648 -133.436106) (xy 17.691862 -132.22732) (xy 17.675965 -132.21208) (xy 17.639932 -132.186773)
			(xy 17.600074 -132.168058) (xy 17.557586 -132.156498) (xy 17.513741 -132.152438) (xy 17.469853 -132.156001)
			(xy 17.427236 -132.167079) (xy 17.387169 -132.185341) (xy 17.350851 -132.210239) (xy 17.319372 -132.241027)
			(xy 17.293673 -132.276783) (xy 17.283684 -132.296408) (xy 17.274714 -132.314683) (xy 17.255148 -132.350389)
			(xy 17.244568 -132.367782) (xy 17.223285 -132.401239) (xy 17.174992 -132.464138) (xy 17.120626 -132.521868)
			(xy 17.060736 -132.573846) (xy 16.995928 -132.619545) (xy 16.926858 -132.658504) (xy 16.854224 -132.690328)
			(xy 16.778761 -132.714696) (xy 16.701232 -132.731361) (xy 16.622421 -132.740154) (xy 16.543125 -132.740987)
			(xy 16.464147 -132.733852) (xy 16.386285 -132.718819) (xy 16.310327 -132.696042) (xy 16.23704 -132.665751)
			(xy 16.167167 -132.628252) (xy 16.101413 -132.583924) (xy 16.040444 -132.533217) (xy 15.984877 -132.476641)
			(xy 15.935273 -132.414771) (xy 15.892135 -132.348231) (xy 15.855898 -132.277695) (xy 15.826929 -132.203876)
			(xy 15.805521 -132.12752) (xy 15.791891 -132.0494) (xy 15.786176 -131.970307) (xy 15.788434 -131.891039)
			(xy 15.798643 -131.812399) (xy 15.807182 -131.773676) (xy 15.816265 -131.736803) (xy 15.84058 -131.664855)
			(xy 15.871701 -131.595578) (xy 15.909339 -131.529615) (xy 15.93088 -131.49834) (xy 15.943794 -131.479137)
			(xy 15.963168 -131.437116) (xy 15.974614 -131.392282) (xy 15.977754 -131.346117) (xy 15.972484 -131.300146)
			(xy 15.958978 -131.255888) (xy 15.937682 -131.214808) (xy 15.909301 -131.178262) (xy 15.874773 -131.147458)
			(xy 15.835238 -131.123414) (xy 15.792003 -131.106926) (xy 15.746498 -131.098537) (xy 15.723362 -131.098036)
			(xy 15.677388 -131.098036) (xy 6.621272 -122.041666) (xy 6.621272 -116.101368) (xy 3.136392 -112.616488)
			(xy 3.136392 -93.429836) (xy 5.78612 -90.780108) (xy 5.813552 -90.780108) (xy 6.13664 -90.45702)
			(xy 6.565646 -90.45702) (xy 6.588433 -90.456507) (xy 6.633276 -90.448372) (xy 6.67595 -90.432369)
			(xy 6.715085 -90.409013) (xy 6.749428 -90.379053) (xy 6.777878 -90.343448) (xy 6.799521 -90.30334)
			(xy 6.813666 -90.260015) (xy 6.819857 -90.214863) (xy 6.817897 -90.16933) (xy 6.807848 -90.124876)
			(xy 6.790032 -90.082928) (xy 6.77799 -90.063574) (xy 6.752758 -90.024311) (xy 6.708467 -89.94215)
			(xy 6.671517 -89.856437) (xy 6.642191 -89.767825) (xy 6.620713 -89.676992) (xy 6.607247 -89.58463)
			(xy 6.601895 -89.491445) (xy 6.604698 -89.398149) (xy 6.615636 -89.305454) (xy 6.634624 -89.214067)
			(xy 6.661518 -89.124687) (xy 6.696111 -89.037996) (xy 6.738141 -88.954656) (xy 6.787286 -88.875304)
			(xy 6.84317 -88.800544) (xy 6.905368 -88.730949) (xy 6.973403 -88.667049) (xy 7.046758 -88.609333)
			(xy 7.124871 -88.558241) (xy 7.207146 -88.514163) (xy 7.292955 -88.477436) (xy 7.381642 -88.44834)
			(xy 7.472531 -88.427097) (xy 7.564928 -88.413871) (xy 7.658126 -88.408761) (xy 7.751415 -88.411806)
			(xy 7.844081 -88.422984) (xy 7.935418 -88.442209) (xy 8.024728 -88.469335) (xy 8.111329 -88.504153)
			(xy 8.19456 -88.546399) (xy 8.273785 -88.595749) (xy 8.311388 -88.623394) (xy 8.330464 -88.63703)
			(xy 8.372493 -88.657806) (xy 8.417619 -88.670522) (xy 8.464313 -88.674746) (xy 8.510989 -88.670334)
			(xy 8.556064 -88.657437) (xy 8.598009 -88.636491) (xy 8.635401 -88.608208) (xy 8.666972 -88.573547)
			(xy 8.69165 -88.533683) (xy 8.708598 -88.48997) (xy 8.717242 -88.443889) (xy 8.717788 -88.420448)
			(xy 8.717788 -78.533244) (xy 8.717261 -78.509789) (xy 8.708672 -78.463672) (xy 8.691759 -78.419917)
			(xy 8.667098 -78.380013) (xy 8.635528 -78.345316) (xy 8.598122 -78.317008) (xy 8.556154 -78.296051)
			(xy 8.51105 -78.283158) (xy 8.464346 -78.278769) (xy 8.41763 -78.283031) (xy 8.372492 -78.295801)
			(xy 8.330467 -78.316643) (xy 8.311388 -78.330298) (xy 8.274012 -78.357761) (xy 8.195305 -78.406842)
			(xy 8.112636 -78.448909) (xy 8.026629 -78.483644) (xy 7.937932 -78.510786) (xy 7.847215 -78.53013)
			(xy 7.755162 -78.541531) (xy 7.662466 -78.544901) (xy 7.569828 -78.540217) (xy 7.477946 -78.527512)
			(xy 7.387512 -78.506883) (xy 7.29921 -78.478486) (xy 7.213704 -78.442534) (xy 7.13164 -78.3993) (xy 7.053636 -78.349108)
			(xy 6.980282 -78.292337) (xy 6.912129 -78.229416) (xy 6.849693 -78.16082) (xy 6.793444 -78.087064)
			(xy 6.743807 -78.008707) (xy 6.701155 -77.926338) (xy 6.66581 -77.84058) (xy 6.63804 -77.752078)
			(xy 6.618053 -77.6615) (xy 6.606 -77.56953) (xy 6.601972 -77.476861) (xy 6.605999 -77.384192) (xy 6.618052 -77.292222)
			(xy 6.638039 -77.201644) (xy 6.665809 -77.113143) (xy 6.701154 -77.027384) (xy 6.743805 -76.945015)
			(xy 6.793443 -76.866658) (xy 6.849692 -76.792902) (xy 6.912128 -76.724305) (xy 6.98028 -76.661384)
			(xy 7.053634 -76.604614) (xy 7.131638 -76.554422) (xy 7.213702 -76.511187) (xy 7.299207 -76.475235)
			(xy 7.38751 -76.446837) (xy 7.477944 -76.426208) (xy 7.569826 -76.413504) (xy 7.662464 -76.408819)
			(xy 7.755159 -76.412189) (xy 7.847213 -76.423589) (xy 7.93793 -76.442933) (xy 8.026626 -76.470075)
			(xy 8.112633 -76.50481) (xy 8.195303 -76.546877) (xy 8.27401 -76.595957) (xy 8.311388 -76.623418)
			(xy 8.330461 -76.637057) (xy 8.372486 -76.657839) (xy 8.41761 -76.670559) (xy 8.464302 -76.674785)
			(xy 8.510977 -76.670374) (xy 8.556051 -76.657476) (xy 8.597994 -76.636529) (xy 8.635382 -76.608243)
			(xy 8.666947 -76.573578) (xy 8.691618 -76.533711) (xy 8.708556 -76.489995) (xy 8.717188 -76.443913)
			(xy 8.717788 -76.420472) (xy 8.717788 -74.440796) (xy 8.717316 -74.41843) (xy 8.709484 -74.374388)
			(xy 8.694061 -74.332399) (xy 8.671525 -74.293758) (xy 8.642572 -74.25966) (xy 8.608095 -74.231158)
			(xy 8.569161 -74.209132) (xy 8.526972 -74.194263) (xy 8.482832 -74.187011) (xy 8.438103 -74.187599)
			(xy 8.394168 -74.196009) (xy 8.37311 -74.20356) (xy 8.313169 -74.226459) (xy 8.190996 -74.26573)
			(xy 8.066638 -74.297406) (xy 7.940566 -74.321368) (xy 7.813258 -74.337525) (xy 7.685197 -74.345815)
			(xy 7.556869 -74.346207) (xy 7.42876 -74.3387) (xy 7.301356 -74.323321) (xy 7.175139 -74.30013) (xy 7.05059 -74.269213)
			(xy 6.92818 -74.23069) (xy 6.808373 -74.184704) (xy 6.691624 -74.131432) (xy 6.578375 -74.071074)
			(xy 6.469056 -74.00386) (xy 6.364082 -73.930045) (xy 6.26385 -73.849909) (xy 6.16874 -73.763755)
			(xy 6.079114 -73.67191) (xy 5.995311 -73.574723) (xy 5.917649 -73.472561) (xy 5.881624 -73.419462)
			(xy 5.846432 -73.365839) (xy 5.781929 -73.254961) (xy 5.72437 -73.140324) (xy 5.673973 -73.022364)
			(xy 5.630929 -72.901525) (xy 5.595402 -72.778268) (xy 5.567526 -72.653058) (xy 5.547406 -72.52637)
			(xy 5.535119 -72.398685) (xy 5.530711 -72.270485) (xy 5.5342 -72.142257) (xy 5.545571 -72.014487)
			(xy 5.564782 -71.887658) (xy 5.59176 -71.762251) (xy 5.626402 -71.638742) (xy 5.668578 -71.517599)
			(xy 5.718128 -71.39928) (xy 5.774864 -71.284233) (xy 5.83857 -71.172896) (xy 5.909006 -71.065689)
			(xy 5.985905 -70.963018) (xy 6.068975 -70.865274) (xy 6.157902 -70.772826) (xy 6.252348 -70.686024)
			(xy 6.351956 -70.605198) (xy 6.456348 -70.530653) (xy 6.565128 -70.462673) (xy 6.621272 -70.43166)
			(xy 6.677365 -70.401786) (xy 6.792575 -70.34811) (xy 6.910843 -70.301557) (xy 7.031729 -70.262301)
			(xy 7.154784 -70.230486) (xy 7.279548 -70.206231) (xy 7.40556 -70.189628) (xy 7.532349 -70.180736)
			(xy 7.659444 -70.17959) (xy 7.786373 -70.186194) (xy 7.912663 -70.200522) (xy 8.037845 -70.222523)
			(xy 8.161453 -70.252113) (xy 8.283027 -70.289184) (xy 8.402115 -70.333596) (xy 8.518275 -70.385186)
			(xy 8.631074 -70.44376) (xy 8.740092 -70.509101) (xy 8.844925 -70.580967) (xy 8.945182 -70.659089)
			(xy 9.04049 -70.743178) (xy 9.130495 -70.83292) (xy 9.214862 -70.927981) (xy 9.293277 -71.028009)
			(xy 9.365449 -71.132631) (xy 9.431109 -71.241458) (xy 9.460992 -71.297546) (xy 9.471861 -71.317293)
			(xy 9.499456 -71.35293) (xy 9.532904 -71.383139) (xy 9.571157 -71.406976) (xy 9.613014 -71.42369)
			(xy 9.657163 -71.43276) (xy 9.70222 -71.433899) (xy 9.746772 -71.427073) (xy 9.78942 -71.412495)
			(xy 9.828828 -71.390622) (xy 9.863761 -71.362141) (xy 9.893121 -71.327945) (xy 9.91599 -71.289106)
			(xy 9.931648 -71.246843) (xy 9.939606 -71.20248) (xy 9.940036 -71.179944) (xy 9.940036 -66.94805)
			(xy 13.164058 -63.724028) (xy 13.183108 -63.666116) (xy 13.175488 -63.617348) (xy 13.170916 -63.602108)
			(xy 13.168376 -63.592456) (xy 13.158028 -63.553069) (xy 13.144221 -63.472807) (xy 13.138381 -63.391575)
			(xy 13.140565 -63.310164) (xy 13.150751 -63.229362) (xy 13.16884 -63.149955) (xy 13.194657 -63.072715)
			(xy 13.227952 -62.99839) (xy 13.2684 -62.927703) (xy 13.31561 -62.861341) (xy 13.369122 -62.799948)
			(xy 13.428416 -62.74412) (xy 13.492918 -62.694399) (xy 13.562001 -62.651268) (xy 13.634993 -62.615146)
			(xy 13.711186 -62.586384) (xy 13.78984 -62.565261) (xy 13.870192 -62.551982) (xy 13.95146 -62.546677)
			(xy 14.032856 -62.549396) (xy 14.113588 -62.560113) (xy 14.192874 -62.578724) (xy 14.269944 -62.605049)
			(xy 14.344048 -62.638832) (xy 14.414466 -62.679745) (xy 14.480517 -62.727389) (xy 14.541557 -62.781304)
			(xy 14.596993 -62.840965) (xy 14.646289 -62.905792) (xy 14.688965 -62.975157) (xy 14.724605 -63.048385)
			(xy 14.752866 -63.124766) (xy 14.773471 -63.203558) (xy 14.786221 -63.283994) (xy 14.790992 -63.365296)
			(xy 14.787738 -63.446672) (xy 14.776489 -63.527332) (xy 14.757357 -63.606494) (xy 14.730525 -63.683389)
			(xy 14.696256 -63.757269) (xy 14.654881 -63.827417) (xy 14.606803 -63.893152) (xy 14.552488 -63.953836)
			(xy 14.492464 -64.00888) (xy 14.427313 -64.057748) (xy 14.357669 -64.099966) (xy 14.284208 -64.135124)
			(xy 14.246098 -64.149478) (xy 14.208252 -64.163194) (xy 14.162278 -64.228726) (xy 14.162278 -64.269112)
			(xy 14.162823 -64.28576) (xy 14.171442 -64.317922) (xy 14.188091 -64.346758) (xy 14.211634 -64.370303)
			(xy 14.240469 -64.386954) (xy 14.27263 -64.395576) (xy 14.289278 -64.396112) (xy 14.59611 -64.396112)
			(xy 16.143986 -65.943734) (xy 16.33855 -66.138298) (xy 16.557752 -66.3575) (xy 16.60144 -66.36258)
			(xy 16.641942 -66.367867) (xy 16.721719 -66.385424) (xy 16.760698 -66.397632) (xy 16.781547 -66.403937)
			(xy 16.824657 -66.410138) (xy 16.868193 -66.408897) (xy 16.91088 -66.400249) (xy 16.951467 -66.384449)
			(xy 16.988764 -66.361958) (xy 17.02168 -66.333436) (xy 17.049249 -66.299718) (xy 17.070664 -66.261793)
			(xy 17.085298 -66.220771) (xy 17.092722 -66.177855) (xy 17.093184 -66.156078) (xy 17.093184 -65.681098)
			(xy 16.850868 -65.438782) (xy 16.781018 -65.42151) (xy 16.74238 -65.434701) (xy 16.663115 -65.454289)
			(xy 16.582305 -65.465961) (xy 16.500737 -65.469603) (xy 16.419208 -65.465179) (xy 16.338513 -65.452733)
			(xy 16.25944 -65.432385) (xy 16.18276 -65.404334) (xy 16.109222 -65.368855) (xy 16.039544 -65.326293)
			(xy 15.974405 -65.277064) (xy 15.914441 -65.221648) (xy 15.860238 -65.160586) (xy 15.812324 -65.094474)
			(xy 15.771166 -65.023956) (xy 15.737168 -64.949722) (xy 15.710659 -64.872496) (xy 15.6919 -64.793031)
			(xy 15.681073 -64.712103) (xy 15.678283 -64.630502) (xy 15.683559 -64.549023) (xy 15.696848 -64.468462)
			(xy 15.706852 -64.428878) (xy 15.717585 -64.390704) (xy 15.745391 -64.316437) (xy 15.780185 -64.245176)
			(xy 15.821648 -64.177577) (xy 15.869397 -64.114262) (xy 15.922994 -64.055813) (xy 15.981945 -64.00277)
			(xy 16.045707 -63.955619) (xy 16.113695 -63.914796) (xy 16.185281 -63.880675) (xy 16.259807 -63.853571)
			(xy 16.336587 -63.833732) (xy 16.414916 -63.821343) (xy 16.494071 -63.816516) (xy 16.573324 -63.819296)
			(xy 16.651946 -63.829658) (xy 16.729214 -63.847506) (xy 16.804415 -63.872676) (xy 16.876859 -63.904936)
			(xy 16.945878 -63.943989) (xy 16.97863 -63.966344) (xy 17.006983 -63.986686) (xy 17.060522 -64.03145)
			(xy 17.085564 -64.055752) (xy 17.087342 -64.05753) (xy 17.088612 -64.0588) (xy 17.105336 -64.074503)
			(xy 17.143328 -64.10021) (xy 17.185317 -64.118681) (xy 17.229939 -64.129316) (xy 17.275745 -64.13177)
			(xy 17.321248 -64.125962) (xy 17.364969 -64.112081) (xy 17.40549 -64.090579) (xy 17.441493 -64.062153)
			(xy 17.471809 -64.027727) (xy 17.495454 -63.988419) (xy 17.511661 -63.945505) (xy 17.519902 -63.90038)
			(xy 17.520412 -63.877444) (xy 17.520412 -63.568326) (xy 16.850868 -62.898782) (xy 16.781018 -62.88151)
			(xy 16.742362 -62.894727) (xy 16.663056 -62.914363) (xy 16.582199 -62.926073) (xy 16.500581 -62.929744)
			(xy 16.418999 -62.925339) (xy 16.338251 -62.912901) (xy 16.259125 -62.892553) (xy 16.182394 -62.864492)
			(xy 16.108809 -62.828993) (xy 16.039088 -62.786403) (xy 15.973912 -62.737138) (xy 15.913918 -62.681678)
			(xy 15.859692 -62.620567) (xy 15.811764 -62.554402) (xy 15.770603 -62.483827) (xy 15.73661 -62.409534)
			(xy 15.710118 -62.332248) (xy 15.691385 -62.252724) (xy 15.680594 -62.171739) (xy 15.677852 -62.090085)
			(xy 15.683184 -62.008558) (xy 15.696539 -61.927956) (xy 15.717785 -61.849067) (xy 15.746717 -61.77266)
			(xy 15.78305 -61.699483) (xy 15.82643 -61.630251) (xy 15.876433 -61.565639) (xy 15.932571 -61.506279)
			(xy 15.963138 -61.479176) (xy 15.993711 -61.45326) (xy 16.059041 -61.406821) (xy 16.128563 -61.366929)
			(xy 16.201621 -61.33396) (xy 16.27753 -61.308222) (xy 16.355575 -61.289958) (xy 16.435022 -61.279341)
			(xy 16.515124 -61.276469) (xy 16.595128 -61.28137) (xy 16.67428 -61.293998) (xy 16.751837 -61.314233)
			(xy 16.827069 -61.341887) (xy 16.899269 -61.376698) (xy 16.967757 -61.418339) (xy 17.031889 -61.466418)
			(xy 17.091062 -61.520484) (xy 17.14472 -61.580027) (xy 17.192358 -61.644488) (xy 17.233527 -61.713261)
			(xy 17.267841 -61.785698) (xy 17.294977 -61.861118) (xy 17.314679 -61.938812) (xy 17.326762 -62.01805)
			(xy 17.329404 -62.058042) (xy 17.330989 -62.094579) (xy 17.3285 -62.167674) (xy 17.319564 -62.240264)
			(xy 17.304252 -62.311781) (xy 17.293844 -62.34684) (xy 17.28343 -62.380622) (xy 17.300448 -62.449202)
			(xy 17.54378 -62.692534) (xy 17.560319 -62.707317) (xy 17.597501 -62.731501) (xy 17.638315 -62.748866)
			(xy 17.681524 -62.758883) (xy 17.725816 -62.761249) (xy 17.769846 -62.755892) (xy 17.812278 -62.742975)
			(xy 17.851825 -62.72289) (xy 17.887285 -62.696246) (xy 17.917583 -62.663852) (xy 17.941799 -62.626691)
			(xy 17.959198 -62.585891) (xy 17.969252 -62.542691) (xy 17.971008 -62.520576) (xy 17.971008 -61.299852)
			(xy 11.299952 -54.628796) (xy 11.299952 -48.909478) (xy 12.058396 -48.151034) (xy 12.058396 -44.584112)
			(xy 13.399516 -43.242992) (xy 15.661894 -43.242992) (xy 15.772892 -43.176444) (xy 15.789402 -43.147996)
			(xy 15.809886 -43.113474) (xy 15.856583 -43.048174) (xy 15.909395 -42.987713) (xy 15.967824 -42.932661)
			(xy 16.031318 -42.883537) (xy 16.099279 -42.840805) (xy 16.171065 -42.804869) (xy 16.245999 -42.776067)
			(xy 16.323374 -42.754671) (xy 16.402459 -42.740882) (xy 16.48251 -42.734832) (xy 16.562769 -42.736576)
			(xy 16.642481 -42.7461) (xy 16.720893 -42.763311) (xy 16.797265 -42.78805) (xy 16.870876 -42.820081)
			(xy 16.941033 -42.859103) (xy 16.974312 -42.88155) (xy 17.004339 -42.902799) (xy 17.060894 -42.949845)
			(xy 17.113047 -43.001728) (xy 17.160387 -43.058037) (xy 17.20254 -43.118328) (xy 17.2212 -43.150028)
			(xy 17.240923 -43.185419) (xy 17.274153 -43.259317) (xy 17.299989 -43.336114) (xy 17.318182 -43.415071)
			(xy 17.328557 -43.49543) (xy 17.331015 -43.576418) (xy 17.325532 -43.657258) (xy 17.312161 -43.737173)
			(xy 17.29103 -43.815395) (xy 17.262343 -43.891173) (xy 17.226374 -43.963777) (xy 17.219215 -43.975246)
			(xy 54.922011 -43.975246) (xy 54.925903 -43.920891) (xy 54.937491 -43.867644) (xy 54.956539 -43.816588)
			(xy 54.98266 -43.768762) (xy 54.99862 -43.746674) (xy 55.012239 -43.727678) (xy 55.032967 -43.68579)
			(xy 55.045689 -43.640818) (xy 55.049976 -43.594279) (xy 55.045682 -43.547741) (xy 55.032953 -43.502771)
			(xy 55.012217 -43.460887) (xy 54.99862 -43.441874) (xy 54.98266 -43.419786) (xy 54.956539 -43.37196)
			(xy 54.937491 -43.320904) (xy 54.925903 -43.267657) (xy 54.922011 -43.213302) (xy 54.925895 -43.158947)
			(xy 54.937475 -43.105698) (xy 54.956516 -43.054639) (xy 54.98263 -43.006809) (xy 55.015285 -42.963183)
			(xy 55.053816 -42.924649) (xy 55.09744 -42.891991) (xy 55.145267 -42.865874) (xy 55.196325 -42.846829)
			(xy 55.249573 -42.835245) (xy 55.303928 -42.831357) (xy 55.358283 -42.835245) (xy 55.411531 -42.846829)
			(xy 55.462589 -42.865874) (xy 55.510416 -42.891991) (xy 55.55404 -42.924649) (xy 55.592571 -42.963183)
			(xy 55.625226 -43.006809) (xy 55.65134 -43.054639) (xy 55.670381 -43.105698) (xy 55.681961 -43.158947)
			(xy 55.685845 -43.213302) (xy 55.681953 -43.267657) (xy 55.670365 -43.320904) (xy 55.651317 -43.37196)
			(xy 55.625196 -43.419786) (xy 55.609236 -43.441874) (xy 55.595663 -43.460902) (xy 55.574925 -43.50278)
			(xy 55.562195 -43.547745) (xy 55.5579 -43.594279) (xy 55.562187 -43.640814) (xy 55.57491 -43.685781)
			(xy 55.595641 -43.727663) (xy 55.609236 -43.746674) (xy 55.625196 -43.768762) (xy 55.651317 -43.816588)
			(xy 55.670365 -43.867644) (xy 55.681953 -43.920891) (xy 55.685845 -43.975246) (xy 57.453883 -43.975246)
			(xy 57.457775 -43.920891) (xy 57.469363 -43.867644) (xy 57.488411 -43.816588) (xy 57.514532 -43.768762)
			(xy 57.530492 -43.746674) (xy 57.544112 -43.727679) (xy 57.564843 -43.685791) (xy 57.577566 -43.640819)
			(xy 57.581853 -43.594279) (xy 57.577559 -43.54774) (xy 57.564828 -43.50277) (xy 57.54409 -43.460886)
			(xy 57.530492 -43.441874) (xy 57.514532 -43.419786) (xy 57.488411 -43.37196) (xy 57.469363 -43.320904)
			(xy 57.457775 -43.267657) (xy 57.453883 -43.213302) (xy 57.457767 -43.158947) (xy 57.469347 -43.105698)
			(xy 57.488388 -43.054639) (xy 57.514502 -43.006809) (xy 57.547157 -42.963183) (xy 57.585688 -42.924649)
			(xy 57.629312 -42.891991) (xy 57.677139 -42.865874) (xy 57.728197 -42.846829) (xy 57.781445 -42.835245)
			(xy 57.8358 -42.831357) (xy 57.890155 -42.835245) (xy 57.943403 -42.846829) (xy 57.994461 -42.865874)
			(xy 58.042288 -42.891991) (xy 58.085912 -42.924649) (xy 58.124443 -42.963183) (xy 58.157098 -43.006809)
			(xy 58.183212 -43.054639) (xy 58.202253 -43.105698) (xy 58.213833 -43.158947) (xy 58.217717 -43.213302)
			(xy 58.213825 -43.267657) (xy 58.202237 -43.320904) (xy 58.183189 -43.37196) (xy 58.157068 -43.419786)
			(xy 58.141108 -43.441874) (xy 58.127536 -43.460902) (xy 58.106801 -43.502781) (xy 58.094072 -43.547746)
			(xy 58.089778 -43.594279) (xy 58.094064 -43.640813) (xy 58.106786 -43.68578) (xy 58.127514 -43.727662)
			(xy 58.141108 -43.746674) (xy 58.157068 -43.768762) (xy 58.183189 -43.816588) (xy 58.202237 -43.867644)
			(xy 58.213825 -43.920891) (xy 58.217717 -43.975246) (xy 60.258297 -43.975246) (xy 60.262189 -43.920891)
			(xy 60.273777 -43.867644) (xy 60.292825 -43.816588) (xy 60.318946 -43.768762) (xy 60.334906 -43.746674)
			(xy 60.348525 -43.727678) (xy 60.369255 -43.68579) (xy 60.381978 -43.640819) (xy 60.386264 -43.594279)
			(xy 60.38197 -43.54774) (xy 60.36924 -43.502771) (xy 60.348504 -43.460886) (xy 60.334906 -43.441874)
			(xy 60.318946 -43.419786) (xy 60.292825 -43.37196) (xy 60.273777 -43.320904) (xy 60.262189 -43.267657)
			(xy 60.258297 -43.213302) (xy 60.262181 -43.158947) (xy 60.273761 -43.105698) (xy 60.292802 -43.054639)
			(xy 60.318916 -43.006809) (xy 60.351571 -42.963183) (xy 60.390102 -42.924649) (xy 60.433726 -42.891991)
			(xy 60.481553 -42.865874) (xy 60.532611 -42.846829) (xy 60.585859 -42.835245) (xy 60.640214 -42.831357)
			(xy 60.694569 -42.835245) (xy 60.747817 -42.846829) (xy 60.798875 -42.865874) (xy 60.846702 -42.891991)
			(xy 60.890326 -42.924649) (xy 60.928857 -42.963183) (xy 60.961512 -43.006809) (xy 60.987626 -43.054639)
			(xy 61.006667 -43.105698) (xy 61.018247 -43.158947) (xy 61.022131 -43.213302) (xy 61.018239 -43.267657)
			(xy 61.006651 -43.320904) (xy 60.987603 -43.37196) (xy 60.961482 -43.419786) (xy 60.945522 -43.441874)
			(xy 60.93195 -43.460902) (xy 60.911213 -43.502781) (xy 60.898483 -43.547745) (xy 60.894189 -43.594279)
			(xy 60.898476 -43.640814) (xy 60.911198 -43.68578) (xy 60.931928 -43.727662) (xy 60.945522 -43.746674)
			(xy 60.961482 -43.768762) (xy 60.987603 -43.816588) (xy 61.006651 -43.867644) (xy 61.018239 -43.920891)
			(xy 61.022131 -43.975246) (xy 62.631165 -43.975246) (xy 62.635057 -43.920891) (xy 62.646645 -43.867644)
			(xy 62.665693 -43.816588) (xy 62.691814 -43.768762) (xy 62.707774 -43.746674) (xy 62.721395 -43.727679)
			(xy 62.742127 -43.685792) (xy 62.754852 -43.64082) (xy 62.759139 -43.594279) (xy 62.754844 -43.547739)
			(xy 62.742112 -43.50277) (xy 62.721373 -43.460886) (xy 62.707774 -43.441874) (xy 62.691814 -43.419786)
			(xy 62.665693 -43.37196) (xy 62.646645 -43.320904) (xy 62.635057 -43.267657) (xy 62.631165 -43.213302)
			(xy 62.635049 -43.158947) (xy 62.646629 -43.105698) (xy 62.66567 -43.054639) (xy 62.691784 -43.006809)
			(xy 62.724439 -42.963183) (xy 62.76297 -42.924649) (xy 62.806594 -42.891991) (xy 62.854421 -42.865874)
			(xy 62.905479 -42.846829) (xy 62.958727 -42.835245) (xy 63.013082 -42.831357) (xy 63.067437 -42.835245)
			(xy 63.120685 -42.846829) (xy 63.171743 -42.865874) (xy 63.21957 -42.891991) (xy 63.263194 -42.924649)
			(xy 63.301725 -42.963183) (xy 63.33438 -43.006809) (xy 63.360494 -43.054639) (xy 63.379535 -43.105698)
			(xy 63.391115 -43.158947) (xy 63.394999 -43.213302) (xy 63.391107 -43.267657) (xy 63.379519 -43.320904)
			(xy 63.360471 -43.37196) (xy 63.33435 -43.419786) (xy 63.31839 -43.441874) (xy 63.304819 -43.460903)
			(xy 63.284085 -43.502782) (xy 63.271357 -43.547746) (xy 63.267064 -43.594279) (xy 63.271349 -43.640813)
			(xy 63.28407 -43.685779) (xy 63.304797 -43.727662) (xy 63.31839 -43.746674) (xy 63.33435 -43.768762)
			(xy 63.360471 -43.816588) (xy 63.379519 -43.867644) (xy 63.391107 -43.920891) (xy 63.394999 -43.975246)
			(xy 64.860777 -43.975246) (xy 64.864669 -43.920891) (xy 64.876257 -43.867644) (xy 64.895305 -43.816588)
			(xy 64.921426 -43.768762) (xy 64.937386 -43.746674) (xy 64.951006 -43.727679) (xy 64.971738 -43.685791)
			(xy 64.984462 -43.640819) (xy 64.988748 -43.594279) (xy 64.984454 -43.54774) (xy 64.971723 -43.50277)
			(xy 64.950985 -43.460886) (xy 64.937386 -43.441874) (xy 64.921426 -43.419786) (xy 64.895305 -43.37196)
			(xy 64.876257 -43.320904) (xy 64.864669 -43.267657) (xy 64.860777 -43.213302) (xy 64.864661 -43.158947)
			(xy 64.876241 -43.105698) (xy 64.895282 -43.054639) (xy 64.921396 -43.006809) (xy 64.954051 -42.963183)
			(xy 64.992582 -42.924649) (xy 65.036206 -42.891991) (xy 65.084033 -42.865874) (xy 65.135091 -42.846829)
			(xy 65.188339 -42.835245) (xy 65.242694 -42.831357) (xy 65.297049 -42.835245) (xy 65.350297 -42.846829)
			(xy 65.401355 -42.865874) (xy 65.449182 -42.891991) (xy 65.492806 -42.924649) (xy 65.531337 -42.963183)
			(xy 65.563992 -43.006809) (xy 65.590106 -43.054639) (xy 65.609147 -43.105698) (xy 65.620727 -43.158947)
			(xy 65.624611 -43.213302) (xy 65.620719 -43.267657) (xy 65.609131 -43.320904) (xy 65.590083 -43.37196)
			(xy 65.563962 -43.419786) (xy 65.548002 -43.441874) (xy 65.534431 -43.460902) (xy 65.513696 -43.502782)
			(xy 65.500967 -43.547746) (xy 65.496673 -43.594279) (xy 65.500959 -43.640813) (xy 65.513681 -43.68578)
			(xy 65.534409 -43.727662) (xy 65.548002 -43.746674) (xy 65.563962 -43.768762) (xy 65.590083 -43.816588)
			(xy 65.609131 -43.867644) (xy 65.620719 -43.920891) (xy 65.624611 -43.975246) (xy 65.620727 -44.029601)
			(xy 65.609147 -44.08285) (xy 65.590106 -44.133909) (xy 65.563992 -44.181739) (xy 65.531337 -44.225365)
			(xy 65.492806 -44.263899) (xy 65.449182 -44.296557) (xy 65.401355 -44.322674) (xy 65.350297 -44.341719)
			(xy 65.297049 -44.353303) (xy 65.242694 -44.357191) (xy 65.188339 -44.353303) (xy 65.135091 -44.341719)
			(xy 65.084033 -44.322674) (xy 65.036206 -44.296557) (xy 64.992582 -44.263899) (xy 64.954051 -44.225365)
			(xy 64.921396 -44.181739) (xy 64.895282 -44.133909) (xy 64.876241 -44.08285) (xy 64.864661 -44.029601)
			(xy 64.860777 -43.975246) (xy 63.394999 -43.975246) (xy 63.391115 -44.029601) (xy 63.379535 -44.08285)
			(xy 63.360494 -44.133909) (xy 63.33438 -44.181739) (xy 63.301725 -44.225365) (xy 63.263194 -44.263899)
			(xy 63.21957 -44.296557) (xy 63.171743 -44.322674) (xy 63.120685 -44.341719) (xy 63.067437 -44.353303)
			(xy 63.013082 -44.357191) (xy 62.958727 -44.353303) (xy 62.905479 -44.341719) (xy 62.854421 -44.322674)
			(xy 62.806594 -44.296557) (xy 62.76297 -44.263899) (xy 62.724439 -44.225365) (xy 62.691784 -44.181739)
			(xy 62.66567 -44.133909) (xy 62.646629 -44.08285) (xy 62.635049 -44.029601) (xy 62.631165 -43.975246)
			(xy 61.022131 -43.975246) (xy 61.018247 -44.029601) (xy 61.006667 -44.08285) (xy 60.987626 -44.133909)
			(xy 60.961512 -44.181739) (xy 60.928857 -44.225365) (xy 60.890326 -44.263899) (xy 60.846702 -44.296557)
			(xy 60.798875 -44.322674) (xy 60.747817 -44.341719) (xy 60.694569 -44.353303) (xy 60.640214 -44.357191)
			(xy 60.585859 -44.353303) (xy 60.532611 -44.341719) (xy 60.481553 -44.322674) (xy 60.433726 -44.296557)
			(xy 60.390102 -44.263899) (xy 60.351571 -44.225365) (xy 60.318916 -44.181739) (xy 60.292802 -44.133909)
			(xy 60.273761 -44.08285) (xy 60.262181 -44.029601) (xy 60.258297 -43.975246) (xy 58.217717 -43.975246)
			(xy 58.213833 -44.029601) (xy 58.202253 -44.08285) (xy 58.183212 -44.133909) (xy 58.157098 -44.181739)
			(xy 58.124443 -44.225365) (xy 58.085912 -44.263899) (xy 58.042288 -44.296557) (xy 57.994461 -44.322674)
			(xy 57.943403 -44.341719) (xy 57.890155 -44.353303) (xy 57.8358 -44.357191) (xy 57.781445 -44.353303)
			(xy 57.728197 -44.341719) (xy 57.677139 -44.322674) (xy 57.629312 -44.296557) (xy 57.585688 -44.263899)
			(xy 57.547157 -44.225365) (xy 57.514502 -44.181739) (xy 57.488388 -44.133909) (xy 57.469347 -44.08285)
			(xy 57.457767 -44.029601) (xy 57.453883 -43.975246) (xy 55.685845 -43.975246) (xy 55.681961 -44.029601)
			(xy 55.670381 -44.08285) (xy 55.65134 -44.133909) (xy 55.625226 -44.181739) (xy 55.592571 -44.225365)
			(xy 55.55404 -44.263899) (xy 55.510416 -44.296557) (xy 55.462589 -44.322674) (xy 55.411531 -44.341719)
			(xy 55.358283 -44.353303) (xy 55.303928 -44.357191) (xy 55.249573 -44.353303) (xy 55.196325 -44.341719)
			(xy 55.145267 -44.322674) (xy 55.09744 -44.296557) (xy 55.053816 -44.263899) (xy 55.015285 -44.225365)
			(xy 54.98263 -44.181739) (xy 54.956516 -44.133909) (xy 54.937475 -44.08285) (xy 54.925895 -44.029601)
			(xy 54.922011 -43.975246) (xy 17.219215 -43.975246) (xy 17.18347 -44.032512) (xy 17.134042 -44.096715)
			(xy 17.078566 -44.155772) (xy 17.017575 -44.209113) (xy 16.951655 -44.256226) (xy 16.881438 -44.296659)
			(xy 16.807601 -44.330024) (xy 16.730851 -44.355999) (xy 16.651927 -44.374336) (xy 16.571588 -44.384857)
			(xy 16.490604 -44.387462) (xy 16.409754 -44.382126) (xy 16.329815 -44.3689) (xy 16.251554 -44.347911)
			(xy 16.175725 -44.319362) (xy 16.103055 -44.283525) (xy 16.034243 -44.240746) (xy 15.969949 -44.191435)
			(xy 15.910793 -44.136066) (xy 15.857341 -44.075172) (xy 15.810108 -44.009337) (xy 15.789402 -43.974512)
			(xy 15.773146 -43.946064) (xy 15.661894 -43.879008) (xy 14.788642 -43.879008) (xy 14.766742 -43.879472)
			(xy 14.723591 -43.886993) (xy 14.68237 -43.901802) (xy 14.644298 -43.923461) (xy 14.610505 -43.951327)
			(xy 14.581991 -43.984576) (xy 14.5596 -44.022221) (xy 14.543997 -44.063149) (xy 14.535644 -44.106146)
			(xy 14.534787 -44.149939) (xy 14.541453 -44.193229) (xy 14.555444 -44.234736) (xy 14.576345 -44.273228)
			(xy 14.589506 -44.290742) (xy 14.614952 -44.320873) (xy 14.660616 -44.385181) (xy 14.699943 -44.453549)
			(xy 14.732574 -44.525353) (xy 14.758212 -44.599942) (xy 14.776623 -44.676634) (xy 14.787641 -44.754732)
			(xy 14.791165 -44.833525) (xy 14.787162 -44.912295) (xy 14.775669 -44.990324) (xy 14.756791 -45.066903)
			(xy 14.730699 -45.141334) (xy 14.697632 -45.212939) (xy 14.65789 -45.281066) (xy 14.611836 -45.345095)
			(xy 14.586204 -45.375068) (xy 14.558773 -45.405633) (xy 14.498809 -45.461758) (xy 14.433572 -45.511656)
			(xy 14.363706 -45.554836) (xy 14.289901 -45.590871) (xy 14.212885 -45.619405) (xy 14.133418 -45.640158)
			(xy 14.052284 -45.652924) (xy 13.970284 -45.657577) (xy 13.888226 -45.654071) (xy 13.806922 -45.642442)
			(xy 13.727172 -45.622803) (xy 13.688314 -45.60951) (xy 13.618464 -45.626782) (xy 13.058648 -46.186598)
			(xy 13.058648 -48.227996) (xy 13.059107 -48.243866) (xy 13.066881 -48.274638) (xy 13.082001 -48.302544)
			(xy 13.103534 -48.325862) (xy 13.13015 -48.343152) (xy 13.160207 -48.353347) (xy 13.175996 -48.354996)
			(xy 13.75664 -48.354996) (xy 13.771966 -48.353593) (xy 13.801309 -48.344336) (xy 13.827576 -48.328311)
			(xy 13.838682 -48.317658) (xy 15.704058 -46.452028) (xy 15.723108 -46.394116) (xy 15.715488 -46.345348)
			(xy 15.710916 -46.330108) (xy 15.708376 -46.320456) (xy 15.69796 -46.28076) (xy 15.684107 -46.199863)
			(xy 15.678347 -46.117992) (xy 15.680735 -46.035953) (xy 15.691248 -45.954555) (xy 15.709782 -45.874601)
			(xy 15.736155 -45.79688) (xy 15.770106 -45.722158) (xy 15.811301 -45.651172) (xy 15.859334 -45.584621)
			(xy 15.91373 -45.523162) (xy 15.973954 -45.467402) (xy 16.039411 -45.417889) (xy 16.109456 -45.375113)
			(xy 16.183399 -45.339495) (xy 16.260509 -45.311387) (xy 16.340027 -45.291065) (xy 16.421169 -45.27873)
			(xy 16.503134 -45.274503) (xy 16.585114 -45.278427) (xy 16.6663 -45.290462) (xy 16.745893 -45.31049)
			(xy 16.823107 -45.338314) (xy 16.89718 -45.373659) (xy 16.967383 -45.416176) (xy 17.033022 -45.465446)
			(xy 17.093452 -45.520984) (xy 17.148075 -45.582241) (xy 17.196353 -45.648614) (xy 17.23781 -45.719448)
			(xy 17.272037 -45.794044) (xy 17.298696 -45.871667) (xy 17.317526 -45.951552) (xy 17.32834 -46.03291)
			(xy 17.331031 -46.11494) (xy 17.325572 -46.196832) (xy 17.312019 -46.277779) (xy 17.290504 -46.356983)
			(xy 17.261239 -46.433662) (xy 17.224514 -46.507061) (xy 17.18069 -46.576455) (xy 17.130199 -46.64116)
			(xy 17.073539 -46.700539) (xy 17.01127 -46.754005) (xy 16.944005 -46.801032) (xy 16.872407 -46.841155)
			(xy 16.797183 -46.87398) (xy 16.719074 -46.899181) (xy 16.638851 -46.916512) (xy 16.557304 -46.9258)
			(xy 16.475239 -46.926954) (xy 16.434308 -46.92396) (xy 16.39443 -46.964092) (xy 14.465808 -48.892714)
			(xy 14.449456 -48.909815) (xy 14.422777 -48.948884) (xy 14.403781 -48.992212) (xy 14.393124 -49.038306)
			(xy 14.391174 -49.085575) (xy 14.397996 -49.13239) (xy 14.413357 -49.177136) (xy 14.436726 -49.218271)
			(xy 14.467298 -49.254375) (xy 14.485366 -49.26965) (xy 14.516478 -49.295544) (xy 14.574033 -49.352467)
			(xy 14.625744 -49.414747) (xy 14.671115 -49.481787) (xy 14.709711 -49.552943) (xy 14.741162 -49.627533)
			(xy 14.765165 -49.704842) (xy 14.781492 -49.784128) (xy 14.789985 -49.864631) (xy 14.790563 -49.945578)
			(xy 14.787372 -49.98593) (xy 14.7831 -50.027122) (xy 14.767349 -50.108429) (xy 14.743539 -50.187751)
			(xy 14.72819 -50.226214) (xy 14.710768 -50.266904) (xy 14.668434 -50.344644) (xy 14.618025 -50.417407)
			(xy 14.589506 -50.451258) (xy 14.576261 -50.468715) (xy 14.555345 -50.507217) (xy 14.541343 -50.548736)
			(xy 14.534671 -50.592042) (xy 14.535526 -50.63585) (xy 14.543882 -50.678862) (xy 14.559493 -50.719803)
			(xy 14.581895 -50.75746) (xy 14.610424 -50.790716) (xy 14.644235 -50.818586) (xy 14.682325 -50.840243)
			(xy 14.723565 -50.855045) (xy 14.766734 -50.862554) (xy 14.788642 -50.862992) (xy 15.661894 -50.862992)
			(xy 15.772892 -50.796444) (xy 15.789402 -50.767996) (xy 15.810235 -50.732905) (xy 15.857816 -50.666597)
			(xy 15.911706 -50.605306) (xy 15.971377 -50.549629) (xy 16.03625 -50.500109) (xy 16.10569 -50.457229)
			(xy 16.179021 -50.421406) (xy 16.255527 -50.392991) (xy 16.334463 -50.372261) (xy 16.415059 -50.359416)
			(xy 16.496528 -50.354584) (xy 16.578077 -50.35781) (xy 16.658911 -50.369064) (xy 16.73824 -50.388236)
			(xy 16.815291 -50.415138) (xy 16.889313 -50.449509) (xy 16.959585 -50.491013) (xy 17.02542 -50.539245)
			(xy 17.086177 -50.593736) (xy 17.141264 -50.653953) (xy 17.190142 -50.71931) (xy 17.232337 -50.789169)
			(xy 17.267435 -50.862849) (xy 17.295095 -50.939632) (xy 17.315047 -51.018768) (xy 17.327097 -51.099487)
			(xy 17.331126 -51.181) (xy 17.327097 -51.262513) (xy 17.315047 -51.343232) (xy 17.310802 -51.36007)
			(xy 39.818564 -51.36007) (xy 39.819054 -51.302663) (xy 39.826889 -51.188117) (xy 39.842523 -51.074372)
			(xy 39.865882 -50.96196) (xy 39.896859 -50.851403) (xy 39.935308 -50.743218) (xy 39.98105 -50.63791)
			(xy 40.033872 -50.535968) (xy 40.093527 -50.437869) (xy 40.159738 -50.344069) (xy 40.232196 -50.255007)
			(xy 40.310562 -50.171096) (xy 40.394473 -50.09273) (xy 40.483535 -50.020272) (xy 40.577335 -49.954061)
			(xy 40.675434 -49.894406) (xy 40.777376 -49.841584) (xy 40.882684 -49.795842) (xy 40.990869 -49.757393)
			(xy 41.101426 -49.726416) (xy 41.213838 -49.703057) (xy 41.327583 -49.687423) (xy 41.442129 -49.679588)
			(xy 41.556943 -49.679588) (xy 41.671489 -49.687423) (xy 41.785234 -49.703057) (xy 41.897646 -49.726416)
			(xy 42.008203 -49.757393) (xy 42.116388 -49.795842) (xy 42.221696 -49.841584) (xy 42.323638 -49.894406)
			(xy 42.421737 -49.954061) (xy 42.50107 -50.01006) (xy 63.647577 -50.01006) (xy 63.651612 -49.934356)
			(xy 63.663671 -49.859511) (xy 63.683617 -49.78637) (xy 63.711224 -49.715765) (xy 63.74618 -49.648494)
			(xy 63.788088 -49.585319) (xy 63.836474 -49.526957) (xy 63.89079 -49.474069) (xy 63.950419 -49.427254)
			(xy 64.014687 -49.387042) (xy 64.082864 -49.35389) (xy 64.15418 -49.328172) (xy 64.227825 -49.31018)
			(xy 64.302965 -49.300118) (xy 64.378749 -49.298099) (xy 64.454319 -49.304148) (xy 64.528817 -49.318195)
			(xy 64.6014 -49.340081) (xy 64.671246 -49.369558) (xy 64.737563 -49.406293) (xy 64.799599 -49.449868)
			(xy 64.856652 -49.49979) (xy 64.908076 -49.555494) (xy 64.953287 -49.616349) (xy 64.991774 -49.681664)
			(xy 65.0231 -49.7507) (xy 65.04691 -49.822675) (xy 65.062935 -49.896773) (xy 65.070994 -49.972154)
			(xy 65.071498 -50.01006) (xy 66.187577 -50.01006) (xy 66.191612 -49.934356) (xy 66.203671 -49.859511)
			(xy 66.223617 -49.78637) (xy 66.251224 -49.715765) (xy 66.28618 -49.648494) (xy 66.328088 -49.585319)
			(xy 66.376474 -49.526957) (xy 66.43079 -49.474069) (xy 66.490419 -49.427254) (xy 66.554687 -49.387042)
			(xy 66.622864 -49.35389) (xy 66.69418 -49.328172) (xy 66.767825 -49.31018) (xy 66.842965 -49.300118)
			(xy 66.918749 -49.298099) (xy 66.994319 -49.304148) (xy 67.068817 -49.318195) (xy 67.1414 -49.340081)
			(xy 67.211246 -49.369558) (xy 67.277563 -49.406293) (xy 67.339599 -49.449868) (xy 67.396652 -49.49979)
			(xy 67.448076 -49.555494) (xy 67.493287 -49.616349) (xy 67.531774 -49.681664) (xy 67.5631 -49.7507)
			(xy 67.58691 -49.822675) (xy 67.602935 -49.896773) (xy 67.610994 -49.972154) (xy 67.611498 -50.01006)
			(xy 68.727577 -50.01006) (xy 68.731612 -49.934356) (xy 68.743671 -49.859511) (xy 68.763617 -49.78637)
			(xy 68.791224 -49.715765) (xy 68.82618 -49.648494) (xy 68.868088 -49.585319) (xy 68.916474 -49.526957)
			(xy 68.97079 -49.474069) (xy 69.030419 -49.427254) (xy 69.094687 -49.387042) (xy 69.162864 -49.35389)
			(xy 69.23418 -49.328172) (xy 69.307825 -49.31018) (xy 69.382965 -49.300118) (xy 69.458749 -49.298099)
			(xy 69.534319 -49.304148) (xy 69.608817 -49.318195) (xy 69.6814 -49.340081) (xy 69.751246 -49.369558)
			(xy 69.817563 -49.406293) (xy 69.879599 -49.449868) (xy 69.936652 -49.49979) (xy 69.988076 -49.555494)
			(xy 70.033287 -49.616349) (xy 70.071774 -49.681664) (xy 70.1031 -49.7507) (xy 70.12691 -49.822675)
			(xy 70.142935 -49.896773) (xy 70.150994 -49.972154) (xy 70.151498 -50.01006) (xy 71.267577 -50.01006)
			(xy 71.271612 -49.934356) (xy 71.283671 -49.859511) (xy 71.303617 -49.78637) (xy 71.331224 -49.715765)
			(xy 71.36618 -49.648494) (xy 71.408088 -49.585319) (xy 71.456474 -49.526957) (xy 71.51079 -49.474069)
			(xy 71.570419 -49.427254) (xy 71.634687 -49.387042) (xy 71.702864 -49.35389) (xy 71.77418 -49.328172)
			(xy 71.847825 -49.31018) (xy 71.922965 -49.300118) (xy 71.998749 -49.298099) (xy 72.074319 -49.304148)
			(xy 72.148817 -49.318195) (xy 72.2214 -49.340081) (xy 72.291246 -49.369558) (xy 72.357563 -49.406293)
			(xy 72.419599 -49.449868) (xy 72.476652 -49.49979) (xy 72.528076 -49.555494) (xy 72.573287 -49.616349)
			(xy 72.611774 -49.681664) (xy 72.6431 -49.7507) (xy 72.66691 -49.822675) (xy 72.682935 -49.896773)
			(xy 72.690994 -49.972154) (xy 72.691498 -50.01006) (xy 73.807577 -50.01006) (xy 73.811612 -49.934356)
			(xy 73.823671 -49.859511) (xy 73.843617 -49.78637) (xy 73.871224 -49.715765) (xy 73.90618 -49.648494)
			(xy 73.948088 -49.585319) (xy 73.996474 -49.526957) (xy 74.05079 -49.474069) (xy 74.110419 -49.427254)
			(xy 74.174687 -49.387042) (xy 74.242864 -49.35389) (xy 74.31418 -49.328172) (xy 74.387825 -49.31018)
			(xy 74.462965 -49.300118) (xy 74.538749 -49.298099) (xy 74.614319 -49.304148) (xy 74.688817 -49.318195)
			(xy 74.7614 -49.340081) (xy 74.831246 -49.369558) (xy 74.897563 -49.406293) (xy 74.959599 -49.449868)
			(xy 75.016652 -49.49979) (xy 75.068076 -49.555494) (xy 75.113287 -49.616349) (xy 75.151774 -49.681664)
			(xy 75.1831 -49.7507) (xy 75.20691 -49.822675) (xy 75.222935 -49.896773) (xy 75.230994 -49.972154)
			(xy 75.231498 -50.01006) (xy 76.347577 -50.01006) (xy 76.351612 -49.934356) (xy 76.363671 -49.859511)
			(xy 76.383617 -49.78637) (xy 76.411224 -49.715765) (xy 76.44618 -49.648494) (xy 76.488088 -49.585319)
			(xy 76.536474 -49.526957) (xy 76.59079 -49.474069) (xy 76.650419 -49.427254) (xy 76.714687 -49.387042)
			(xy 76.782864 -49.35389) (xy 76.85418 -49.328172) (xy 76.927825 -49.31018) (xy 77.002965 -49.300118)
			(xy 77.078749 -49.298099) (xy 77.154319 -49.304148) (xy 77.228817 -49.318195) (xy 77.3014 -49.340081)
			(xy 77.371246 -49.369558) (xy 77.437563 -49.406293) (xy 77.499599 -49.449868) (xy 77.556652 -49.49979)
			(xy 77.608076 -49.555494) (xy 77.653287 -49.616349) (xy 77.691774 -49.681664) (xy 77.7231 -49.7507)
			(xy 77.74691 -49.822675) (xy 77.762935 -49.896773) (xy 77.770994 -49.972154) (xy 77.771498 -50.01006)
			(xy 78.887577 -50.01006) (xy 78.891612 -49.934356) (xy 78.903671 -49.859511) (xy 78.923617 -49.78637)
			(xy 78.951224 -49.715765) (xy 78.98618 -49.648494) (xy 79.028088 -49.585319) (xy 79.076474 -49.526957)
			(xy 79.13079 -49.474069) (xy 79.190419 -49.427254) (xy 79.254687 -49.387042) (xy 79.322864 -49.35389)
			(xy 79.39418 -49.328172) (xy 79.467825 -49.31018) (xy 79.542965 -49.300118) (xy 79.618749 -49.298099)
			(xy 79.694319 -49.304148) (xy 79.768817 -49.318195) (xy 79.8414 -49.340081) (xy 79.911246 -49.369558)
			(xy 79.977563 -49.406293) (xy 80.039599 -49.449868) (xy 80.096652 -49.49979) (xy 80.148076 -49.555494)
			(xy 80.193287 -49.616349) (xy 80.231774 -49.681664) (xy 80.2631 -49.7507) (xy 80.28691 -49.822675)
			(xy 80.302935 -49.896773) (xy 80.310994 -49.972154) (xy 80.311498 -50.01006) (xy 81.427577 -50.01006)
			(xy 81.431612 -49.934356) (xy 81.443671 -49.859511) (xy 81.463617 -49.78637) (xy 81.491224 -49.715765)
			(xy 81.52618 -49.648494) (xy 81.568088 -49.585319) (xy 81.616474 -49.526957) (xy 81.67079 -49.474069)
			(xy 81.730419 -49.427254) (xy 81.794687 -49.387042) (xy 81.862864 -49.35389) (xy 81.93418 -49.328172)
			(xy 82.007825 -49.31018) (xy 82.082965 -49.300118) (xy 82.158749 -49.298099) (xy 82.234319 -49.304148)
			(xy 82.308817 -49.318195) (xy 82.3814 -49.340081) (xy 82.451246 -49.369558) (xy 82.517563 -49.406293)
			(xy 82.579599 -49.449868) (xy 82.636652 -49.49979) (xy 82.688076 -49.555494) (xy 82.733287 -49.616349)
			(xy 82.771774 -49.681664) (xy 82.8031 -49.7507) (xy 82.82691 -49.822675) (xy 82.842935 -49.896773)
			(xy 82.850994 -49.972154) (xy 82.851498 -50.01006) (xy 82.850994 -50.047966) (xy 82.842935 -50.123347)
			(xy 82.82691 -50.197445) (xy 82.8031 -50.26942) (xy 82.771774 -50.338456) (xy 82.733287 -50.403771)
			(xy 82.688076 -50.464626) (xy 82.636652 -50.52033) (xy 82.579599 -50.570252) (xy 82.517563 -50.613827)
			(xy 82.451246 -50.650562) (xy 82.3814 -50.680039) (xy 82.308817 -50.701925) (xy 82.234319 -50.715972)
			(xy 82.158749 -50.722021) (xy 82.082965 -50.720002) (xy 82.007825 -50.70994) (xy 81.93418 -50.691948)
			(xy 81.862864 -50.66623) (xy 81.794687 -50.633078) (xy 81.730419 -50.592866) (xy 81.67079 -50.546051)
			(xy 81.616474 -50.493163) (xy 81.568088 -50.434801) (xy 81.52618 -50.371626) (xy 81.491224 -50.304355)
			(xy 81.463617 -50.23375) (xy 81.443671 -50.160609) (xy 81.431612 -50.085764) (xy 81.427577 -50.01006)
			(xy 80.311498 -50.01006) (xy 80.310994 -50.047966) (xy 80.302935 -50.123347) (xy 80.28691 -50.197445)
			(xy 80.2631 -50.26942) (xy 80.231774 -50.338456) (xy 80.193287 -50.403771) (xy 80.148076 -50.464626)
			(xy 80.096652 -50.52033) (xy 80.039599 -50.570252) (xy 79.977563 -50.613827) (xy 79.911246 -50.650562)
			(xy 79.8414 -50.680039) (xy 79.768817 -50.701925) (xy 79.694319 -50.715972) (xy 79.618749 -50.722021)
			(xy 79.542965 -50.720002) (xy 79.467825 -50.70994) (xy 79.39418 -50.691948) (xy 79.322864 -50.66623)
			(xy 79.254687 -50.633078) (xy 79.190419 -50.592866) (xy 79.13079 -50.546051) (xy 79.076474 -50.493163)
			(xy 79.028088 -50.434801) (xy 78.98618 -50.371626) (xy 78.951224 -50.304355) (xy 78.923617 -50.23375)
			(xy 78.903671 -50.160609) (xy 78.891612 -50.085764) (xy 78.887577 -50.01006) (xy 77.771498 -50.01006)
			(xy 77.770994 -50.047966) (xy 77.762935 -50.123347) (xy 77.74691 -50.197445) (xy 77.7231 -50.26942)
			(xy 77.691774 -50.338456) (xy 77.653287 -50.403771) (xy 77.608076 -50.464626) (xy 77.556652 -50.52033)
			(xy 77.499599 -50.570252) (xy 77.437563 -50.613827) (xy 77.371246 -50.650562) (xy 77.3014 -50.680039)
			(xy 77.228817 -50.701925) (xy 77.154319 -50.715972) (xy 77.078749 -50.722021) (xy 77.002965 -50.720002)
			(xy 76.927825 -50.70994) (xy 76.85418 -50.691948) (xy 76.782864 -50.66623) (xy 76.714687 -50.633078)
			(xy 76.650419 -50.592866) (xy 76.59079 -50.546051) (xy 76.536474 -50.493163) (xy 76.488088 -50.434801)
			(xy 76.44618 -50.371626) (xy 76.411224 -50.304355) (xy 76.383617 -50.23375) (xy 76.363671 -50.160609)
			(xy 76.351612 -50.085764) (xy 76.347577 -50.01006) (xy 75.231498 -50.01006) (xy 75.230994 -50.047966)
			(xy 75.222935 -50.123347) (xy 75.20691 -50.197445) (xy 75.1831 -50.26942) (xy 75.151774 -50.338456)
			(xy 75.113287 -50.403771) (xy 75.068076 -50.464626) (xy 75.016652 -50.52033) (xy 74.959599 -50.570252)
			(xy 74.897563 -50.613827) (xy 74.831246 -50.650562) (xy 74.7614 -50.680039) (xy 74.688817 -50.701925)
			(xy 74.614319 -50.715972) (xy 74.538749 -50.722021) (xy 74.462965 -50.720002) (xy 74.387825 -50.70994)
			(xy 74.31418 -50.691948) (xy 74.242864 -50.66623) (xy 74.174687 -50.633078) (xy 74.110419 -50.592866)
			(xy 74.05079 -50.546051) (xy 73.996474 -50.493163) (xy 73.948088 -50.434801) (xy 73.90618 -50.371626)
			(xy 73.871224 -50.304355) (xy 73.843617 -50.23375) (xy 73.823671 -50.160609) (xy 73.811612 -50.085764)
			(xy 73.807577 -50.01006) (xy 72.691498 -50.01006) (xy 72.690994 -50.047966) (xy 72.682935 -50.123347)
			(xy 72.66691 -50.197445) (xy 72.6431 -50.26942) (xy 72.611774 -50.338456) (xy 72.573287 -50.403771)
			(xy 72.528076 -50.464626) (xy 72.476652 -50.52033) (xy 72.419599 -50.570252) (xy 72.357563 -50.613827)
			(xy 72.291246 -50.650562) (xy 72.2214 -50.680039) (xy 72.148817 -50.701925) (xy 72.074319 -50.715972)
			(xy 71.998749 -50.722021) (xy 71.922965 -50.720002) (xy 71.847825 -50.70994) (xy 71.77418 -50.691948)
			(xy 71.702864 -50.66623) (xy 71.634687 -50.633078) (xy 71.570419 -50.592866) (xy 71.51079 -50.546051)
			(xy 71.456474 -50.493163) (xy 71.408088 -50.434801) (xy 71.36618 -50.371626) (xy 71.331224 -50.304355)
			(xy 71.303617 -50.23375) (xy 71.283671 -50.160609) (xy 71.271612 -50.085764) (xy 71.267577 -50.01006)
			(xy 70.151498 -50.01006) (xy 70.150994 -50.047966) (xy 70.142935 -50.123347) (xy 70.12691 -50.197445)
			(xy 70.1031 -50.26942) (xy 70.071774 -50.338456) (xy 70.033287 -50.403771) (xy 69.988076 -50.464626)
			(xy 69.936652 -50.52033) (xy 69.879599 -50.570252) (xy 69.817563 -50.613827) (xy 69.751246 -50.650562)
			(xy 69.6814 -50.680039) (xy 69.608817 -50.701925) (xy 69.534319 -50.715972) (xy 69.458749 -50.722021)
			(xy 69.382965 -50.720002) (xy 69.307825 -50.70994) (xy 69.23418 -50.691948) (xy 69.162864 -50.66623)
			(xy 69.094687 -50.633078) (xy 69.030419 -50.592866) (xy 68.97079 -50.546051) (xy 68.916474 -50.493163)
			(xy 68.868088 -50.434801) (xy 68.82618 -50.371626) (xy 68.791224 -50.304355) (xy 68.763617 -50.23375)
			(xy 68.743671 -50.160609) (xy 68.731612 -50.085764) (xy 68.727577 -50.01006) (xy 67.611498 -50.01006)
			(xy 67.610994 -50.047966) (xy 67.602935 -50.123347) (xy 67.58691 -50.197445) (xy 67.5631 -50.26942)
			(xy 67.531774 -50.338456) (xy 67.493287 -50.403771) (xy 67.448076 -50.464626) (xy 67.396652 -50.52033)
			(xy 67.339599 -50.570252) (xy 67.277563 -50.613827) (xy 67.211246 -50.650562) (xy 67.1414 -50.680039)
			(xy 67.068817 -50.701925) (xy 66.994319 -50.715972) (xy 66.918749 -50.722021) (xy 66.842965 -50.720002)
			(xy 66.767825 -50.70994) (xy 66.69418 -50.691948) (xy 66.622864 -50.66623) (xy 66.554687 -50.633078)
			(xy 66.490419 -50.592866) (xy 66.43079 -50.546051) (xy 66.376474 -50.493163) (xy 66.328088 -50.434801)
			(xy 66.28618 -50.371626) (xy 66.251224 -50.304355) (xy 66.223617 -50.23375) (xy 66.203671 -50.160609)
			(xy 66.191612 -50.085764) (xy 66.187577 -50.01006) (xy 65.071498 -50.01006) (xy 65.070994 -50.047966)
			(xy 65.062935 -50.123347) (xy 65.04691 -50.197445) (xy 65.0231 -50.26942) (xy 64.991774 -50.338456)
			(xy 64.953287 -50.403771) (xy 64.908076 -50.464626) (xy 64.856652 -50.52033) (xy 64.799599 -50.570252)
			(xy 64.737563 -50.613827) (xy 64.671246 -50.650562) (xy 64.6014 -50.680039) (xy 64.528817 -50.701925)
			(xy 64.454319 -50.715972) (xy 64.378749 -50.722021) (xy 64.302965 -50.720002) (xy 64.227825 -50.70994)
			(xy 64.15418 -50.691948) (xy 64.082864 -50.66623) (xy 64.014687 -50.633078) (xy 63.950419 -50.592866)
			(xy 63.89079 -50.546051) (xy 63.836474 -50.493163) (xy 63.788088 -50.434801) (xy 63.74618 -50.371626)
			(xy 63.711224 -50.304355) (xy 63.683617 -50.23375) (xy 63.663671 -50.160609) (xy 63.651612 -50.085764)
			(xy 63.647577 -50.01006) (xy 42.50107 -50.01006) (xy 42.515537 -50.020272) (xy 42.604599 -50.09273)
			(xy 42.68851 -50.171096) (xy 42.766876 -50.255007) (xy 42.839334 -50.344069) (xy 42.905545 -50.437869)
			(xy 42.9652 -50.535968) (xy 43.018022 -50.63791) (xy 43.063764 -50.743218) (xy 43.102213 -50.851403)
			(xy 43.13319 -50.96196) (xy 43.156549 -51.074372) (xy 43.172183 -51.188117) (xy 43.180018 -51.302663)
			(xy 43.180508 -51.36007) (xy 43.180381 -51.393251) (xy 43.177842 -51.459565) (xy 43.175428 -51.492658)
			(xy 43.170272 -51.550942) (xy 43.152948 -51.666671) (xy 43.127616 -51.780914) (xy 43.094401 -51.893119)
			(xy 43.053462 -52.002742) (xy 43.004999 -52.109253) (xy 42.949245 -52.212135) (xy 42.886471 -52.310891)
			(xy 42.816981 -52.405042) (xy 42.741111 -52.494132) (xy 42.659229 -52.577729) (xy 42.571732 -52.65543)
			(xy 42.500813 -52.71008) (xy 63.647577 -52.71008) (xy 63.651612 -52.634376) (xy 63.663671 -52.559531)
			(xy 63.683617 -52.48639) (xy 63.711224 -52.415785) (xy 63.74618 -52.348514) (xy 63.788088 -52.285339)
			(xy 63.836474 -52.226977) (xy 63.89079 -52.174089) (xy 63.950419 -52.127274) (xy 64.014687 -52.087062)
			(xy 64.082864 -52.05391) (xy 64.15418 -52.028192) (xy 64.227825 -52.0102) (xy 64.302965 -52.000138)
			(xy 64.378749 -51.998119) (xy 64.454319 -52.004168) (xy 64.528817 -52.018215) (xy 64.6014 -52.040101)
			(xy 64.671246 -52.069578) (xy 64.737563 -52.106313) (xy 64.799599 -52.149888) (xy 64.856652 -52.19981)
			(xy 64.908076 -52.255514) (xy 64.953287 -52.316369) (xy 64.991774 -52.381684) (xy 65.0231 -52.45072)
			(xy 65.04691 -52.522695) (xy 65.062935 -52.596793) (xy 65.070994 -52.672174) (xy 65.071498 -52.71008)
			(xy 66.187577 -52.71008) (xy 66.191612 -52.634376) (xy 66.203671 -52.559531) (xy 66.223617 -52.48639)
			(xy 66.251224 -52.415785) (xy 66.28618 -52.348514) (xy 66.328088 -52.285339) (xy 66.376474 -52.226977)
			(xy 66.43079 -52.174089) (xy 66.490419 -52.127274) (xy 66.554687 -52.087062) (xy 66.622864 -52.05391)
			(xy 66.69418 -52.028192) (xy 66.767825 -52.0102) (xy 66.842965 -52.000138) (xy 66.918749 -51.998119)
			(xy 66.994319 -52.004168) (xy 67.068817 -52.018215) (xy 67.1414 -52.040101) (xy 67.211246 -52.069578)
			(xy 67.277563 -52.106313) (xy 67.339599 -52.149888) (xy 67.396652 -52.19981) (xy 67.448076 -52.255514)
			(xy 67.493287 -52.316369) (xy 67.531774 -52.381684) (xy 67.5631 -52.45072) (xy 67.58691 -52.522695)
			(xy 67.602935 -52.596793) (xy 67.610994 -52.672174) (xy 67.611498 -52.71008) (xy 68.727577 -52.71008)
			(xy 68.731612 -52.634376) (xy 68.743671 -52.559531) (xy 68.763617 -52.48639) (xy 68.791224 -52.415785)
			(xy 68.82618 -52.348514) (xy 68.868088 -52.285339) (xy 68.916474 -52.226977) (xy 68.97079 -52.174089)
			(xy 69.030419 -52.127274) (xy 69.094687 -52.087062) (xy 69.162864 -52.05391) (xy 69.23418 -52.028192)
			(xy 69.307825 -52.0102) (xy 69.382965 -52.000138) (xy 69.458749 -51.998119) (xy 69.534319 -52.004168)
			(xy 69.608817 -52.018215) (xy 69.6814 -52.040101) (xy 69.751246 -52.069578) (xy 69.817563 -52.106313)
			(xy 69.879599 -52.149888) (xy 69.936652 -52.19981) (xy 69.988076 -52.255514) (xy 70.033287 -52.316369)
			(xy 70.071774 -52.381684) (xy 70.1031 -52.45072) (xy 70.12691 -52.522695) (xy 70.142935 -52.596793)
			(xy 70.150994 -52.672174) (xy 70.151498 -52.71008) (xy 71.267577 -52.71008) (xy 71.271612 -52.634376)
			(xy 71.283671 -52.559531) (xy 71.303617 -52.48639) (xy 71.331224 -52.415785) (xy 71.36618 -52.348514)
			(xy 71.408088 -52.285339) (xy 71.456474 -52.226977) (xy 71.51079 -52.174089) (xy 71.570419 -52.127274)
			(xy 71.634687 -52.087062) (xy 71.702864 -52.05391) (xy 71.77418 -52.028192) (xy 71.847825 -52.0102)
			(xy 71.922965 -52.000138) (xy 71.998749 -51.998119) (xy 72.074319 -52.004168) (xy 72.148817 -52.018215)
			(xy 72.2214 -52.040101) (xy 72.291246 -52.069578) (xy 72.357563 -52.106313) (xy 72.419599 -52.149888)
			(xy 72.476652 -52.19981) (xy 72.528076 -52.255514) (xy 72.573287 -52.316369) (xy 72.611774 -52.381684)
			(xy 72.6431 -52.45072) (xy 72.66691 -52.522695) (xy 72.682935 -52.596793) (xy 72.690994 -52.672174)
			(xy 72.691498 -52.71008) (xy 73.807577 -52.71008) (xy 73.811612 -52.634376) (xy 73.823671 -52.559531)
			(xy 73.843617 -52.48639) (xy 73.871224 -52.415785) (xy 73.90618 -52.348514) (xy 73.948088 -52.285339)
			(xy 73.996474 -52.226977) (xy 74.05079 -52.174089) (xy 74.110419 -52.127274) (xy 74.174687 -52.087062)
			(xy 74.242864 -52.05391) (xy 74.31418 -52.028192) (xy 74.387825 -52.0102) (xy 74.462965 -52.000138)
			(xy 74.538749 -51.998119) (xy 74.614319 -52.004168) (xy 74.688817 -52.018215) (xy 74.7614 -52.040101)
			(xy 74.831246 -52.069578) (xy 74.897563 -52.106313) (xy 74.959599 -52.149888) (xy 75.016652 -52.19981)
			(xy 75.068076 -52.255514) (xy 75.113287 -52.316369) (xy 75.151774 -52.381684) (xy 75.1831 -52.45072)
			(xy 75.20691 -52.522695) (xy 75.222935 -52.596793) (xy 75.230994 -52.672174) (xy 75.231498 -52.71008)
			(xy 76.347577 -52.71008) (xy 76.351612 -52.634376) (xy 76.363671 -52.559531) (xy 76.383617 -52.48639)
			(xy 76.411224 -52.415785) (xy 76.44618 -52.348514) (xy 76.488088 -52.285339) (xy 76.536474 -52.226977)
			(xy 76.59079 -52.174089) (xy 76.650419 -52.127274) (xy 76.714687 -52.087062) (xy 76.782864 -52.05391)
			(xy 76.85418 -52.028192) (xy 76.927825 -52.0102) (xy 77.002965 -52.000138) (xy 77.078749 -51.998119)
			(xy 77.154319 -52.004168) (xy 77.228817 -52.018215) (xy 77.3014 -52.040101) (xy 77.371246 -52.069578)
			(xy 77.437563 -52.106313) (xy 77.499599 -52.149888) (xy 77.556652 -52.19981) (xy 77.608076 -52.255514)
			(xy 77.653287 -52.316369) (xy 77.691774 -52.381684) (xy 77.7231 -52.45072) (xy 77.74691 -52.522695)
			(xy 77.762935 -52.596793) (xy 77.770994 -52.672174) (xy 77.771498 -52.71008) (xy 78.887577 -52.71008)
			(xy 78.891612 -52.634376) (xy 78.903671 -52.559531) (xy 78.923617 -52.48639) (xy 78.951224 -52.415785)
			(xy 78.98618 -52.348514) (xy 79.028088 -52.285339) (xy 79.076474 -52.226977) (xy 79.13079 -52.174089)
			(xy 79.190419 -52.127274) (xy 79.254687 -52.087062) (xy 79.322864 -52.05391) (xy 79.39418 -52.028192)
			(xy 79.467825 -52.0102) (xy 79.542965 -52.000138) (xy 79.618749 -51.998119) (xy 79.694319 -52.004168)
			(xy 79.768817 -52.018215) (xy 79.8414 -52.040101) (xy 79.911246 -52.069578) (xy 79.977563 -52.106313)
			(xy 80.039599 -52.149888) (xy 80.096652 -52.19981) (xy 80.148076 -52.255514) (xy 80.193287 -52.316369)
			(xy 80.231774 -52.381684) (xy 80.2631 -52.45072) (xy 80.28691 -52.522695) (xy 80.302935 -52.596793)
			(xy 80.310994 -52.672174) (xy 80.311498 -52.71008) (xy 81.427577 -52.71008) (xy 81.431612 -52.634376)
			(xy 81.443671 -52.559531) (xy 81.463617 -52.48639) (xy 81.491224 -52.415785) (xy 81.52618 -52.348514)
			(xy 81.568088 -52.285339) (xy 81.616474 -52.226977) (xy 81.67079 -52.174089) (xy 81.730419 -52.127274)
			(xy 81.794687 -52.087062) (xy 81.862864 -52.05391) (xy 81.93418 -52.028192) (xy 82.007825 -52.0102)
			(xy 82.082965 -52.000138) (xy 82.158749 -51.998119) (xy 82.234319 -52.004168) (xy 82.308817 -52.018215)
			(xy 82.3814 -52.040101) (xy 82.451246 -52.069578) (xy 82.517563 -52.106313) (xy 82.579599 -52.149888)
			(xy 82.636652 -52.19981) (xy 82.688076 -52.255514) (xy 82.733287 -52.316369) (xy 82.771774 -52.381684)
			(xy 82.8031 -52.45072) (xy 82.82691 -52.522695) (xy 82.842935 -52.596793) (xy 82.850994 -52.672174)
			(xy 82.851498 -52.71008) (xy 82.850994 -52.747986) (xy 82.842935 -52.823367) (xy 82.82691 -52.897465)
			(xy 82.8031 -52.96944) (xy 82.771774 -53.038476) (xy 82.733287 -53.103791) (xy 82.688076 -53.164646)
			(xy 82.636652 -53.22035) (xy 82.579599 -53.270272) (xy 82.517563 -53.313847) (xy 82.451246 -53.350582)
			(xy 82.3814 -53.380059) (xy 82.308817 -53.401945) (xy 82.234319 -53.415992) (xy 82.158749 -53.422041)
			(xy 82.082965 -53.420022) (xy 82.007825 -53.40996) (xy 81.93418 -53.391968) (xy 81.862864 -53.36625)
			(xy 81.794687 -53.333098) (xy 81.730419 -53.292886) (xy 81.67079 -53.246071) (xy 81.616474 -53.193183)
			(xy 81.568088 -53.134821) (xy 81.52618 -53.071646) (xy 81.491224 -53.004375) (xy 81.463617 -52.93377)
			(xy 81.443671 -52.860629) (xy 81.431612 -52.785784) (xy 81.427577 -52.71008) (xy 80.311498 -52.71008)
			(xy 80.310994 -52.747986) (xy 80.302935 -52.823367) (xy 80.28691 -52.897465) (xy 80.2631 -52.96944)
			(xy 80.231774 -53.038476) (xy 80.193287 -53.103791) (xy 80.148076 -53.164646) (xy 80.096652 -53.22035)
			(xy 80.039599 -53.270272) (xy 79.977563 -53.313847) (xy 79.911246 -53.350582) (xy 79.8414 -53.380059)
			(xy 79.768817 -53.401945) (xy 79.694319 -53.415992) (xy 79.618749 -53.422041) (xy 79.542965 -53.420022)
			(xy 79.467825 -53.40996) (xy 79.39418 -53.391968) (xy 79.322864 -53.36625) (xy 79.254687 -53.333098)
			(xy 79.190419 -53.292886) (xy 79.13079 -53.246071) (xy 79.076474 -53.193183) (xy 79.028088 -53.134821)
			(xy 78.98618 -53.071646) (xy 78.951224 -53.004375) (xy 78.923617 -52.93377) (xy 78.903671 -52.860629)
			(xy 78.891612 -52.785784) (xy 78.887577 -52.71008) (xy 77.771498 -52.71008) (xy 77.770994 -52.747986)
			(xy 77.762935 -52.823367) (xy 77.74691 -52.897465) (xy 77.7231 -52.96944) (xy 77.691774 -53.038476)
			(xy 77.653287 -53.103791) (xy 77.608076 -53.164646) (xy 77.556652 -53.22035) (xy 77.499599 -53.270272)
			(xy 77.437563 -53.313847) (xy 77.371246 -53.350582) (xy 77.3014 -53.380059) (xy 77.228817 -53.401945)
			(xy 77.154319 -53.415992) (xy 77.078749 -53.422041) (xy 77.002965 -53.420022) (xy 76.927825 -53.40996)
			(xy 76.85418 -53.391968) (xy 76.782864 -53.36625) (xy 76.714687 -53.333098) (xy 76.650419 -53.292886)
			(xy 76.59079 -53.246071) (xy 76.536474 -53.193183) (xy 76.488088 -53.134821) (xy 76.44618 -53.071646)
			(xy 76.411224 -53.004375) (xy 76.383617 -52.93377) (xy 76.363671 -52.860629) (xy 76.351612 -52.785784)
			(xy 76.347577 -52.71008) (xy 75.231498 -52.71008) (xy 75.230994 -52.747986) (xy 75.222935 -52.823367)
			(xy 75.20691 -52.897465) (xy 75.1831 -52.96944) (xy 75.151774 -53.038476) (xy 75.113287 -53.103791)
			(xy 75.068076 -53.164646) (xy 75.016652 -53.22035) (xy 74.959599 -53.270272) (xy 74.897563 -53.313847)
			(xy 74.831246 -53.350582) (xy 74.7614 -53.380059) (xy 74.688817 -53.401945) (xy 74.614319 -53.415992)
			(xy 74.538749 -53.422041) (xy 74.462965 -53.420022) (xy 74.387825 -53.40996) (xy 74.31418 -53.391968)
			(xy 74.242864 -53.36625) (xy 74.174687 -53.333098) (xy 74.110419 -53.292886) (xy 74.05079 -53.246071)
			(xy 73.996474 -53.193183) (xy 73.948088 -53.134821) (xy 73.90618 -53.071646) (xy 73.871224 -53.004375)
			(xy 73.843617 -52.93377) (xy 73.823671 -52.860629) (xy 73.811612 -52.785784) (xy 73.807577 -52.71008)
			(xy 72.691498 -52.71008) (xy 72.690994 -52.747986) (xy 72.682935 -52.823367) (xy 72.66691 -52.897465)
			(xy 72.6431 -52.96944) (xy 72.611774 -53.038476) (xy 72.573287 -53.103791) (xy 72.528076 -53.164646)
			(xy 72.476652 -53.22035) (xy 72.419599 -53.270272) (xy 72.357563 -53.313847) (xy 72.291246 -53.350582)
			(xy 72.2214 -53.380059) (xy 72.148817 -53.401945) (xy 72.074319 -53.415992) (xy 71.998749 -53.422041)
			(xy 71.922965 -53.420022) (xy 71.847825 -53.40996) (xy 71.77418 -53.391968) (xy 71.702864 -53.36625)
			(xy 71.634687 -53.333098) (xy 71.570419 -53.292886) (xy 71.51079 -53.246071) (xy 71.456474 -53.193183)
			(xy 71.408088 -53.134821) (xy 71.36618 -53.071646) (xy 71.331224 -53.004375) (xy 71.303617 -52.93377)
			(xy 71.283671 -52.860629) (xy 71.271612 -52.785784) (xy 71.267577 -52.71008) (xy 70.151498 -52.71008)
			(xy 70.150994 -52.747986) (xy 70.142935 -52.823367) (xy 70.12691 -52.897465) (xy 70.1031 -52.96944)
			(xy 70.071774 -53.038476) (xy 70.033287 -53.103791) (xy 69.988076 -53.164646) (xy 69.936652 -53.22035)
			(xy 69.879599 -53.270272) (xy 69.817563 -53.313847) (xy 69.751246 -53.350582) (xy 69.6814 -53.380059)
			(xy 69.608817 -53.401945) (xy 69.534319 -53.415992) (xy 69.458749 -53.422041) (xy 69.382965 -53.420022)
			(xy 69.307825 -53.40996) (xy 69.23418 -53.391968) (xy 69.162864 -53.36625) (xy 69.094687 -53.333098)
			(xy 69.030419 -53.292886) (xy 68.97079 -53.246071) (xy 68.916474 -53.193183) (xy 68.868088 -53.134821)
			(xy 68.82618 -53.071646) (xy 68.791224 -53.004375) (xy 68.763617 -52.93377) (xy 68.743671 -52.860629)
			(xy 68.731612 -52.785784) (xy 68.727577 -52.71008) (xy 67.611498 -52.71008) (xy 67.610994 -52.747986)
			(xy 67.602935 -52.823367) (xy 67.58691 -52.897465) (xy 67.5631 -52.96944) (xy 67.531774 -53.038476)
			(xy 67.493287 -53.103791) (xy 67.448076 -53.164646) (xy 67.396652 -53.22035) (xy 67.339599 -53.270272)
			(xy 67.277563 -53.313847) (xy 67.211246 -53.350582) (xy 67.1414 -53.380059) (xy 67.068817 -53.401945)
			(xy 66.994319 -53.415992) (xy 66.918749 -53.422041) (xy 66.842965 -53.420022) (xy 66.767825 -53.40996)
			(xy 66.69418 -53.391968) (xy 66.622864 -53.36625) (xy 66.554687 -53.333098) (xy 66.490419 -53.292886)
			(xy 66.43079 -53.246071) (xy 66.376474 -53.193183) (xy 66.328088 -53.134821) (xy 66.28618 -53.071646)
			(xy 66.251224 -53.004375) (xy 66.223617 -52.93377) (xy 66.203671 -52.860629) (xy 66.191612 -52.785784)
			(xy 66.187577 -52.71008) (xy 65.071498 -52.71008) (xy 65.070994 -52.747986) (xy 65.062935 -52.823367)
			(xy 65.04691 -52.897465) (xy 65.0231 -52.96944) (xy 64.991774 -53.038476) (xy 64.953287 -53.103791)
			(xy 64.908076 -53.164646) (xy 64.856652 -53.22035) (xy 64.799599 -53.270272) (xy 64.737563 -53.313847)
			(xy 64.671246 -53.350582) (xy 64.6014 -53.380059) (xy 64.528817 -53.401945) (xy 64.454319 -53.415992)
			(xy 64.378749 -53.422041) (xy 64.302965 -53.420022) (xy 64.227825 -53.40996) (xy 64.15418 -53.391968)
			(xy 64.082864 -53.36625) (xy 64.014687 -53.333098) (xy 63.950419 -53.292886) (xy 63.89079 -53.246071)
			(xy 63.836474 -53.193183) (xy 63.788088 -53.134821) (xy 63.74618 -53.071646) (xy 63.711224 -53.004375)
			(xy 63.683617 -52.93377) (xy 63.663671 -52.860629) (xy 63.651612 -52.785784) (xy 63.647577 -52.71008)
			(xy 42.500813 -52.71008) (xy 42.479042 -52.726857) (xy 42.381609 -52.791665) (xy 42.279905 -52.84954)
			(xy 42.174422 -52.900202) (xy 42.065671 -52.943404) (xy 41.954179 -52.978939) (xy 41.840485 -53.006634)
			(xy 41.725141 -53.026354) (xy 41.608704 -53.038005) (xy 41.491739 -53.04153) (xy 41.374812 -53.036912)
			(xy 41.258489 -53.024173) (xy 41.143334 -53.003375) (xy 41.029905 -52.974618) (xy 40.91875 -52.938042)
			(xy 40.810407 -52.893825) (xy 40.705403 -52.842179) (xy 40.604244 -52.783356) (xy 40.507421 -52.71764)
			(xy 40.415403 -52.645349) (xy 40.328636 -52.566834) (xy 40.247539 -52.482474) (xy 40.172506 -52.392679)
			(xy 40.103899 -52.297883) (xy 40.042051 -52.198544) (xy 39.987262 -52.095145) (xy 39.939796 -51.988186)
			(xy 39.899884 -51.878185) (xy 39.86772 -51.765674) (xy 39.843457 -51.651199) (xy 39.827215 -51.535313)
			(xy 39.819072 -51.418579) (xy 39.818564 -51.36007) (xy 17.310802 -51.36007) (xy 17.295095 -51.422368)
			(xy 17.267435 -51.499151) (xy 17.232337 -51.572831) (xy 17.190142 -51.64269) (xy 17.141264 -51.708047)
			(xy 17.086177 -51.768264) (xy 17.02542 -51.822755) (xy 16.959585 -51.870987) (xy 16.889313 -51.912491)
			(xy 16.815291 -51.946862) (xy 16.73824 -51.973764) (xy 16.658911 -51.992936) (xy 16.578077 -52.00419)
			(xy 16.496528 -52.007416) (xy 16.415059 -52.002584) (xy 16.334463 -51.989739) (xy 16.255527 -51.969009)
			(xy 16.179021 -51.940594) (xy 16.10569 -51.904771) (xy 16.03625 -51.861891) (xy 15.971377 -51.812371)
			(xy 15.911706 -51.756694) (xy 15.857816 -51.695403) (xy 15.810235 -51.629095) (xy 15.789402 -51.594004)
			(xy 15.772892 -51.565556) (xy 15.661894 -51.499008) (xy 14.788642 -51.499008) (xy 14.766742 -51.499472)
			(xy 14.723591 -51.506993) (xy 14.68237 -51.521802) (xy 14.644298 -51.543461) (xy 14.610505 -51.571327)
			(xy 14.581991 -51.604576) (xy 14.5596 -51.642221) (xy 14.543997 -51.683149) (xy 14.535644 -51.726146)
			(xy 14.534787 -51.769939) (xy 14.541453 -51.813229) (xy 14.555444 -51.854736) (xy 14.576345 -51.893228)
			(xy 14.589506 -51.910742) (xy 14.615597 -51.941674) (xy 14.662284 -52.007774) (xy 14.702284 -52.078123)
			(xy 14.735213 -52.152047) (xy 14.760755 -52.228836) (xy 14.778665 -52.307755) (xy 14.788772 -52.388048)
			(xy 14.790979 -52.468943) (xy 14.785265 -52.549667) (xy 14.771684 -52.629445) (xy 14.750367 -52.707513)
			(xy 14.721518 -52.783122) (xy 14.685413 -52.855548) (xy 14.642399 -52.924095) (xy 14.592888 -52.988108)
			(xy 14.537354 -53.046973) (xy 14.476331 -53.100125) (xy 14.410402 -53.147054) (xy 14.3402 -53.187312)
			(xy 14.303502 -53.204364) (xy 14.270736 -53.219096) (xy 14.191488 -53.335936) (xy 14.191488 -54.106572)
			(xy 15.5184 -55.433484) (xy 29.519874 -55.433484) (xy 29.519874 -55.346584) (xy 29.527892 -55.260055)
			(xy 29.54386 -55.174635) (xy 29.567641 -55.091053) (xy 29.599033 -55.010021) (xy 29.637767 -54.932232)
			(xy 29.683514 -54.858348) (xy 29.735883 -54.789001) (xy 29.794427 -54.724781) (xy 29.858647 -54.666237)
			(xy 29.927994 -54.613868) (xy 30.001878 -54.568121) (xy 30.079667 -54.529387) (xy 30.160699 -54.497995)
			(xy 30.244281 -54.474214) (xy 30.329701 -54.458246) (xy 30.41623 -54.450228) (xy 30.50313 -54.450228)
			(xy 30.589659 -54.458246) (xy 30.675079 -54.474214) (xy 30.758661 -54.497995) (xy 30.839693 -54.529387)
			(xy 30.917482 -54.568121) (xy 30.991366 -54.613868) (xy 31.060713 -54.666237) (xy 31.124933 -54.724781)
			(xy 31.183477 -54.789001) (xy 31.235846 -54.858348) (xy 31.281593 -54.932232) (xy 31.320327 -55.010021)
			(xy 31.351719 -55.091053) (xy 31.3755 -55.174635) (xy 31.391468 -55.260055) (xy 31.399486 -55.346584)
			(xy 31.399988 -55.390034) (xy 31.399486 -55.433484) (xy 34.599874 -55.433484) (xy 34.599874 -55.346584)
			(xy 34.607892 -55.260055) (xy 34.62386 -55.174635) (xy 34.647641 -55.091053) (xy 34.679033 -55.010021)
			(xy 34.717767 -54.932232) (xy 34.763514 -54.858348) (xy 34.815883 -54.789001) (xy 34.874427 -54.724781)
			(xy 34.938647 -54.666237) (xy 35.007994 -54.613868) (xy 35.081878 -54.568121) (xy 35.159667 -54.529387)
			(xy 35.240699 -54.497995) (xy 35.324281 -54.474214) (xy 35.409701 -54.458246) (xy 35.49623 -54.450228)
			(xy 35.58313 -54.450228) (xy 35.669659 -54.458246) (xy 35.755079 -54.474214) (xy 35.838661 -54.497995)
			(xy 35.919693 -54.529387) (xy 35.997482 -54.568121) (xy 36.071366 -54.613868) (xy 36.140713 -54.666237)
			(xy 36.204933 -54.724781) (xy 36.263477 -54.789001) (xy 36.315846 -54.858348) (xy 36.361593 -54.932232)
			(xy 36.400327 -55.010021) (xy 36.431719 -55.091053) (xy 36.4555 -55.174635) (xy 36.471468 -55.260055)
			(xy 36.479486 -55.346584) (xy 36.479988 -55.390034) (xy 36.479486 -55.433484) (xy 36.471468 -55.520013)
			(xy 36.4555 -55.605433) (xy 36.431719 -55.689015) (xy 36.400327 -55.770047) (xy 36.361593 -55.847836)
			(xy 36.315846 -55.92172) (xy 36.263477 -55.991067) (xy 36.204933 -56.055287) (xy 36.140713 -56.113831)
			(xy 36.071366 -56.1662) (xy 35.997482 -56.211947) (xy 35.919693 -56.250681) (xy 35.838661 -56.282073)
			(xy 35.766073 -56.302726) (xy 63.833865 -56.302726) (xy 63.837749 -56.24837) (xy 63.849329 -56.19512)
			(xy 63.86837 -56.144059) (xy 63.894484 -56.096229) (xy 63.927139 -56.052602) (xy 63.965671 -56.014066)
			(xy 64.009295 -55.981406) (xy 64.057122 -55.955287) (xy 64.108181 -55.936241) (xy 64.16143 -55.924655)
			(xy 64.215786 -55.920765) (xy 64.270142 -55.924651) (xy 64.323392 -55.936233) (xy 64.374452 -55.955275)
			(xy 64.422281 -55.981391) (xy 64.444372 -55.997348) (xy 64.463384 -56.010944) (xy 64.505267 -56.031676)
			(xy 64.550235 -56.044402) (xy 64.596772 -56.048692) (xy 64.643309 -56.044402) (xy 64.688277 -56.031676)
			(xy 64.73016 -56.010944) (xy 64.749172 -55.997348) (xy 64.771302 -55.981445) (xy 64.819127 -55.955326)
			(xy 64.870182 -55.936279) (xy 64.923429 -55.924692) (xy 64.977782 -55.920802) (xy 65.032136 -55.924687)
			(xy 65.085384 -55.936269) (xy 65.136441 -55.955311) (xy 65.184268 -55.981426) (xy 65.227892 -56.014082)
			(xy 65.266424 -56.052615) (xy 65.299079 -56.096239) (xy 65.325193 -56.144067) (xy 65.344234 -56.195125)
			(xy 65.355814 -56.248372) (xy 65.359698 -56.302726) (xy 66.063458 -56.302726) (xy 66.067342 -56.248368)
			(xy 66.078923 -56.195116) (xy 66.097964 -56.144055) (xy 66.124079 -56.096223) (xy 66.156736 -56.052595)
			(xy 66.195269 -56.014058) (xy 66.238894 -55.981398) (xy 66.286724 -55.955278) (xy 66.337784 -55.936232)
			(xy 66.391035 -55.924647) (xy 66.445393 -55.920758) (xy 66.49975 -55.924645) (xy 66.553002 -55.936228)
			(xy 66.604062 -55.955272) (xy 66.651893 -55.98139) (xy 66.673984 -55.997348) (xy 66.692996 -56.010944)
			(xy 66.734879 -56.031676) (xy 66.779847 -56.044402) (xy 66.826384 -56.048692) (xy 66.872921 -56.044402)
			(xy 66.917889 -56.031676) (xy 66.959772 -56.010944) (xy 66.978784 -55.997348) (xy 67.000914 -55.981446)
			(xy 67.048738 -55.955328) (xy 67.099792 -55.936283) (xy 67.153037 -55.924698) (xy 67.207389 -55.920809)
			(xy 67.261741 -55.924695) (xy 67.314987 -55.936277) (xy 67.366043 -55.95532) (xy 67.413868 -55.981434)
			(xy 67.45749 -56.01409) (xy 67.49602 -56.052622) (xy 67.528674 -56.096245) (xy 67.554787 -56.144072)
			(xy 67.573827 -56.195128) (xy 67.585407 -56.248374) (xy 67.589291 -56.302726) (xy 67.5854 -56.357078)
			(xy 67.573812 -56.410323) (xy 67.554765 -56.461376) (xy 67.528645 -56.509199) (xy 67.495986 -56.552818)
			(xy 67.45745 -56.591344) (xy 67.413824 -56.623994) (xy 67.365995 -56.650102) (xy 67.314937 -56.669138)
			(xy 67.261689 -56.680712) (xy 67.207336 -56.684591) (xy 67.152985 -56.680694) (xy 67.099741 -56.669102)
			(xy 67.04869 -56.65005) (xy 67.000869 -56.623925) (xy 66.978784 -56.607964) (xy 66.959772 -56.594368)
			(xy 66.917889 -56.573636) (xy 66.872921 -56.56091) (xy 66.826384 -56.55662) (xy 66.779847 -56.56091)
			(xy 66.734879 -56.573636) (xy 66.692996 -56.594368) (xy 66.673984 -56.607964) (xy 66.651937 -56.623982)
			(xy 66.60411 -56.650106) (xy 66.553052 -56.669157) (xy 66.499803 -56.680748) (xy 66.445445 -56.684642)
			(xy 66.391087 -56.680761) (xy 66.337835 -56.669183) (xy 66.286772 -56.650143) (xy 66.238939 -56.624031)
			(xy 66.195309 -56.591377) (xy 66.15677 -56.552845) (xy 66.124108 -56.509222) (xy 66.097986 -56.461393)
			(xy 66.078938 -56.410334) (xy 66.067349 -56.357084) (xy 66.063458 -56.302726) (xy 65.359698 -56.302726)
			(xy 65.355807 -56.35708) (xy 65.344219 -56.410326) (xy 65.325171 -56.461381) (xy 65.29905 -56.509205)
			(xy 65.266389 -56.552825) (xy 65.227852 -56.591352) (xy 65.184224 -56.624003) (xy 65.136393 -56.650111)
			(xy 65.085333 -56.669146) (xy 65.032084 -56.68072) (xy 64.97773 -56.684598) (xy 64.923377 -56.6807)
			(xy 64.870132 -56.669106) (xy 64.819079 -56.650052) (xy 64.771258 -56.623926) (xy 64.749172 -56.607964)
			(xy 64.73016 -56.594368) (xy 64.688277 -56.573636) (xy 64.643309 -56.56091) (xy 64.596772 -56.55662)
			(xy 64.550235 -56.56091) (xy 64.505267 -56.573636) (xy 64.463384 -56.594368) (xy 64.444372 -56.607964)
			(xy 64.422326 -56.623981) (xy 64.3745 -56.650103) (xy 64.323443 -56.669152) (xy 64.270194 -56.680742)
			(xy 64.215839 -56.684635) (xy 64.161482 -56.680753) (xy 64.108231 -56.669174) (xy 64.057171 -56.650135)
			(xy 64.009339 -56.624023) (xy 63.965711 -56.591369) (xy 63.927174 -56.552838) (xy 63.894513 -56.509216)
			(xy 63.868392 -56.461389) (xy 63.849344 -56.410331) (xy 63.837756 -56.357082) (xy 63.833865 -56.302726)
			(xy 35.766073 -56.302726) (xy 35.755079 -56.305854) (xy 35.669659 -56.321822) (xy 35.58313 -56.32984)
			(xy 35.49623 -56.32984) (xy 35.409701 -56.321822) (xy 35.324281 -56.305854) (xy 35.240699 -56.282073)
			(xy 35.159667 -56.250681) (xy 35.081878 -56.211947) (xy 35.007994 -56.1662) (xy 34.938647 -56.113831)
			(xy 34.874427 -56.055287) (xy 34.815883 -55.991067) (xy 34.763514 -55.92172) (xy 34.717767 -55.847836)
			(xy 34.679033 -55.770047) (xy 34.647641 -55.689015) (xy 34.62386 -55.605433) (xy 34.607892 -55.520013)
			(xy 34.599874 -55.433484) (xy 31.399486 -55.433484) (xy 31.391468 -55.520013) (xy 31.3755 -55.605433)
			(xy 31.351719 -55.689015) (xy 31.320327 -55.770047) (xy 31.281593 -55.847836) (xy 31.235846 -55.92172)
			(xy 31.183477 -55.991067) (xy 31.124933 -56.055287) (xy 31.060713 -56.113831) (xy 30.991366 -56.1662)
			(xy 30.917482 -56.211947) (xy 30.839693 -56.250681) (xy 30.758661 -56.282073) (xy 30.675079 -56.305854)
			(xy 30.589659 -56.321822) (xy 30.50313 -56.32984) (xy 30.41623 -56.32984) (xy 30.329701 -56.321822)
			(xy 30.244281 -56.305854) (xy 30.160699 -56.282073) (xy 30.079667 -56.250681) (xy 30.001878 -56.211947)
			(xy 29.927994 -56.1662) (xy 29.858647 -56.113831) (xy 29.794427 -56.055287) (xy 29.735883 -55.991067)
			(xy 29.683514 -55.92172) (xy 29.637767 -55.847836) (xy 29.599033 -55.770047) (xy 29.567641 -55.689015)
			(xy 29.54386 -55.605433) (xy 29.527892 -55.520013) (xy 29.519874 -55.433484) (xy 15.5184 -55.433484)
			(xy 18.0584 -57.973484) (xy 29.519874 -57.973484) (xy 29.519874 -57.886584) (xy 29.527892 -57.800055)
			(xy 29.54386 -57.714635) (xy 29.567641 -57.631053) (xy 29.599033 -57.550021) (xy 29.637767 -57.472232)
			(xy 29.683514 -57.398348) (xy 29.735883 -57.329001) (xy 29.794427 -57.264781) (xy 29.858647 -57.206237)
			(xy 29.927994 -57.153868) (xy 30.001878 -57.108121) (xy 30.079667 -57.069387) (xy 30.160699 -57.037995)
			(xy 30.244281 -57.014214) (xy 30.329701 -56.998246) (xy 30.41623 -56.990228) (xy 30.50313 -56.990228)
			(xy 30.589659 -56.998246) (xy 30.675079 -57.014214) (xy 30.758661 -57.037995) (xy 30.839693 -57.069387)
			(xy 30.917482 -57.108121) (xy 30.991366 -57.153868) (xy 31.060713 -57.206237) (xy 31.124933 -57.264781)
			(xy 31.183477 -57.329001) (xy 31.235846 -57.398348) (xy 31.281593 -57.472232) (xy 31.320327 -57.550021)
			(xy 31.351719 -57.631053) (xy 31.3755 -57.714635) (xy 31.391468 -57.800055) (xy 31.399486 -57.886584)
			(xy 31.399988 -57.930034) (xy 31.399486 -57.973484) (xy 34.599874 -57.973484) (xy 34.599874 -57.886584)
			(xy 34.607892 -57.800055) (xy 34.62386 -57.714635) (xy 34.647641 -57.631053) (xy 34.679033 -57.550021)
			(xy 34.717767 -57.472232) (xy 34.763514 -57.398348) (xy 34.815883 -57.329001) (xy 34.874427 -57.264781)
			(xy 34.938647 -57.206237) (xy 35.007994 -57.153868) (xy 35.081878 -57.108121) (xy 35.159667 -57.069387)
			(xy 35.240699 -57.037995) (xy 35.324281 -57.014214) (xy 35.409701 -56.998246) (xy 35.49623 -56.990228)
			(xy 35.58313 -56.990228) (xy 35.669659 -56.998246) (xy 35.755079 -57.014214) (xy 35.838661 -57.037995)
			(xy 35.919693 -57.069387) (xy 35.997482 -57.108121) (xy 36.071366 -57.153868) (xy 36.140713 -57.206237)
			(xy 36.204933 -57.264781) (xy 36.263477 -57.329001) (xy 36.315846 -57.398348) (xy 36.361593 -57.472232)
			(xy 36.400327 -57.550021) (xy 36.431719 -57.631053) (xy 36.4555 -57.714635) (xy 36.471468 -57.800055)
			(xy 36.479486 -57.886584) (xy 36.479988 -57.930034) (xy 36.479486 -57.973484) (xy 36.471468 -58.060013)
			(xy 36.4555 -58.145433) (xy 36.431719 -58.229015) (xy 36.400327 -58.310047) (xy 36.361593 -58.387836)
			(xy 36.315846 -58.46172) (xy 36.263477 -58.531067) (xy 36.204933 -58.595287) (xy 36.140713 -58.653831)
			(xy 36.071366 -58.7062) (xy 35.997482 -58.751947) (xy 35.919693 -58.790681) (xy 35.838661 -58.822073)
			(xy 35.755079 -58.845854) (xy 35.669659 -58.861822) (xy 35.58313 -58.86984) (xy 35.49623 -58.86984)
			(xy 35.409701 -58.861822) (xy 35.324281 -58.845854) (xy 35.240699 -58.822073) (xy 35.159667 -58.790681)
			(xy 35.081878 -58.751947) (xy 35.007994 -58.7062) (xy 34.938647 -58.653831) (xy 34.874427 -58.595287)
			(xy 34.815883 -58.531067) (xy 34.763514 -58.46172) (xy 34.717767 -58.387836) (xy 34.679033 -58.310047)
			(xy 34.647641 -58.229015) (xy 34.62386 -58.145433) (xy 34.607892 -58.060013) (xy 34.599874 -57.973484)
			(xy 31.399486 -57.973484) (xy 31.391468 -58.060013) (xy 31.3755 -58.145433) (xy 31.351719 -58.229015)
			(xy 31.320327 -58.310047) (xy 31.281593 -58.387836) (xy 31.235846 -58.46172) (xy 31.183477 -58.531067)
			(xy 31.124933 -58.595287) (xy 31.060713 -58.653831) (xy 30.991366 -58.7062) (xy 30.917482 -58.751947)
			(xy 30.839693 -58.790681) (xy 30.758661 -58.822073) (xy 30.675079 -58.845854) (xy 30.589659 -58.861822)
			(xy 30.50313 -58.86984) (xy 30.41623 -58.86984) (xy 30.329701 -58.861822) (xy 30.244281 -58.845854)
			(xy 30.160699 -58.822073) (xy 30.079667 -58.790681) (xy 30.001878 -58.751947) (xy 29.927994 -58.7062)
			(xy 29.858647 -58.653831) (xy 29.794427 -58.595287) (xy 29.735883 -58.531067) (xy 29.683514 -58.46172)
			(xy 29.637767 -58.387836) (xy 29.599033 -58.310047) (xy 29.567641 -58.229015) (xy 29.54386 -58.145433)
			(xy 29.527892 -58.060013) (xy 29.519874 -57.973484) (xy 18.0584 -57.973484) (xy 18.954496 -58.86958)
			(xy 19.029934 -58.86958) (xy 19.133874 -58.97352) (xy 63.833873 -58.97352) (xy 63.837758 -58.919165)
			(xy 63.849339 -58.865916) (xy 63.86838 -58.814857) (xy 63.894494 -58.767028) (xy 63.927149 -58.723402)
			(xy 63.965681 -58.684868) (xy 64.009304 -58.652209) (xy 64.057131 -58.626092) (xy 64.108189 -58.607047)
			(xy 64.161437 -58.595462) (xy 64.215792 -58.591573) (xy 64.270147 -58.595459) (xy 64.323395 -58.607042)
			(xy 64.374454 -58.626085) (xy 64.422282 -58.6522) (xy 64.444372 -58.668158) (xy 64.463384 -58.681754)
			(xy 64.505267 -58.702486) (xy 64.550235 -58.715212) (xy 64.596772 -58.719502) (xy 64.643309 -58.715212)
			(xy 64.688277 -58.702486) (xy 64.73016 -58.681754) (xy 64.749172 -58.668158) (xy 64.771293 -58.652242)
			(xy 64.819118 -58.626121) (xy 64.870174 -58.607073) (xy 64.923422 -58.595485) (xy 64.977776 -58.591594)
			(xy 65.032132 -58.595478) (xy 65.08538 -58.607059) (xy 65.136439 -58.626101) (xy 65.184268 -58.652216)
			(xy 65.227893 -58.684872) (xy 65.266426 -58.723405) (xy 65.299082 -58.76703) (xy 65.325197 -58.814858)
			(xy 65.34424 -58.865917) (xy 65.355821 -58.919165) (xy 65.359706 -58.97352) (xy 66.063466 -58.97352)
			(xy 66.067351 -58.919164) (xy 66.078932 -58.865913) (xy 66.097974 -58.814853) (xy 66.124089 -58.767022)
			(xy 66.156746 -58.723395) (xy 66.195279 -58.68486) (xy 66.238904 -58.652201) (xy 66.286733 -58.626083)
			(xy 66.337792 -58.607038) (xy 66.391042 -58.595454) (xy 66.445399 -58.591566) (xy 66.499755 -58.595453)
			(xy 66.553005 -58.607037) (xy 66.604065 -58.626082) (xy 66.651894 -58.652199) (xy 66.673984 -58.668158)
			(xy 66.692996 -58.681754) (xy 66.734879 -58.702486) (xy 66.779847 -58.715212) (xy 66.826384 -58.719502)
			(xy 66.872921 -58.715212) (xy 66.917889 -58.702486) (xy 66.959772 -58.681754) (xy 66.978784 -58.668158)
			(xy 67.000904 -58.652243) (xy 67.048729 -58.626124) (xy 67.099784 -58.607077) (xy 67.15303 -58.595491)
			(xy 67.207383 -58.591601) (xy 67.261737 -58.595486) (xy 67.314984 -58.607068) (xy 67.366041 -58.62611)
			(xy 67.413867 -58.652224) (xy 67.457491 -58.68488) (xy 67.496022 -58.723412) (xy 67.528678 -58.767036)
			(xy 67.554792 -58.814863) (xy 67.573833 -58.86592) (xy 67.585414 -58.919167) (xy 67.589299 -58.97352)
			(xy 67.585408 -59.027873) (xy 67.573822 -59.081119) (xy 67.554775 -59.132174) (xy 67.528655 -59.179999)
			(xy 67.495996 -59.223619) (xy 67.45746 -59.262147) (xy 67.413833 -59.294798) (xy 67.366003 -59.320907)
			(xy 67.314945 -59.339944) (xy 67.261696 -59.351519) (xy 67.207342 -59.355399) (xy 67.15299 -59.351503)
			(xy 67.099745 -59.339911) (xy 67.048692 -59.320859) (xy 67.00087 -59.294735) (xy 66.978784 -59.278774)
			(xy 66.959772 -59.265178) (xy 66.917889 -59.244446) (xy 66.872921 -59.23172) (xy 66.826384 -59.22743)
			(xy 66.779847 -59.23172) (xy 66.734879 -59.244446) (xy 66.692996 -59.265178) (xy 66.673984 -59.278774)
			(xy 66.651928 -59.294778) (xy 66.604102 -59.320901) (xy 66.553044 -59.339951) (xy 66.499796 -59.351541)
			(xy 66.445439 -59.355434) (xy 66.391082 -59.351552) (xy 66.337831 -59.339973) (xy 66.28677 -59.320934)
			(xy 66.238938 -59.294821) (xy 66.19531 -59.262167) (xy 66.156772 -59.223636) (xy 66.124111 -59.180012)
			(xy 66.097991 -59.132184) (xy 66.078944 -59.081126) (xy 66.067357 -59.027877) (xy 66.063466 -58.97352)
			(xy 65.359706 -58.97352) (xy 65.355815 -59.027875) (xy 65.344228 -59.081123) (xy 65.325181 -59.132179)
			(xy 65.29906 -59.180005) (xy 65.266399 -59.223626) (xy 65.227862 -59.262154) (xy 65.184233 -59.294806)
			(xy 65.136402 -59.320916) (xy 65.085341 -59.339952) (xy 65.032091 -59.351527) (xy 64.977736 -59.355406)
			(xy 64.923381 -59.351509) (xy 64.870135 -59.339916) (xy 64.819081 -59.320862) (xy 64.771258 -59.294736)
			(xy 64.749172 -59.278774) (xy 64.73016 -59.265178) (xy 64.688277 -59.244446) (xy 64.643309 -59.23172)
			(xy 64.596772 -59.22743) (xy 64.550235 -59.23172) (xy 64.505267 -59.244446) (xy 64.463384 -59.265178)
			(xy 64.444372 -59.278774) (xy 64.422316 -59.294777) (xy 64.374491 -59.320898) (xy 64.323435 -59.339946)
			(xy 64.270187 -59.351535) (xy 64.215833 -59.355427) (xy 64.161477 -59.351544) (xy 64.108228 -59.339965)
			(xy 64.057168 -59.320925) (xy 64.009338 -59.294813) (xy 63.965711 -59.262159) (xy 63.927176 -59.223629)
			(xy 63.894516 -59.180006) (xy 63.868397 -59.13218) (xy 63.84935 -59.081123) (xy 63.837764 -59.027875)
			(xy 63.833873 -58.97352) (xy 19.133874 -58.97352) (xy 19.315684 -59.15533) (xy 19.435064 -59.27471)
			(xy 20.384516 -60.224416) (xy 20.384516 -60.513484) (xy 29.519874 -60.513484) (xy 29.519874 -60.426584)
			(xy 29.527892 -60.340055) (xy 29.54386 -60.254635) (xy 29.567641 -60.171053) (xy 29.599033 -60.090021)
			(xy 29.637767 -60.012232) (xy 29.683514 -59.938348) (xy 29.735883 -59.869001) (xy 29.794427 -59.804781)
			(xy 29.858647 -59.746237) (xy 29.927994 -59.693868) (xy 30.001878 -59.648121) (xy 30.079667 -59.609387)
			(xy 30.160699 -59.577995) (xy 30.244281 -59.554214) (xy 30.329701 -59.538246) (xy 30.41623 -59.530228)
			(xy 30.50313 -59.530228) (xy 30.589659 -59.538246) (xy 30.675079 -59.554214) (xy 30.758661 -59.577995)
			(xy 30.839693 -59.609387) (xy 30.917482 -59.648121) (xy 30.991366 -59.693868) (xy 31.060713 -59.746237)
			(xy 31.124933 -59.804781) (xy 31.183477 -59.869001) (xy 31.235846 -59.938348) (xy 31.281593 -60.012232)
			(xy 31.320327 -60.090021) (xy 31.351719 -60.171053) (xy 31.3755 -60.254635) (xy 31.391468 -60.340055)
			(xy 31.399486 -60.426584) (xy 31.399988 -60.470034) (xy 31.399486 -60.513484) (xy 34.599874 -60.513484)
			(xy 34.599874 -60.426584) (xy 34.607892 -60.340055) (xy 34.62386 -60.254635) (xy 34.647641 -60.171053)
			(xy 34.679033 -60.090021) (xy 34.717767 -60.012232) (xy 34.763514 -59.938348) (xy 34.815883 -59.869001)
			(xy 34.874427 -59.804781) (xy 34.938647 -59.746237) (xy 35.007994 -59.693868) (xy 35.081878 -59.648121)
			(xy 35.159667 -59.609387) (xy 35.240699 -59.577995) (xy 35.324281 -59.554214) (xy 35.409701 -59.538246)
			(xy 35.49623 -59.530228) (xy 35.58313 -59.530228) (xy 35.669659 -59.538246) (xy 35.755079 -59.554214)
			(xy 35.838661 -59.577995) (xy 35.919693 -59.609387) (xy 35.997482 -59.648121) (xy 36.071366 -59.693868)
			(xy 36.140713 -59.746237) (xy 36.204933 -59.804781) (xy 36.263477 -59.869001) (xy 36.315846 -59.938348)
			(xy 36.361593 -60.012232) (xy 36.400327 -60.090021) (xy 36.431719 -60.171053) (xy 36.4555 -60.254635)
			(xy 36.471468 -60.340055) (xy 36.479486 -60.426584) (xy 36.479988 -60.470034) (xy 36.479486 -60.513484)
			(xy 36.471468 -60.600013) (xy 36.4555 -60.685433) (xy 36.431719 -60.769015) (xy 36.400327 -60.850047)
			(xy 36.361593 -60.927836) (xy 36.315846 -61.00172) (xy 36.263477 -61.071067) (xy 36.204933 -61.135287)
			(xy 36.140713 -61.193831) (xy 36.071366 -61.2462) (xy 35.997482 -61.291947) (xy 35.919693 -61.330681)
			(xy 35.838661 -61.362073) (xy 35.755079 -61.385854) (xy 35.669659 -61.401822) (xy 35.58313 -61.40984)
			(xy 35.49623 -61.40984) (xy 35.409701 -61.401822) (xy 35.324281 -61.385854) (xy 35.240699 -61.362073)
			(xy 35.159667 -61.330681) (xy 35.081878 -61.291947) (xy 35.007994 -61.2462) (xy 34.938647 -61.193831)
			(xy 34.874427 -61.135287) (xy 34.815883 -61.071067) (xy 34.763514 -61.00172) (xy 34.717767 -60.927836)
			(xy 34.679033 -60.850047) (xy 34.647641 -60.769015) (xy 34.62386 -60.685433) (xy 34.607892 -60.600013)
			(xy 34.599874 -60.513484) (xy 31.399486 -60.513484) (xy 31.391468 -60.600013) (xy 31.3755 -60.685433)
			(xy 31.351719 -60.769015) (xy 31.320327 -60.850047) (xy 31.281593 -60.927836) (xy 31.235846 -61.00172)
			(xy 31.183477 -61.071067) (xy 31.124933 -61.135287) (xy 31.060713 -61.193831) (xy 30.991366 -61.2462)
			(xy 30.917482 -61.291947) (xy 30.839693 -61.330681) (xy 30.758661 -61.362073) (xy 30.675079 -61.385854)
			(xy 30.589659 -61.401822) (xy 30.50313 -61.40984) (xy 30.41623 -61.40984) (xy 30.329701 -61.401822)
			(xy 30.244281 -61.385854) (xy 30.160699 -61.362073) (xy 30.079667 -61.330681) (xy 30.001878 -61.291947)
			(xy 29.927994 -61.2462) (xy 29.858647 -61.193831) (xy 29.794427 -61.135287) (xy 29.735883 -61.071067)
			(xy 29.683514 -61.00172) (xy 29.637767 -60.927836) (xy 29.599033 -60.850047) (xy 29.567641 -60.769015)
			(xy 29.54386 -60.685433) (xy 29.527892 -60.600013) (xy 29.519874 -60.513484) (xy 20.384516 -60.513484)
			(xy 20.384516 -61.641678) (xy 63.833929 -61.641678) (xy 63.837819 -61.587332) (xy 63.849404 -61.534092)
			(xy 63.868448 -61.483042) (xy 63.894564 -61.435223) (xy 63.927219 -61.391607) (xy 63.965749 -61.353083)
			(xy 64.00937 -61.320434) (xy 64.057193 -61.294325) (xy 64.108245 -61.275289) (xy 64.161486 -61.263711)
			(xy 64.215834 -61.259829) (xy 64.27018 -61.263721) (xy 64.32342 -61.275308) (xy 64.374469 -61.294353)
			(xy 64.422287 -61.32047) (xy 64.444372 -61.336428) (xy 64.463384 -61.350024) (xy 64.505267 -61.370756)
			(xy 64.550235 -61.383482) (xy 64.596772 -61.387772) (xy 64.643309 -61.383482) (xy 64.688277 -61.370756)
			(xy 64.73016 -61.350024) (xy 64.749172 -61.336428) (xy 64.771227 -61.320417) (xy 64.819057 -61.294287)
			(xy 64.870118 -61.275231) (xy 64.923372 -61.263636) (xy 64.977734 -61.259738) (xy 65.032098 -61.263617)
			(xy 65.085356 -61.275194) (xy 65.136424 -61.294233) (xy 65.184263 -61.320346) (xy 65.227898 -61.353002)
			(xy 65.26644 -61.391537) (xy 65.299107 -61.435164) (xy 65.325231 -61.482997) (xy 65.344282 -61.53406)
			(xy 65.355871 -61.587316) (xy 65.359762 -61.641678) (xy 66.063522 -61.641678) (xy 66.067412 -61.58733)
			(xy 66.078998 -61.534088) (xy 66.098043 -61.483038) (xy 66.124159 -61.435217) (xy 66.156816 -61.3916)
			(xy 66.195347 -61.353075) (xy 66.238969 -61.320425) (xy 66.286794 -61.294317) (xy 66.337848 -61.27528)
			(xy 66.391092 -61.263703) (xy 66.445441 -61.259822) (xy 66.499789 -61.263715) (xy 66.55303 -61.275303)
			(xy 66.604079 -61.29435) (xy 66.651899 -61.320469) (xy 66.673984 -61.336428) (xy 66.692996 -61.350024)
			(xy 66.734879 -61.370756) (xy 66.779847 -61.383482) (xy 66.826384 -61.387772) (xy 66.872921 -61.383482)
			(xy 66.917889 -61.370756) (xy 66.959772 -61.350024) (xy 66.978784 -61.336428) (xy 67.000839 -61.320418)
			(xy 67.048668 -61.29429) (xy 67.099728 -61.275235) (xy 67.152981 -61.263642) (xy 67.207341 -61.259745)
			(xy 67.261703 -61.263625) (xy 67.314959 -61.275202) (xy 67.366026 -61.294241) (xy 67.413862 -61.320355)
			(xy 67.457496 -61.35301) (xy 67.496037 -61.391544) (xy 67.528702 -61.43517) (xy 67.554825 -61.483001)
			(xy 67.573875 -61.534064) (xy 67.585464 -61.587317) (xy 67.589355 -61.641678) (xy 67.58547 -61.69604)
			(xy 67.573887 -61.749295) (xy 67.554843 -61.800359) (xy 67.528725 -61.848194) (xy 67.496065 -61.891824)
			(xy 67.457528 -61.930361) (xy 67.413899 -61.963022) (xy 67.366065 -61.989141) (xy 67.315001 -62.008186)
			(xy 67.261746 -62.019769) (xy 67.207384 -62.023655) (xy 67.153023 -62.019764) (xy 67.099769 -62.008177)
			(xy 67.048707 -61.989128) (xy 67.000875 -61.963005) (xy 66.978784 -61.947044) (xy 66.959772 -61.933448)
			(xy 66.917889 -61.912716) (xy 66.872921 -61.89999) (xy 66.826384 -61.8957) (xy 66.779847 -61.89999)
			(xy 66.734879 -61.912716) (xy 66.692996 -61.933448) (xy 66.673984 -61.947044) (xy 66.651862 -61.962954)
			(xy 66.60404 -61.989068) (xy 66.552988 -62.008109) (xy 66.499746 -62.019691) (xy 66.445397 -62.023578)
			(xy 66.391049 -62.019691) (xy 66.337807 -62.008108) (xy 66.286755 -61.989065) (xy 66.238933 -61.962951)
			(xy 66.195314 -61.930297) (xy 66.156787 -61.891767) (xy 66.124136 -61.848147) (xy 66.098025 -61.800323)
			(xy 66.078986 -61.74927) (xy 66.067406 -61.696027) (xy 66.063522 -61.641678) (xy 65.359762 -61.641678)
			(xy 65.355877 -61.696041) (xy 65.344294 -61.749298) (xy 65.325249 -61.800364) (xy 65.29913 -61.8482)
			(xy 65.266469 -61.891831) (xy 65.22793 -61.930369) (xy 65.184299 -61.96303) (xy 65.136463 -61.989149)
			(xy 65.085397 -62.008194) (xy 65.032141 -62.019777) (xy 64.977778 -62.023662) (xy 64.923415 -62.019771)
			(xy 64.87016 -62.008181) (xy 64.819096 -61.989131) (xy 64.771263 -61.963006) (xy 64.749172 -61.947044)
			(xy 64.73016 -61.933448) (xy 64.688277 -61.912716) (xy 64.643309 -61.89999) (xy 64.596772 -61.8957)
			(xy 64.550235 -61.89999) (xy 64.505267 -61.912716) (xy 64.463384 -61.933448) (xy 64.444372 -61.947044)
			(xy 64.422251 -61.962953) (xy 64.374429 -61.989065) (xy 64.323378 -62.008105) (xy 64.270138 -62.019685)
			(xy 64.215791 -62.023571) (xy 64.161444 -62.019683) (xy 64.108203 -62.008099) (xy 64.057153 -61.989057)
			(xy 64.009333 -61.962943) (xy 63.965716 -61.930289) (xy 63.927191 -61.89176) (xy 63.89454 -61.848141)
			(xy 63.86843 -61.800318) (xy 63.849392 -61.749267) (xy 63.837813 -61.696026) (xy 63.833929 -61.641678)
			(xy 20.384516 -61.641678) (xy 20.384516 -63.053484) (xy 29.519874 -63.053484) (xy 29.519874 -62.966584)
			(xy 29.527892 -62.880055) (xy 29.54386 -62.794635) (xy 29.567641 -62.711053) (xy 29.599033 -62.630021)
			(xy 29.637767 -62.552232) (xy 29.683514 -62.478348) (xy 29.735883 -62.409001) (xy 29.794427 -62.344781)
			(xy 29.858647 -62.286237) (xy 29.927994 -62.233868) (xy 30.001878 -62.188121) (xy 30.079667 -62.149387)
			(xy 30.160699 -62.117995) (xy 30.244281 -62.094214) (xy 30.329701 -62.078246) (xy 30.41623 -62.070228)
			(xy 30.50313 -62.070228) (xy 30.589659 -62.078246) (xy 30.675079 -62.094214) (xy 30.758661 -62.117995)
			(xy 30.839693 -62.149387) (xy 30.917482 -62.188121) (xy 30.991366 -62.233868) (xy 31.060713 -62.286237)
			(xy 31.124933 -62.344781) (xy 31.183477 -62.409001) (xy 31.235846 -62.478348) (xy 31.281593 -62.552232)
			(xy 31.320327 -62.630021) (xy 31.351719 -62.711053) (xy 31.3755 -62.794635) (xy 31.391468 -62.880055)
			(xy 31.399486 -62.966584) (xy 31.399988 -63.010034) (xy 31.399486 -63.053484) (xy 34.599874 -63.053484)
			(xy 34.599874 -62.966584) (xy 34.607892 -62.880055) (xy 34.62386 -62.794635) (xy 34.647641 -62.711053)
			(xy 34.679033 -62.630021) (xy 34.717767 -62.552232) (xy 34.763514 -62.478348) (xy 34.815883 -62.409001)
			(xy 34.874427 -62.344781) (xy 34.938647 -62.286237) (xy 35.007994 -62.233868) (xy 35.081878 -62.188121)
			(xy 35.159667 -62.149387) (xy 35.240699 -62.117995) (xy 35.324281 -62.094214) (xy 35.409701 -62.078246)
			(xy 35.49623 -62.070228) (xy 35.58313 -62.070228) (xy 35.669659 -62.078246) (xy 35.755079 -62.094214)
			(xy 35.838661 -62.117995) (xy 35.919693 -62.149387) (xy 35.997482 -62.188121) (xy 36.071366 -62.233868)
			(xy 36.140713 -62.286237) (xy 36.204933 -62.344781) (xy 36.263477 -62.409001) (xy 36.315846 -62.478348)
			(xy 36.361593 -62.552232) (xy 36.400327 -62.630021) (xy 36.431719 -62.711053) (xy 36.4555 -62.794635)
			(xy 36.471468 -62.880055) (xy 36.475431 -62.922827) (xy 47.525168 -62.922827) (xy 47.525168 -62.841717)
			(xy 47.533118 -62.760998) (xy 47.548941 -62.681447) (xy 47.572486 -62.603831) (xy 47.603525 -62.528895)
			(xy 47.64176 -62.457363) (xy 47.686822 -62.389923) (xy 47.738277 -62.327224) (xy 47.79563 -62.269871)
			(xy 47.858329 -62.218416) (xy 47.925769 -62.173354) (xy 47.997301 -62.135119) (xy 48.072237 -62.10408)
			(xy 48.149853 -62.080535) (xy 48.229404 -62.064712) (xy 48.310123 -62.056762) (xy 48.391233 -62.056762)
			(xy 48.471952 -62.064712) (xy 48.551503 -62.080535) (xy 48.629119 -62.10408) (xy 48.704055 -62.135119)
			(xy 48.775587 -62.173354) (xy 48.843027 -62.218416) (xy 48.905726 -62.269871) (xy 48.963079 -62.327224)
			(xy 49.014534 -62.389923) (xy 49.059596 -62.457363) (xy 49.097831 -62.528895) (xy 49.12887 -62.603831)
			(xy 49.152415 -62.681447) (xy 49.168238 -62.760998) (xy 49.176188 -62.841717) (xy 49.176686 -62.882272)
			(xy 49.176188 -62.922827) (xy 51.025288 -62.922827) (xy 51.025288 -62.841717) (xy 51.033238 -62.760998)
			(xy 51.049061 -62.681447) (xy 51.072606 -62.603831) (xy 51.103645 -62.528895) (xy 51.14188 -62.457363)
			(xy 51.186942 -62.389923) (xy 51.238397 -62.327224) (xy 51.29575 -62.269871) (xy 51.358449 -62.218416)
			(xy 51.425889 -62.173354) (xy 51.497421 -62.135119) (xy 51.572357 -62.10408) (xy 51.649973 -62.080535)
			(xy 51.729524 -62.064712) (xy 51.810243 -62.056762) (xy 51.891353 -62.056762) (xy 51.972072 -62.064712)
			(xy 52.051623 -62.080535) (xy 52.129239 -62.10408) (xy 52.204175 -62.135119) (xy 52.275707 -62.173354)
			(xy 52.343147 -62.218416) (xy 52.405846 -62.269871) (xy 52.463199 -62.327224) (xy 52.514654 -62.389923)
			(xy 52.559716 -62.457363) (xy 52.597951 -62.528895) (xy 52.62899 -62.603831) (xy 52.652535 -62.681447)
			(xy 52.668358 -62.760998) (xy 52.676308 -62.841717) (xy 52.676806 -62.882272) (xy 52.676308 -62.922827)
			(xy 52.668358 -63.003546) (xy 52.652535 -63.083097) (xy 52.62899 -63.160713) (xy 52.597951 -63.235649)
			(xy 52.559716 -63.307181) (xy 52.514654 -63.374621) (xy 52.463199 -63.43732) (xy 52.405846 -63.494673)
			(xy 52.343147 -63.546128) (xy 52.275707 -63.59119) (xy 52.204175 -63.629425) (xy 52.129239 -63.660464)
			(xy 52.051623 -63.684009) (xy 51.972072 -63.699832) (xy 51.891353 -63.707782) (xy 51.810243 -63.707782)
			(xy 51.729524 -63.699832) (xy 51.649973 -63.684009) (xy 51.572357 -63.660464) (xy 51.497421 -63.629425)
			(xy 51.425889 -63.59119) (xy 51.358449 -63.546128) (xy 51.29575 -63.494673) (xy 51.238397 -63.43732)
			(xy 51.186942 -63.374621) (xy 51.14188 -63.307181) (xy 51.103645 -63.235649) (xy 51.072606 -63.160713)
			(xy 51.049061 -63.083097) (xy 51.033238 -63.003546) (xy 51.025288 -62.922827) (xy 49.176188 -62.922827)
			(xy 49.168238 -63.003546) (xy 49.152415 -63.083097) (xy 49.12887 -63.160713) (xy 49.097831 -63.235649)
			(xy 49.059596 -63.307181) (xy 49.014534 -63.374621) (xy 48.963079 -63.43732) (xy 48.905726 -63.494673)
			(xy 48.843027 -63.546128) (xy 48.775587 -63.59119) (xy 48.704055 -63.629425) (xy 48.629119 -63.660464)
			(xy 48.551503 -63.684009) (xy 48.471952 -63.699832) (xy 48.391233 -63.707782) (xy 48.310123 -63.707782)
			(xy 48.229404 -63.699832) (xy 48.149853 -63.684009) (xy 48.072237 -63.660464) (xy 47.997301 -63.629425)
			(xy 47.925769 -63.59119) (xy 47.858329 -63.546128) (xy 47.79563 -63.494673) (xy 47.738277 -63.43732)
			(xy 47.686822 -63.374621) (xy 47.64176 -63.307181) (xy 47.603525 -63.235649) (xy 47.572486 -63.160713)
			(xy 47.548941 -63.083097) (xy 47.533118 -63.003546) (xy 47.525168 -62.922827) (xy 36.475431 -62.922827)
			(xy 36.479486 -62.966584) (xy 36.479988 -63.010034) (xy 36.479486 -63.053484) (xy 36.471468 -63.140013)
			(xy 36.4555 -63.225433) (xy 36.431719 -63.309015) (xy 36.400327 -63.390047) (xy 36.361593 -63.467836)
			(xy 36.315846 -63.54172) (xy 36.263477 -63.611067) (xy 36.204933 -63.675287) (xy 36.140713 -63.733831)
			(xy 36.071366 -63.7862) (xy 35.997482 -63.831947) (xy 35.919693 -63.870681) (xy 35.838661 -63.902073)
			(xy 35.755079 -63.925854) (xy 35.669659 -63.941822) (xy 35.58313 -63.94984) (xy 35.49623 -63.94984)
			(xy 35.409701 -63.941822) (xy 35.324281 -63.925854) (xy 35.240699 -63.902073) (xy 35.159667 -63.870681)
			(xy 35.081878 -63.831947) (xy 35.007994 -63.7862) (xy 34.938647 -63.733831) (xy 34.874427 -63.675287)
			(xy 34.815883 -63.611067) (xy 34.763514 -63.54172) (xy 34.717767 -63.467836) (xy 34.679033 -63.390047)
			(xy 34.647641 -63.309015) (xy 34.62386 -63.225433) (xy 34.607892 -63.140013) (xy 34.599874 -63.053484)
			(xy 31.399486 -63.053484) (xy 31.391468 -63.140013) (xy 31.3755 -63.225433) (xy 31.351719 -63.309015)
			(xy 31.320327 -63.390047) (xy 31.281593 -63.467836) (xy 31.235846 -63.54172) (xy 31.183477 -63.611067)
			(xy 31.124933 -63.675287) (xy 31.060713 -63.733831) (xy 30.991366 -63.7862) (xy 30.917482 -63.831947)
			(xy 30.839693 -63.870681) (xy 30.758661 -63.902073) (xy 30.675079 -63.925854) (xy 30.589659 -63.941822)
			(xy 30.50313 -63.94984) (xy 30.41623 -63.94984) (xy 30.329701 -63.941822) (xy 30.244281 -63.925854)
			(xy 30.160699 -63.902073) (xy 30.079667 -63.870681) (xy 30.001878 -63.831947) (xy 29.927994 -63.7862)
			(xy 29.858647 -63.733831) (xy 29.794427 -63.675287) (xy 29.735883 -63.611067) (xy 29.683514 -63.54172)
			(xy 29.637767 -63.467836) (xy 29.599033 -63.390047) (xy 29.567641 -63.309015) (xy 29.54386 -63.225433)
			(xy 29.527892 -63.140013) (xy 29.519874 -63.053484) (xy 20.384516 -63.053484) (xy 20.384516 -64.01328)
			(xy 63.833927 -64.01328) (xy 63.837817 -63.958933) (xy 63.849402 -63.905692) (xy 63.868446 -63.854643)
			(xy 63.894562 -63.806823) (xy 63.927217 -63.763207) (xy 63.965747 -63.724682) (xy 64.009368 -63.692033)
			(xy 64.057191 -63.665924) (xy 64.108243 -63.646887) (xy 64.161485 -63.63531) (xy 64.215833 -63.631427)
			(xy 64.270179 -63.635319) (xy 64.323419 -63.646906) (xy 64.374468 -63.665951) (xy 64.422287 -63.692068)
			(xy 64.444372 -63.708026) (xy 64.463384 -63.721622) (xy 64.505267 -63.742354) (xy 64.550235 -63.75508)
			(xy 64.596772 -63.75937) (xy 64.643309 -63.75508) (xy 64.688277 -63.742354) (xy 64.73016 -63.721622)
			(xy 64.749172 -63.708026) (xy 64.771229 -63.692018) (xy 64.819058 -63.665888) (xy 64.87012 -63.646832)
			(xy 64.923374 -63.635237) (xy 64.977736 -63.631339) (xy 65.032099 -63.635219) (xy 65.085357 -63.646796)
			(xy 65.136424 -63.665835) (xy 65.184263 -63.691948) (xy 65.227897 -63.724604) (xy 65.26644 -63.763139)
			(xy 65.299106 -63.806766) (xy 65.32523 -63.854598) (xy 65.34428 -63.905662) (xy 65.355869 -63.958917)
			(xy 65.359761 -64.01328) (xy 66.06352 -64.01328) (xy 66.06741 -63.958931) (xy 66.078996 -63.905689)
			(xy 66.098041 -63.854638) (xy 66.124157 -63.806817) (xy 66.156814 -63.7632) (xy 66.195345 -63.724674)
			(xy 66.238968 -63.692025) (xy 66.286793 -63.665916) (xy 66.337846 -63.646879) (xy 66.39109 -63.635302)
			(xy 66.445439 -63.63142) (xy 66.499788 -63.635313) (xy 66.553029 -63.646901) (xy 66.604079 -63.665948)
			(xy 66.651899 -63.692067) (xy 66.673984 -63.708026) (xy 66.692996 -63.721622) (xy 66.734879 -63.742354)
			(xy 66.779847 -63.75508) (xy 66.826384 -63.75937) (xy 66.872921 -63.75508) (xy 66.917889 -63.742354)
			(xy 66.959772 -63.721622) (xy 66.978784 -63.708026) (xy 67.000841 -63.692019) (xy 67.048669 -63.665891)
			(xy 67.09973 -63.646837) (xy 67.152982 -63.635243) (xy 67.207342 -63.631347) (xy 67.261704 -63.635227)
			(xy 67.31496 -63.646804) (xy 67.366026 -63.665843) (xy 67.413863 -63.691957) (xy 67.457495 -63.724612)
			(xy 67.496037 -63.763146) (xy 67.528701 -63.806772) (xy 67.554824 -63.854603) (xy 67.573874 -63.905665)
			(xy 67.585462 -63.958919) (xy 67.589353 -64.01328) (xy 67.585468 -64.067641) (xy 67.573885 -64.120896)
			(xy 67.554841 -64.17196) (xy 67.528723 -64.219794) (xy 67.496063 -64.263424) (xy 67.457526 -64.301961)
			(xy 67.413897 -64.334621) (xy 67.366063 -64.36074) (xy 67.314999 -64.379784) (xy 67.261744 -64.391367)
			(xy 67.207383 -64.395253) (xy 67.153022 -64.391363) (xy 67.099769 -64.379775) (xy 67.048706 -64.360726)
			(xy 67.000875 -64.334603) (xy 66.978784 -64.318642) (xy 66.959772 -64.305046) (xy 66.917889 -64.284314)
			(xy 66.872921 -64.271588) (xy 66.826384 -64.267298) (xy 66.779847 -64.271588) (xy 66.734879 -64.284314)
			(xy 66.692996 -64.305046) (xy 66.673984 -64.318642) (xy 66.651864 -64.334555) (xy 66.604042 -64.360668)
			(xy 66.55299 -64.37971) (xy 66.499747 -64.391293) (xy 66.445399 -64.39518) (xy 66.39105 -64.391292)
			(xy 66.337807 -64.37971) (xy 66.286755 -64.360667) (xy 66.238933 -64.334553) (xy 66.195314 -64.301899)
			(xy 66.156787 -64.263369) (xy 66.124135 -64.219748) (xy 66.098024 -64.171925) (xy 66.078984 -64.120872)
			(xy 66.067405 -64.067629) (xy 66.06352 -64.01328) (xy 65.359761 -64.01328) (xy 65.355875 -64.067642)
			(xy 65.344292 -64.120899) (xy 65.325247 -64.171964) (xy 65.299128 -64.2198) (xy 65.266467 -64.263431)
			(xy 65.227928 -64.301969) (xy 65.184297 -64.33463) (xy 65.136462 -64.360748) (xy 65.085396 -64.379793)
			(xy 65.032139 -64.391375) (xy 64.977776 -64.395261) (xy 64.923414 -64.391369) (xy 64.870159 -64.37978)
			(xy 64.819096 -64.360729) (xy 64.771263 -64.334604) (xy 64.749172 -64.318642) (xy 64.73016 -64.305046)
			(xy 64.688277 -64.284314) (xy 64.643309 -64.271588) (xy 64.596772 -64.267298) (xy 64.550235 -64.271588)
			(xy 64.505267 -64.284314) (xy 64.463384 -64.305046) (xy 64.444372 -64.318642) (xy 64.422253 -64.334554)
			(xy 64.374431 -64.360666) (xy 64.32338 -64.379706) (xy 64.270139 -64.391287) (xy 64.215792 -64.395173)
			(xy 64.161445 -64.391284) (xy 64.108204 -64.379701) (xy 64.057154 -64.360659) (xy 64.009333 -64.334545)
			(xy 63.965716 -64.301891) (xy 63.92719 -64.263362) (xy 63.89454 -64.219742) (xy 63.868429 -64.17192)
			(xy 63.849391 -64.120868) (xy 63.837812 -64.067627) (xy 63.833927 -64.01328) (xy 20.384516 -64.01328)
			(xy 20.384516 -65.593484) (xy 29.519874 -65.593484) (xy 29.519874 -65.506584) (xy 29.527892 -65.420055)
			(xy 29.54386 -65.334635) (xy 29.567641 -65.251053) (xy 29.599033 -65.170021) (xy 29.637767 -65.092232)
			(xy 29.683514 -65.018348) (xy 29.735883 -64.949001) (xy 29.794427 -64.884781) (xy 29.858647 -64.826237)
			(xy 29.927994 -64.773868) (xy 30.001878 -64.728121) (xy 30.079667 -64.689387) (xy 30.160699 -64.657995)
			(xy 30.244281 -64.634214) (xy 30.329701 -64.618246) (xy 30.41623 -64.610228) (xy 30.50313 -64.610228)
			(xy 30.589659 -64.618246) (xy 30.675079 -64.634214) (xy 30.758661 -64.657995) (xy 30.839693 -64.689387)
			(xy 30.917482 -64.728121) (xy 30.991366 -64.773868) (xy 31.060713 -64.826237) (xy 31.124933 -64.884781)
			(xy 31.183477 -64.949001) (xy 31.235846 -65.018348) (xy 31.281593 -65.092232) (xy 31.320327 -65.170021)
			(xy 31.351719 -65.251053) (xy 31.3755 -65.334635) (xy 31.391468 -65.420055) (xy 31.399486 -65.506584)
			(xy 31.399988 -65.550034) (xy 31.399486 -65.593484) (xy 34.599874 -65.593484) (xy 34.599874 -65.506584)
			(xy 34.607892 -65.420055) (xy 34.62386 -65.334635) (xy 34.647641 -65.251053) (xy 34.679033 -65.170021)
			(xy 34.717767 -65.092232) (xy 34.763514 -65.018348) (xy 34.815883 -64.949001) (xy 34.874427 -64.884781)
			(xy 34.938647 -64.826237) (xy 35.007994 -64.773868) (xy 35.081878 -64.728121) (xy 35.159667 -64.689387)
			(xy 35.240699 -64.657995) (xy 35.324281 -64.634214) (xy 35.409701 -64.618246) (xy 35.49623 -64.610228)
			(xy 35.58313 -64.610228) (xy 35.669659 -64.618246) (xy 35.755079 -64.634214) (xy 35.838661 -64.657995)
			(xy 35.919693 -64.689387) (xy 35.997482 -64.728121) (xy 36.071366 -64.773868) (xy 36.140713 -64.826237)
			(xy 36.204933 -64.884781) (xy 36.263477 -64.949001) (xy 36.315846 -65.018348) (xy 36.361593 -65.092232)
			(xy 36.400327 -65.170021) (xy 36.431719 -65.251053) (xy 36.4555 -65.334635) (xy 36.471468 -65.420055)
			(xy 36.479486 -65.506584) (xy 36.479988 -65.550034) (xy 36.479486 -65.593484) (xy 36.471468 -65.680013)
			(xy 36.4555 -65.765433) (xy 36.431719 -65.849015) (xy 36.400327 -65.930047) (xy 36.37736 -65.976172)
			(xy 63.833937 -65.976172) (xy 63.837828 -65.921827) (xy 63.849414 -65.868588) (xy 63.868458 -65.81754)
			(xy 63.894574 -65.769722) (xy 63.927229 -65.726108) (xy 63.965759 -65.687585) (xy 64.009379 -65.654937)
			(xy 64.057202 -65.62883) (xy 64.108253 -65.609795) (xy 64.161493 -65.598218) (xy 64.21584 -65.594337)
			(xy 64.270185 -65.59823) (xy 64.323423 -65.609817) (xy 64.374471 -65.628863) (xy 64.422288 -65.65498)
			(xy 64.444372 -65.670938) (xy 64.463384 -65.684534) (xy 64.505267 -65.705266) (xy 64.550235 -65.717992)
			(xy 64.596772 -65.722282) (xy 64.643309 -65.717992) (xy 64.688277 -65.705266) (xy 64.73016 -65.684534)
			(xy 64.749172 -65.670938) (xy 64.771218 -65.654914) (xy 64.819048 -65.628782) (xy 64.87011 -65.609725)
			(xy 64.923365 -65.598129) (xy 64.977728 -65.59423) (xy 65.032093 -65.598108) (xy 65.085352 -65.609684)
			(xy 65.136422 -65.628723) (xy 65.184262 -65.654836) (xy 65.227898 -65.687492) (xy 65.266443 -65.726027)
			(xy 65.29911 -65.769655) (xy 65.325236 -65.817488) (xy 65.344288 -65.868552) (xy 65.355878 -65.921809)
			(xy 65.35977 -65.976172) (xy 66.06353 -65.976172) (xy 66.067421 -65.921825) (xy 66.079007 -65.868585)
			(xy 66.098052 -65.817536) (xy 66.124169 -65.769716) (xy 66.156826 -65.726101) (xy 66.195357 -65.687577)
			(xy 66.238979 -65.654929) (xy 66.286803 -65.628822) (xy 66.337856 -65.609786) (xy 66.391099 -65.59821)
			(xy 66.445447 -65.59433) (xy 66.499794 -65.598224) (xy 66.553033 -65.609812) (xy 66.604082 -65.62886)
			(xy 66.6519 -65.654979) (xy 66.673984 -65.670938) (xy 66.692996 -65.684534) (xy 66.734879 -65.705266)
			(xy 66.779847 -65.717992) (xy 66.826384 -65.722282) (xy 66.872921 -65.717992) (xy 66.917889 -65.705266)
			(xy 66.959772 -65.684534) (xy 66.978784 -65.670938) (xy 67.000829 -65.654915) (xy 67.048659 -65.628785)
			(xy 67.09972 -65.609729) (xy 67.152974 -65.598135) (xy 67.207335 -65.594237) (xy 67.261698 -65.598116)
			(xy 67.314956 -65.609693) (xy 67.366023 -65.628732) (xy 67.413862 -65.654845) (xy 67.457496 -65.6875)
			(xy 67.496039 -65.726034) (xy 67.528705 -65.769661) (xy 67.55483 -65.817493) (xy 67.573881 -65.868556)
			(xy 67.585471 -65.92181) (xy 67.589363 -65.976172) (xy 67.585479 -66.030535) (xy 67.573897 -66.083791)
			(xy 67.554853 -66.134857) (xy 67.528735 -66.182693) (xy 67.496075 -66.226324) (xy 67.457538 -66.264864)
			(xy 67.413908 -66.297526) (xy 67.366074 -66.323645) (xy 67.315009 -66.342692) (xy 67.261753 -66.354276)
			(xy 67.20739 -66.358163) (xy 67.153028 -66.354273) (xy 67.099773 -66.342686) (xy 67.048709 -66.323638)
			(xy 67.000876 -66.297515) (xy 66.978784 -66.281554) (xy 66.959772 -66.267958) (xy 66.917889 -66.247226)
			(xy 66.872921 -66.2345) (xy 66.826384 -66.23021) (xy 66.779847 -66.2345) (xy 66.734879 -66.247226)
			(xy 66.692996 -66.267958) (xy 66.673984 -66.281554) (xy 66.651853 -66.297451) (xy 66.604031 -66.323563)
			(xy 66.55298 -66.342603) (xy 66.499739 -66.354184) (xy 66.445391 -66.35807) (xy 66.391044 -66.354182)
			(xy 66.337803 -66.342598) (xy 66.286753 -66.323556) (xy 66.238932 -66.297441) (xy 66.195315 -66.264787)
			(xy 66.156789 -66.226257) (xy 66.124139 -66.182637) (xy 66.098029 -66.134814) (xy 66.078992 -66.083762)
			(xy 66.067413 -66.03052) (xy 66.06353 -65.976172) (xy 65.35977 -65.976172) (xy 65.355886 -66.030537)
			(xy 65.344303 -66.083795) (xy 65.325259 -66.134862) (xy 65.29914 -66.182699) (xy 65.266479 -66.226331)
			(xy 65.22794 -66.264871) (xy 65.184308 -66.297534) (xy 65.136472 -66.323654) (xy 65.085405 -66.3427)
			(xy 65.032148 -66.354284) (xy 64.977784 -66.35817) (xy 64.92342 -66.354279) (xy 64.870163 -66.342691)
			(xy 64.819098 -66.32364) (xy 64.771264 -66.297516) (xy 64.749172 -66.281554) (xy 64.73016 -66.267958)
			(xy 64.688277 -66.247226) (xy 64.643309 -66.2345) (xy 64.596772 -66.23021) (xy 64.550235 -66.2345)
			(xy 64.505267 -66.247226) (xy 64.463384 -66.267958) (xy 64.444372 -66.281554) (xy 64.422241 -66.29745)
			(xy 64.374421 -66.32356) (xy 64.32337 -66.342599) (xy 64.270131 -66.354178) (xy 64.215785 -66.358063)
			(xy 64.161439 -66.354174) (xy 64.1082 -66.34259) (xy 64.057151 -66.323547) (xy 64.009333 -66.297433)
			(xy 63.965717 -66.264779) (xy 63.927193 -66.22625) (xy 63.894544 -66.182631) (xy 63.868435 -66.134809)
			(xy 63.849398 -66.083759) (xy 63.83782 -66.030519) (xy 63.833937 -65.976172) (xy 36.37736 -65.976172)
			(xy 36.361593 -66.007836) (xy 36.315846 -66.08172) (xy 36.263477 -66.151067) (xy 36.204933 -66.215287)
			(xy 36.140713 -66.273831) (xy 36.071366 -66.3262) (xy 35.997482 -66.371947) (xy 35.919693 -66.410681)
			(xy 35.838661 -66.442073) (xy 35.755079 -66.465854) (xy 35.669659 -66.481822) (xy 35.58313 -66.48984)
			(xy 35.49623 -66.48984) (xy 35.409701 -66.481822) (xy 35.324281 -66.465854) (xy 35.240699 -66.442073)
			(xy 35.159667 -66.410681) (xy 35.081878 -66.371947) (xy 35.007994 -66.3262) (xy 34.938647 -66.273831)
			(xy 34.874427 -66.215287) (xy 34.815883 -66.151067) (xy 34.763514 -66.08172) (xy 34.717767 -66.007836)
			(xy 34.679033 -65.930047) (xy 34.647641 -65.849015) (xy 34.62386 -65.765433) (xy 34.607892 -65.680013)
			(xy 34.599874 -65.593484) (xy 31.399486 -65.593484) (xy 31.391468 -65.680013) (xy 31.3755 -65.765433)
			(xy 31.351719 -65.849015) (xy 31.320327 -65.930047) (xy 31.281593 -66.007836) (xy 31.235846 -66.08172)
			(xy 31.183477 -66.151067) (xy 31.124933 -66.215287) (xy 31.060713 -66.273831) (xy 30.991366 -66.3262)
			(xy 30.917482 -66.371947) (xy 30.839693 -66.410681) (xy 30.758661 -66.442073) (xy 30.675079 -66.465854)
			(xy 30.589659 -66.481822) (xy 30.50313 -66.48984) (xy 30.41623 -66.48984) (xy 30.329701 -66.481822)
			(xy 30.244281 -66.465854) (xy 30.160699 -66.442073) (xy 30.079667 -66.410681) (xy 30.001878 -66.371947)
			(xy 29.927994 -66.3262) (xy 29.858647 -66.273831) (xy 29.794427 -66.215287) (xy 29.735883 -66.151067)
			(xy 29.683514 -66.08172) (xy 29.637767 -66.007836) (xy 29.599033 -65.930047) (xy 29.567641 -65.849015)
			(xy 29.54386 -65.765433) (xy 29.527892 -65.680013) (xy 29.519874 -65.593484) (xy 20.384516 -65.593484)
			(xy 20.384516 -68.133484) (xy 29.519874 -68.133484) (xy 29.519874 -68.046584) (xy 29.527892 -67.960055)
			(xy 29.54386 -67.874635) (xy 29.567641 -67.791053) (xy 29.599033 -67.710021) (xy 29.637767 -67.632232)
			(xy 29.683514 -67.558348) (xy 29.735883 -67.489001) (xy 29.794427 -67.424781) (xy 29.858647 -67.366237)
			(xy 29.927994 -67.313868) (xy 30.001878 -67.268121) (xy 30.079667 -67.229387) (xy 30.160699 -67.197995)
			(xy 30.244281 -67.174214) (xy 30.329701 -67.158246) (xy 30.41623 -67.150228) (xy 30.50313 -67.150228)
			(xy 30.589659 -67.158246) (xy 30.675079 -67.174214) (xy 30.758661 -67.197995) (xy 30.839693 -67.229387)
			(xy 30.917482 -67.268121) (xy 30.991366 -67.313868) (xy 31.060713 -67.366237) (xy 31.124933 -67.424781)
			(xy 31.183477 -67.489001) (xy 31.235846 -67.558348) (xy 31.281593 -67.632232) (xy 31.320327 -67.710021)
			(xy 31.351719 -67.791053) (xy 31.3755 -67.874635) (xy 31.391468 -67.960055) (xy 31.399486 -68.046584)
			(xy 31.399988 -68.090034) (xy 31.399486 -68.133484) (xy 34.599874 -68.133484) (xy 34.599874 -68.046584)
			(xy 34.607892 -67.960055) (xy 34.62386 -67.874635) (xy 34.647641 -67.791053) (xy 34.679033 -67.710021)
			(xy 34.717767 -67.632232) (xy 34.763514 -67.558348) (xy 34.815883 -67.489001) (xy 34.874427 -67.424781)
			(xy 34.938647 -67.366237) (xy 35.007994 -67.313868) (xy 35.081878 -67.268121) (xy 35.159667 -67.229387)
			(xy 35.240699 -67.197995) (xy 35.324281 -67.174214) (xy 35.409701 -67.158246) (xy 35.49623 -67.150228)
			(xy 35.58313 -67.150228) (xy 35.669659 -67.158246) (xy 35.755079 -67.174214) (xy 35.838661 -67.197995)
			(xy 35.919693 -67.229387) (xy 35.997482 -67.268121) (xy 36.071366 -67.313868) (xy 36.140713 -67.366237)
			(xy 36.204933 -67.424781) (xy 36.263477 -67.489001) (xy 36.278512 -67.508911) (xy 41.775639 -67.508911)
			(xy 41.779526 -67.454547) (xy 41.791111 -67.40129) (xy 41.810158 -67.350224) (xy 41.836279 -67.302388)
			(xy 41.868943 -67.258758) (xy 41.907484 -67.22022) (xy 41.951117 -67.18756) (xy 41.998955 -67.161444)
			(xy 42.050023 -67.142401) (xy 42.103281 -67.130821) (xy 42.157646 -67.126939) (xy 42.212009 -67.130834)
			(xy 42.265265 -67.142427) (xy 42.316328 -67.161482) (xy 42.364159 -67.18761) (xy 42.38625 -67.203574)
			(xy 42.405262 -67.21717) (xy 42.447145 -67.237902) (xy 42.492113 -67.250628) (xy 42.53865 -67.254918)
			(xy 42.585187 -67.250628) (xy 42.630155 -67.237902) (xy 42.672038 -67.21717) (xy 42.69105 -67.203574)
			(xy 42.713156 -67.187634) (xy 42.760984 -67.161508) (xy 42.812044 -67.142455) (xy 42.865295 -67.130863)
			(xy 42.919654 -67.126968) (xy 42.974014 -67.13085) (xy 43.027269 -67.142429) (xy 43.078333 -67.16147)
			(xy 43.126167 -67.187585) (xy 43.169797 -67.220242) (xy 43.208335 -67.258776) (xy 43.240996 -67.302404)
			(xy 43.267116 -67.350235) (xy 43.286161 -67.401298) (xy 43.297745 -67.454551) (xy 43.301632 -67.508911)
			(xy 43.297742 -67.56327) (xy 43.286155 -67.616523) (xy 43.267107 -67.667584) (xy 43.240985 -67.715414)
			(xy 43.208321 -67.75904) (xy 43.169781 -67.797572) (xy 43.126149 -67.830227) (xy 43.078313 -67.856339)
			(xy 43.027248 -67.875377) (xy 42.973993 -67.886953) (xy 42.919633 -67.890832) (xy 42.865274 -67.886934)
			(xy 42.812023 -67.875339) (xy 42.760964 -67.856283) (xy 42.713138 -67.830154) (xy 42.69105 -67.81419)
			(xy 42.672038 -67.800594) (xy 42.630155 -67.779862) (xy 42.585187 -67.767136) (xy 42.53865 -67.762846)
			(xy 42.492113 -67.767136) (xy 42.447145 -67.779862) (xy 42.405262 -67.800594) (xy 42.38625 -67.81419)
			(xy 42.364178 -67.830178) (xy 42.316348 -67.856309) (xy 42.265285 -67.875367) (xy 42.21203 -67.886963)
			(xy 42.157667 -67.890861) (xy 42.103303 -67.886982) (xy 42.050044 -67.875405) (xy 41.998975 -67.856365)
			(xy 41.951136 -67.830251) (xy 41.9075 -67.797594) (xy 41.868957 -67.759059) (xy 41.836291 -67.71543)
			(xy 41.810167 -67.667596) (xy 41.791117 -67.616531) (xy 41.779529 -67.563274) (xy 41.775639 -67.508911)
			(xy 36.278512 -67.508911) (xy 36.315846 -67.558348) (xy 36.361593 -67.632232) (xy 36.400327 -67.710021)
			(xy 36.431719 -67.791053) (xy 36.4555 -67.874635) (xy 36.471468 -67.960055) (xy 36.479486 -68.046584)
			(xy 36.479988 -68.090034) (xy 36.479644 -68.119829) (xy 63.833862 -68.119829) (xy 63.837745 -68.065472)
			(xy 63.849326 -68.012221) (xy 63.868366 -67.96116) (xy 63.89448 -67.913329) (xy 63.927135 -67.869701)
			(xy 63.965667 -67.831165) (xy 64.009291 -67.798505) (xy 64.057119 -67.772385) (xy 64.108177 -67.753338)
			(xy 64.161427 -67.741752) (xy 64.215783 -67.737862) (xy 64.27014 -67.741747) (xy 64.323391 -67.753329)
			(xy 64.374451 -67.772371) (xy 64.422281 -67.798487) (xy 64.444372 -67.814444) (xy 64.463384 -67.82804)
			(xy 64.505267 -67.848772) (xy 64.550235 -67.861498) (xy 64.596772 -67.865788) (xy 64.643309 -67.861498)
			(xy 64.688277 -67.848772) (xy 64.73016 -67.82804) (xy 64.749172 -67.814444) (xy 64.771306 -67.798546)
			(xy 64.81913 -67.772427) (xy 64.870186 -67.753381) (xy 64.923432 -67.741795) (xy 64.977785 -67.737905)
			(xy 65.032138 -67.741791) (xy 65.085385 -67.753373) (xy 65.136442 -67.772415) (xy 65.184269 -67.79853)
			(xy 65.227892 -67.831186) (xy 65.266423 -67.869719) (xy 65.299077 -67.913343) (xy 65.325191 -67.96117)
			(xy 65.344231 -68.012228) (xy 65.355811 -68.065475) (xy 65.359695 -68.119829) (xy 66.063455 -68.119829)
			(xy 66.067338 -68.06547) (xy 66.078919 -68.012218) (xy 66.09796 -67.961156) (xy 66.124075 -67.913323)
			(xy 66.156732 -67.869694) (xy 66.195265 -67.831157) (xy 66.238891 -67.798496) (xy 66.28672 -67.772377)
			(xy 66.337781 -67.75333) (xy 66.391032 -67.741744) (xy 66.44539 -67.737855) (xy 66.499748 -67.741741)
			(xy 66.553 -67.753324) (xy 66.604062 -67.772368) (xy 66.651893 -67.798486) (xy 66.673984 -67.814444)
			(xy 66.692996 -67.82804) (xy 66.734879 -67.848772) (xy 66.779847 -67.861498) (xy 66.826384 -67.865788)
			(xy 66.872921 -67.861498) (xy 66.917889 -67.848772) (xy 66.959772 -67.82804) (xy 66.978784 -67.814444)
			(xy 67.000918 -67.798547) (xy 67.048741 -67.77243) (xy 67.099795 -67.753386) (xy 67.15304 -67.741801)
			(xy 67.207392 -67.737912) (xy 67.261743 -67.741799) (xy 67.314989 -67.753381) (xy 67.366044 -67.772423)
			(xy 67.413868 -67.798538) (xy 67.45749 -67.831194) (xy 67.496019 -67.869726) (xy 67.528673 -67.913349)
			(xy 67.554785 -67.961175) (xy 67.573825 -68.012231) (xy 67.585404 -68.065477) (xy 67.589288 -68.119829)
			(xy 67.585396 -68.17418) (xy 67.573809 -68.227424) (xy 67.554761 -68.278477) (xy 67.528641 -68.3263)
			(xy 67.495982 -68.369918) (xy 67.457446 -68.408444) (xy 67.41382 -68.441093) (xy 67.365991 -68.4672)
			(xy 67.314933 -68.486235) (xy 67.261686 -68.49781) (xy 67.207334 -68.501688) (xy 67.152983 -68.497791)
			(xy 67.09974 -68.486198) (xy 67.048689 -68.467146) (xy 67.000869 -68.441021) (xy 66.978784 -68.42506)
			(xy 66.959772 -68.411464) (xy 66.917889 -68.390732) (xy 66.872921 -68.378006) (xy 66.826384 -68.373716)
			(xy 66.779847 -68.378006) (xy 66.734879 -68.390732) (xy 66.692996 -68.411464) (xy 66.673984 -68.42506)
			(xy 66.651941 -68.441083) (xy 66.604114 -68.467208) (xy 66.553056 -68.486259) (xy 66.499805 -68.497851)
			(xy 66.445448 -68.501745) (xy 66.391089 -68.497864) (xy 66.337836 -68.486286) (xy 66.286773 -68.467247)
			(xy 66.238939 -68.441135) (xy 66.195309 -68.408481) (xy 66.156769 -68.369949) (xy 66.124106 -68.326325)
			(xy 66.097984 -68.278497) (xy 66.078935 -68.227437) (xy 66.067347 -68.174187) (xy 66.063455 -68.119829)
			(xy 65.359695 -68.119829) (xy 65.355803 -68.174182) (xy 65.344215 -68.227428) (xy 65.325167 -68.278482)
			(xy 65.299046 -68.326306) (xy 65.266385 -68.369925) (xy 65.227848 -68.408451) (xy 65.18422 -68.441101)
			(xy 65.13639 -68.467209) (xy 65.08533 -68.486244) (xy 65.032081 -68.497818) (xy 64.977727 -68.501695)
			(xy 64.923375 -68.497797) (xy 64.87013 -68.486203) (xy 64.819078 -68.467149) (xy 64.771257 -68.441022)
			(xy 64.749172 -68.42506) (xy 64.73016 -68.411464) (xy 64.688277 -68.390732) (xy 64.643309 -68.378006)
			(xy 64.596772 -68.373716) (xy 64.550235 -68.378006) (xy 64.505267 -68.390732) (xy 64.463384 -68.411464)
			(xy 64.444372 -68.42506) (xy 64.422329 -68.441082) (xy 64.374503 -68.467205) (xy 64.323446 -68.486255)
			(xy 64.270197 -68.497845) (xy 64.215841 -68.501738) (xy 64.161484 -68.497856) (xy 64.108233 -68.486278)
			(xy 64.057171 -68.467239) (xy 64.009339 -68.441127) (xy 63.96571 -68.408473) (xy 63.927173 -68.369942)
			(xy 63.894511 -68.326319) (xy 63.86839 -68.278492) (xy 63.849342 -68.227434) (xy 63.837754 -68.174185)
			(xy 63.833862 -68.119829) (xy 36.479644 -68.119829) (xy 36.479486 -68.133484) (xy 36.471468 -68.220013)
			(xy 36.4555 -68.305433) (xy 36.431719 -68.389015) (xy 36.400327 -68.470047) (xy 36.361593 -68.547836)
			(xy 36.315846 -68.62172) (xy 36.263477 -68.691067) (xy 36.204933 -68.755287) (xy 36.140713 -68.813831)
			(xy 36.071366 -68.8662) (xy 35.997482 -68.911947) (xy 35.919693 -68.950681) (xy 35.838661 -68.982073)
			(xy 35.755079 -69.005854) (xy 35.669659 -69.021822) (xy 35.58313 -69.02984) (xy 35.49623 -69.02984)
			(xy 35.409701 -69.021822) (xy 35.324281 -69.005854) (xy 35.240699 -68.982073) (xy 35.159667 -68.950681)
			(xy 35.081878 -68.911947) (xy 35.007994 -68.8662) (xy 34.938647 -68.813831) (xy 34.874427 -68.755287)
			(xy 34.815883 -68.691067) (xy 34.763514 -68.62172) (xy 34.717767 -68.547836) (xy 34.679033 -68.470047)
			(xy 34.647641 -68.389015) (xy 34.62386 -68.305433) (xy 34.607892 -68.220013) (xy 34.599874 -68.133484)
			(xy 31.399486 -68.133484) (xy 31.391468 -68.220013) (xy 31.3755 -68.305433) (xy 31.351719 -68.389015)
			(xy 31.320327 -68.470047) (xy 31.281593 -68.547836) (xy 31.235846 -68.62172) (xy 31.183477 -68.691067)
			(xy 31.124933 -68.755287) (xy 31.060713 -68.813831) (xy 30.991366 -68.8662) (xy 30.917482 -68.911947)
			(xy 30.839693 -68.950681) (xy 30.758661 -68.982073) (xy 30.675079 -69.005854) (xy 30.589659 -69.021822)
			(xy 30.50313 -69.02984) (xy 30.41623 -69.02984) (xy 30.329701 -69.021822) (xy 30.244281 -69.005854)
			(xy 30.160699 -68.982073) (xy 30.079667 -68.950681) (xy 30.001878 -68.911947) (xy 29.927994 -68.8662)
			(xy 29.858647 -68.813831) (xy 29.794427 -68.755287) (xy 29.735883 -68.691067) (xy 29.683514 -68.62172)
			(xy 29.637767 -68.547836) (xy 29.599033 -68.470047) (xy 29.567641 -68.389015) (xy 29.54386 -68.305433)
			(xy 29.527892 -68.220013) (xy 29.519874 -68.133484) (xy 20.384516 -68.133484) (xy 20.384516 -70.673484)
			(xy 29.519874 -70.673484) (xy 29.519874 -70.586584) (xy 29.527892 -70.500055) (xy 29.54386 -70.414635)
			(xy 29.567641 -70.331053) (xy 29.599033 -70.250021) (xy 29.637767 -70.172232) (xy 29.683514 -70.098348)
			(xy 29.735883 -70.029001) (xy 29.794427 -69.964781) (xy 29.858647 -69.906237) (xy 29.927994 -69.853868)
			(xy 30.001878 -69.808121) (xy 30.079667 -69.769387) (xy 30.160699 -69.737995) (xy 30.244281 -69.714214)
			(xy 30.329701 -69.698246) (xy 30.41623 -69.690228) (xy 30.50313 -69.690228) (xy 30.589659 -69.698246)
			(xy 30.675079 -69.714214) (xy 30.758661 -69.737995) (xy 30.839693 -69.769387) (xy 30.917482 -69.808121)
			(xy 30.991366 -69.853868) (xy 31.060713 -69.906237) (xy 31.124933 -69.964781) (xy 31.183477 -70.029001)
			(xy 31.235846 -70.098348) (xy 31.281593 -70.172232) (xy 31.320327 -70.250021) (xy 31.351719 -70.331053)
			(xy 31.3755 -70.414635) (xy 31.391468 -70.500055) (xy 31.399486 -70.586584) (xy 31.399988 -70.630034)
			(xy 31.399486 -70.673484) (xy 34.599874 -70.673484) (xy 34.599874 -70.586584) (xy 34.607892 -70.500055)
			(xy 34.62386 -70.414635) (xy 34.647641 -70.331053) (xy 34.679033 -70.250021) (xy 34.717767 -70.172232)
			(xy 34.763514 -70.098348) (xy 34.815883 -70.029001) (xy 34.874427 -69.964781) (xy 34.938647 -69.906237)
			(xy 35.007994 -69.853868) (xy 35.081878 -69.808121) (xy 35.159667 -69.769387) (xy 35.240699 -69.737995)
			(xy 35.324281 -69.714214) (xy 35.409701 -69.698246) (xy 35.49623 -69.690228) (xy 35.58313 -69.690228)
			(xy 35.669659 -69.698246) (xy 35.755079 -69.714214) (xy 35.838661 -69.737995) (xy 35.919693 -69.769387)
			(xy 35.997482 -69.808121) (xy 36.071366 -69.853868) (xy 36.140713 -69.906237) (xy 36.204933 -69.964781)
			(xy 36.263477 -70.029001) (xy 36.315846 -70.098348) (xy 36.361593 -70.172232) (xy 36.365314 -70.179705)
			(xy 41.775647 -70.179705) (xy 41.779535 -70.125342) (xy 41.79112 -70.072086) (xy 41.810168 -70.021021)
			(xy 41.836289 -69.973187) (xy 41.868953 -69.929558) (xy 41.907494 -69.891022) (xy 41.951127 -69.858364)
			(xy 41.998964 -69.832248) (xy 42.050031 -69.813207) (xy 42.103289 -69.801628) (xy 42.157652 -69.797747)
			(xy 42.212014 -69.801643) (xy 42.265268 -69.813236) (xy 42.31633 -69.832291) (xy 42.36416 -69.85842)
			(xy 42.38625 -69.874384) (xy 42.405262 -69.88798) (xy 42.447145 -69.908712) (xy 42.492113 -69.921438)
			(xy 42.53865 -69.925728) (xy 42.585187 -69.921438) (xy 42.630155 -69.908712) (xy 42.672038 -69.88798)
			(xy 42.69105 -69.874384) (xy 42.713147 -69.858431) (xy 42.760975 -69.832303) (xy 42.812036 -69.813249)
			(xy 42.865288 -69.801656) (xy 42.919648 -69.79776) (xy 42.97401 -69.801641) (xy 43.027265 -69.81322)
			(xy 43.078331 -69.83226) (xy 43.126166 -69.858375) (xy 43.169798 -69.891032) (xy 43.208337 -69.929567)
			(xy 43.241 -69.973194) (xy 43.267121 -70.021027) (xy 43.286167 -70.07209) (xy 43.297752 -70.125344)
			(xy 43.30164 -70.179705) (xy 43.297751 -70.234066) (xy 43.286165 -70.287319) (xy 43.267117 -70.338382)
			(xy 43.240995 -70.386214) (xy 43.208331 -70.429841) (xy 43.169791 -70.468374) (xy 43.126158 -70.50103)
			(xy 43.078322 -70.527144) (xy 43.027256 -70.546183) (xy 42.974 -70.55776) (xy 42.919639 -70.56164)
			(xy 42.865279 -70.557743) (xy 42.812026 -70.546149) (xy 42.760967 -70.527093) (xy 42.713139 -70.500964)
			(xy 42.69105 -70.485) (xy 42.672038 -70.471404) (xy 42.630155 -70.450672) (xy 42.585187 -70.437946)
			(xy 42.53865 -70.433656) (xy 42.492113 -70.437946) (xy 42.447145 -70.450672) (xy 42.405262 -70.471404)
			(xy 42.38625 -70.485) (xy 42.364168 -70.500975) (xy 42.316339 -70.527105) (xy 42.265277 -70.546161)
			(xy 42.212023 -70.557756) (xy 42.157661 -70.561653) (xy 42.103298 -70.557773) (xy 42.05004 -70.546195)
			(xy 41.998973 -70.527156) (xy 41.951135 -70.501041) (xy 41.907501 -70.468384) (xy 41.868959 -70.429849)
			(xy 41.836294 -70.386221) (xy 41.810172 -70.338387) (xy 41.791123 -70.287323) (xy 41.779536 -70.234067)
			(xy 41.775647 -70.179705) (xy 36.365314 -70.179705) (xy 36.400327 -70.250021) (xy 36.431719 -70.331053)
			(xy 36.4555 -70.414635) (xy 36.471468 -70.500055) (xy 36.479486 -70.586584) (xy 36.479988 -70.630034)
			(xy 36.479486 -70.673484) (xy 36.471468 -70.760013) (xy 36.4555 -70.845433) (xy 36.431719 -70.929015)
			(xy 36.400327 -71.010047) (xy 36.361593 -71.087836) (xy 36.315846 -71.16172) (xy 36.263477 -71.231067)
			(xy 36.204933 -71.295287) (xy 36.140713 -71.353831) (xy 36.071366 -71.4062) (xy 35.997482 -71.451947)
			(xy 35.919693 -71.490681) (xy 35.838661 -71.522073) (xy 35.755079 -71.545854) (xy 35.669659 -71.561822)
			(xy 35.58313 -71.56984) (xy 35.49623 -71.56984) (xy 35.409701 -71.561822) (xy 35.324281 -71.545854)
			(xy 35.240699 -71.522073) (xy 35.159667 -71.490681) (xy 35.081878 -71.451947) (xy 35.007994 -71.4062)
			(xy 34.938647 -71.353831) (xy 34.874427 -71.295287) (xy 34.815883 -71.231067) (xy 34.763514 -71.16172)
			(xy 34.717767 -71.087836) (xy 34.679033 -71.010047) (xy 34.647641 -70.929015) (xy 34.62386 -70.845433)
			(xy 34.607892 -70.760013) (xy 34.599874 -70.673484) (xy 31.399486 -70.673484) (xy 31.391468 -70.760013)
			(xy 31.3755 -70.845433) (xy 31.351719 -70.929015) (xy 31.320327 -71.010047) (xy 31.281593 -71.087836)
			(xy 31.235846 -71.16172) (xy 31.183477 -71.231067) (xy 31.124933 -71.295287) (xy 31.060713 -71.353831)
			(xy 30.991366 -71.4062) (xy 30.917482 -71.451947) (xy 30.839693 -71.490681) (xy 30.758661 -71.522073)
			(xy 30.675079 -71.545854) (xy 30.589659 -71.561822) (xy 30.50313 -71.56984) (xy 30.41623 -71.56984)
			(xy 30.329701 -71.561822) (xy 30.244281 -71.545854) (xy 30.160699 -71.522073) (xy 30.079667 -71.490681)
			(xy 30.001878 -71.451947) (xy 29.927994 -71.4062) (xy 29.858647 -71.353831) (xy 29.794427 -71.295287)
			(xy 29.735883 -71.231067) (xy 29.683514 -71.16172) (xy 29.637767 -71.087836) (xy 29.599033 -71.010047)
			(xy 29.567641 -70.929015) (xy 29.54386 -70.845433) (xy 29.527892 -70.760013) (xy 29.519874 -70.673484)
			(xy 20.384516 -70.673484) (xy 20.384516 -73.213484) (xy 29.519874 -73.213484) (xy 29.519874 -73.126584)
			(xy 29.527892 -73.040055) (xy 29.54386 -72.954635) (xy 29.567641 -72.871053) (xy 29.599033 -72.790021)
			(xy 29.637767 -72.712232) (xy 29.683514 -72.638348) (xy 29.735883 -72.569001) (xy 29.794427 -72.504781)
			(xy 29.858647 -72.446237) (xy 29.927994 -72.393868) (xy 30.001878 -72.348121) (xy 30.079667 -72.309387)
			(xy 30.160699 -72.277995) (xy 30.244281 -72.254214) (xy 30.329701 -72.238246) (xy 30.41623 -72.230228)
			(xy 30.50313 -72.230228) (xy 30.589659 -72.238246) (xy 30.675079 -72.254214) (xy 30.758661 -72.277995)
			(xy 30.839693 -72.309387) (xy 30.917482 -72.348121) (xy 30.991366 -72.393868) (xy 31.060713 -72.446237)
			(xy 31.124933 -72.504781) (xy 31.183477 -72.569001) (xy 31.235846 -72.638348) (xy 31.281593 -72.712232)
			(xy 31.320327 -72.790021) (xy 31.351719 -72.871053) (xy 31.3755 -72.954635) (xy 31.391468 -73.040055)
			(xy 31.399486 -73.126584) (xy 31.399988 -73.170034) (xy 31.399486 -73.213484) (xy 34.599874 -73.213484)
			(xy 34.599874 -73.126584) (xy 34.607892 -73.040055) (xy 34.62386 -72.954635) (xy 34.647641 -72.871053)
			(xy 34.679033 -72.790021) (xy 34.717767 -72.712232) (xy 34.763514 -72.638348) (xy 34.815883 -72.569001)
			(xy 34.874427 -72.504781) (xy 34.938647 -72.446237) (xy 35.007994 -72.393868) (xy 35.081878 -72.348121)
			(xy 35.159667 -72.309387) (xy 35.240699 -72.277995) (xy 35.324281 -72.254214) (xy 35.409701 -72.238246)
			(xy 35.49623 -72.230228) (xy 35.58313 -72.230228) (xy 35.669659 -72.238246) (xy 35.755079 -72.254214)
			(xy 35.838661 -72.277995) (xy 35.919693 -72.309387) (xy 35.997482 -72.348121) (xy 36.071366 -72.393868)
			(xy 36.140713 -72.446237) (xy 36.204933 -72.504781) (xy 36.263477 -72.569001) (xy 36.315846 -72.638348)
			(xy 36.361593 -72.712232) (xy 36.400327 -72.790021) (xy 36.422797 -72.848023) (xy 41.775623 -72.848023)
			(xy 41.779509 -72.793657) (xy 41.791092 -72.740397) (xy 41.810139 -72.689328) (xy 41.836259 -72.64149)
			(xy 41.868923 -72.597856) (xy 41.907464 -72.559316) (xy 41.951099 -72.526653) (xy 41.998938 -72.500534)
			(xy 42.050007 -72.481489) (xy 42.103267 -72.469907) (xy 42.157634 -72.466023) (xy 42.211999 -72.469917)
			(xy 42.265258 -72.481508) (xy 42.316324 -72.500562) (xy 42.364158 -72.52669) (xy 42.38625 -72.542654)
			(xy 42.405262 -72.55625) (xy 42.447145 -72.576982) (xy 42.492113 -72.589708) (xy 42.53865 -72.593998)
			(xy 42.585187 -72.589708) (xy 42.630155 -72.576982) (xy 42.672038 -72.55625) (xy 42.69105 -72.542654)
			(xy 42.713175 -72.526741) (xy 42.761002 -72.500617) (xy 42.81206 -72.481567) (xy 42.865309 -72.469977)
			(xy 42.919666 -72.466084) (xy 42.974024 -72.469967) (xy 43.027276 -72.481548) (xy 43.078337 -72.500589)
			(xy 43.126168 -72.526705) (xy 43.169796 -72.559362) (xy 43.208331 -72.597896) (xy 43.240989 -72.641522)
			(xy 43.267106 -72.689353) (xy 43.286149 -72.740414) (xy 43.297731 -72.793665) (xy 43.301616 -72.848023)
			(xy 43.297725 -72.90238) (xy 43.286136 -72.95563) (xy 43.267087 -73.006688) (xy 43.240965 -73.054516)
			(xy 43.208301 -73.098138) (xy 43.169761 -73.136668) (xy 43.12613 -73.16932) (xy 43.078296 -73.19543)
			(xy 43.027232 -73.214465) (xy 42.973979 -73.226039) (xy 42.919621 -73.229916) (xy 42.865264 -73.226017)
			(xy 42.812016 -73.214421) (xy 42.76096 -73.195364) (xy 42.713137 -73.169234) (xy 42.69105 -73.15327)
			(xy 42.672038 -73.139674) (xy 42.630155 -73.118942) (xy 42.585187 -73.106216) (xy 42.53865 -73.101926)
			(xy 42.492113 -73.106216) (xy 42.447145 -73.118942) (xy 42.405262 -73.139674) (xy 42.38625 -73.15327)
			(xy 42.364196 -73.169285) (xy 42.316365 -73.195419) (xy 42.265301 -73.214479) (xy 42.212045 -73.226077)
			(xy 42.157679 -73.229977) (xy 42.103312 -73.226099) (xy 42.050051 -73.214524) (xy 41.998979 -73.195485)
			(xy 41.951137 -73.169371) (xy 41.907499 -73.136714) (xy 41.868953 -73.098178) (xy 41.836284 -73.054549)
			(xy 41.810157 -73.006714) (xy 41.791105 -72.955647) (xy 41.779515 -72.902389) (xy 41.775623 -72.848023)
			(xy 36.422797 -72.848023) (xy 36.431719 -72.871053) (xy 36.4555 -72.954635) (xy 36.471468 -73.040055)
			(xy 36.479486 -73.126584) (xy 36.479988 -73.170034) (xy 36.479486 -73.213484) (xy 36.471468 -73.300013)
			(xy 36.4555 -73.385433) (xy 36.431719 -73.469015) (xy 36.400327 -73.550047) (xy 36.361593 -73.627836)
			(xy 36.315846 -73.70172) (xy 36.263477 -73.771067) (xy 36.204933 -73.835287) (xy 36.140713 -73.893831)
			(xy 36.071366 -73.9462) (xy 35.997482 -73.991947) (xy 35.919693 -74.030681) (xy 35.838661 -74.062073)
			(xy 35.755079 -74.085854) (xy 35.669659 -74.101822) (xy 35.58313 -74.10984) (xy 35.49623 -74.10984)
			(xy 35.409701 -74.101822) (xy 35.324281 -74.085854) (xy 35.240699 -74.062073) (xy 35.159667 -74.030681)
			(xy 35.081878 -73.991947) (xy 35.007994 -73.9462) (xy 34.938647 -73.893831) (xy 34.874427 -73.835287)
			(xy 34.815883 -73.771067) (xy 34.763514 -73.70172) (xy 34.717767 -73.627836) (xy 34.679033 -73.550047)
			(xy 34.647641 -73.469015) (xy 34.62386 -73.385433) (xy 34.607892 -73.300013) (xy 34.599874 -73.213484)
			(xy 31.399486 -73.213484) (xy 31.391468 -73.300013) (xy 31.3755 -73.385433) (xy 31.351719 -73.469015)
			(xy 31.320327 -73.550047) (xy 31.281593 -73.627836) (xy 31.235846 -73.70172) (xy 31.183477 -73.771067)
			(xy 31.124933 -73.835287) (xy 31.060713 -73.893831) (xy 30.991366 -73.9462) (xy 30.917482 -73.991947)
			(xy 30.839693 -74.030681) (xy 30.758661 -74.062073) (xy 30.675079 -74.085854) (xy 30.589659 -74.101822)
			(xy 30.50313 -74.10984) (xy 30.41623 -74.10984) (xy 30.329701 -74.101822) (xy 30.244281 -74.085854)
			(xy 30.160699 -74.062073) (xy 30.079667 -74.030681) (xy 30.001878 -73.991947) (xy 29.927994 -73.9462)
			(xy 29.858647 -73.893831) (xy 29.794427 -73.835287) (xy 29.735883 -73.771067) (xy 29.683514 -73.70172)
			(xy 29.637767 -73.627836) (xy 29.599033 -73.550047) (xy 29.567641 -73.469015) (xy 29.54386 -73.385433)
			(xy 29.527892 -73.300013) (xy 29.519874 -73.213484) (xy 20.384516 -73.213484) (xy 20.384516 -75.753484)
			(xy 29.519874 -75.753484) (xy 29.519874 -75.666584) (xy 29.527892 -75.580055) (xy 29.54386 -75.494635)
			(xy 29.567641 -75.411053) (xy 29.599033 -75.330021) (xy 29.637767 -75.252232) (xy 29.683514 -75.178348)
			(xy 29.735883 -75.109001) (xy 29.794427 -75.044781) (xy 29.858647 -74.986237) (xy 29.927994 -74.933868)
			(xy 30.001878 -74.888121) (xy 30.079667 -74.849387) (xy 30.160699 -74.817995) (xy 30.244281 -74.794214)
			(xy 30.329701 -74.778246) (xy 30.41623 -74.770228) (xy 30.50313 -74.770228) (xy 30.589659 -74.778246)
			(xy 30.675079 -74.794214) (xy 30.758661 -74.817995) (xy 30.839693 -74.849387) (xy 30.917482 -74.888121)
			(xy 30.991366 -74.933868) (xy 31.060713 -74.986237) (xy 31.124933 -75.044781) (xy 31.183477 -75.109001)
			(xy 31.235846 -75.178348) (xy 31.281593 -75.252232) (xy 31.320327 -75.330021) (xy 31.351719 -75.411053)
			(xy 31.3755 -75.494635) (xy 31.391468 -75.580055) (xy 31.399486 -75.666584) (xy 31.399988 -75.710034)
			(xy 31.399486 -75.753484) (xy 34.599874 -75.753484) (xy 34.599874 -75.666584) (xy 34.607892 -75.580055)
			(xy 34.62386 -75.494635) (xy 34.647641 -75.411053) (xy 34.679033 -75.330021) (xy 34.717767 -75.252232)
			(xy 34.763514 -75.178348) (xy 34.815883 -75.109001) (xy 34.874427 -75.044781) (xy 34.938647 -74.986237)
			(xy 35.007994 -74.933868) (xy 35.081878 -74.888121) (xy 35.159667 -74.849387) (xy 35.240699 -74.817995)
			(xy 35.324281 -74.794214) (xy 35.409701 -74.778246) (xy 35.49623 -74.770228) (xy 35.58313 -74.770228)
			(xy 35.669659 -74.778246) (xy 35.755079 -74.794214) (xy 35.838661 -74.817995) (xy 35.919693 -74.849387)
			(xy 35.997482 -74.888121) (xy 36.071366 -74.933868) (xy 36.140713 -74.986237) (xy 36.204933 -75.044781)
			(xy 36.263477 -75.109001) (xy 36.315846 -75.178348) (xy 36.341403 -75.219624) (xy 41.775621 -75.219624)
			(xy 41.779507 -75.165257) (xy 41.79109 -75.111997) (xy 41.810137 -75.060928) (xy 41.836257 -75.01309)
			(xy 41.868921 -74.969456) (xy 41.907462 -74.930915) (xy 41.951097 -74.898253) (xy 41.998936 -74.872133)
			(xy 42.050006 -74.853088) (xy 42.103266 -74.841506) (xy 42.157632 -74.837621) (xy 42.211998 -74.841515)
			(xy 42.265257 -74.853106) (xy 42.316323 -74.87216) (xy 42.364158 -74.898288) (xy 42.38625 -74.914252)
			(xy 42.405262 -74.927848) (xy 42.447145 -74.94858) (xy 42.492113 -74.961306) (xy 42.53865 -74.965596)
			(xy 42.585187 -74.961306) (xy 42.630155 -74.94858) (xy 42.672038 -74.927848) (xy 42.69105 -74.914252)
			(xy 42.713177 -74.898342) (xy 42.761003 -74.872218) (xy 42.812061 -74.853168) (xy 42.865311 -74.841578)
			(xy 42.919668 -74.837686) (xy 42.974025 -74.841569) (xy 43.027276 -74.853149) (xy 43.078337 -74.872191)
			(xy 43.126169 -74.898307) (xy 43.169796 -74.930964) (xy 43.208331 -74.969498) (xy 43.240989 -75.013124)
			(xy 43.267105 -75.060955) (xy 43.286148 -75.112015) (xy 43.29773 -75.165267) (xy 43.301614 -75.219624)
			(xy 43.297723 -75.273981) (xy 43.286135 -75.327231) (xy 43.267085 -75.378289) (xy 43.240963 -75.426116)
			(xy 43.208299 -75.469738) (xy 43.169759 -75.508268) (xy 43.126128 -75.540919) (xy 43.078294 -75.567029)
			(xy 43.02723 -75.586064) (xy 42.973978 -75.597638) (xy 42.91962 -75.601514) (xy 42.865263 -75.597615)
			(xy 42.812015 -75.586019) (xy 42.76096 -75.566962) (xy 42.713136 -75.540832) (xy 42.69105 -75.524868)
			(xy 42.672038 -75.511272) (xy 42.630155 -75.49054) (xy 42.585187 -75.477814) (xy 42.53865 -75.473524)
			(xy 42.492113 -75.477814) (xy 42.447145 -75.49054) (xy 42.405262 -75.511272) (xy 42.38625 -75.524868)
			(xy 42.364198 -75.540886) (xy 42.316367 -75.56702) (xy 42.265303 -75.58608) (xy 42.212046 -75.597678)
			(xy 42.157681 -75.601579) (xy 42.103313 -75.597701) (xy 42.050052 -75.586125) (xy 41.99898 -75.567087)
			(xy 41.951137 -75.540973) (xy 41.907499 -75.508316) (xy 41.868952 -75.46978) (xy 41.836283 -75.426151)
			(xy 41.810157 -75.378315) (xy 41.791104 -75.327249) (xy 41.779514 -75.27399) (xy 41.775621 -75.219624)
			(xy 36.341403 -75.219624) (xy 36.361593 -75.252232) (xy 36.400327 -75.330021) (xy 36.431719 -75.411053)
			(xy 36.4555 -75.494635) (xy 36.471468 -75.580055) (xy 36.479486 -75.666584) (xy 36.479988 -75.710034)
			(xy 36.479486 -75.753484) (xy 36.471468 -75.840013) (xy 36.4555 -75.925433) (xy 36.431719 -76.009015)
			(xy 36.400327 -76.090047) (xy 36.361593 -76.167836) (xy 36.315846 -76.24172) (xy 36.263477 -76.311067)
			(xy 36.204933 -76.375287) (xy 36.140713 -76.433831) (xy 36.071366 -76.4862) (xy 35.997482 -76.531947)
			(xy 35.919693 -76.570681) (xy 35.838661 -76.602073) (xy 35.755079 -76.625854) (xy 35.669659 -76.641822)
			(xy 35.58313 -76.64984) (xy 35.49623 -76.64984) (xy 35.409701 -76.641822) (xy 35.324281 -76.625854)
			(xy 35.240699 -76.602073) (xy 35.159667 -76.570681) (xy 35.081878 -76.531947) (xy 35.007994 -76.4862)
			(xy 34.938647 -76.433831) (xy 34.874427 -76.375287) (xy 34.815883 -76.311067) (xy 34.763514 -76.24172)
			(xy 34.717767 -76.167836) (xy 34.679033 -76.090047) (xy 34.647641 -76.009015) (xy 34.62386 -75.925433)
			(xy 34.607892 -75.840013) (xy 34.599874 -75.753484) (xy 31.399486 -75.753484) (xy 31.391468 -75.840013)
			(xy 31.3755 -75.925433) (xy 31.351719 -76.009015) (xy 31.320327 -76.090047) (xy 31.281593 -76.167836)
			(xy 31.235846 -76.24172) (xy 31.183477 -76.311067) (xy 31.124933 -76.375287) (xy 31.060713 -76.433831)
			(xy 30.991366 -76.4862) (xy 30.917482 -76.531947) (xy 30.839693 -76.570681) (xy 30.758661 -76.602073)
			(xy 30.675079 -76.625854) (xy 30.589659 -76.641822) (xy 30.50313 -76.64984) (xy 30.41623 -76.64984)
			(xy 30.329701 -76.641822) (xy 30.244281 -76.625854) (xy 30.160699 -76.602073) (xy 30.079667 -76.570681)
			(xy 30.001878 -76.531947) (xy 29.927994 -76.4862) (xy 29.858647 -76.433831) (xy 29.794427 -76.375287)
			(xy 29.735883 -76.311067) (xy 29.683514 -76.24172) (xy 29.637767 -76.167836) (xy 29.599033 -76.090047)
			(xy 29.567641 -76.009015) (xy 29.54386 -75.925433) (xy 29.527892 -75.840013) (xy 29.519874 -75.753484)
			(xy 20.384516 -75.753484) (xy 20.384516 -77.182517) (xy 41.775631 -77.182517) (xy 41.779517 -77.128152)
			(xy 41.791102 -77.074893) (xy 41.810148 -77.023826) (xy 41.836269 -76.975989) (xy 41.868933 -76.932357)
			(xy 41.907474 -76.893818) (xy 41.951108 -76.861157) (xy 41.998946 -76.835039) (xy 42.050015 -76.815995)
			(xy 42.103274 -76.804414) (xy 42.15764 -76.800531) (xy 42.212004 -76.804425) (xy 42.265261 -76.816018)
			(xy 42.316326 -76.835072) (xy 42.364159 -76.8612) (xy 42.38625 -76.877164) (xy 42.405262 -76.89076)
			(xy 42.447145 -76.911492) (xy 42.492113 -76.924218) (xy 42.53865 -76.928508) (xy 42.585187 -76.924218)
			(xy 42.630155 -76.911492) (xy 42.672038 -76.89076) (xy 42.69105 -76.877164) (xy 42.713166 -76.861238)
			(xy 42.760993 -76.835113) (xy 42.812052 -76.816061) (xy 42.865302 -76.80447) (xy 42.91966 -76.800576)
			(xy 42.974019 -76.804458) (xy 43.027272 -76.816038) (xy 43.078335 -76.83508) (xy 43.126168 -76.861195)
			(xy 43.169797 -76.893852) (xy 43.208333 -76.932386) (xy 43.240993 -76.976013) (xy 43.267111 -77.023844)
			(xy 43.286155 -77.074906) (xy 43.297738 -77.128158) (xy 43.301624 -77.182517) (xy 43.297734 -77.236875)
			(xy 43.286146 -77.290126) (xy 43.267097 -77.341186) (xy 43.240975 -77.389015) (xy 43.208311 -77.432639)
			(xy 43.169771 -77.47117) (xy 43.126139 -77.503823) (xy 43.078304 -77.529934) (xy 43.02724 -77.548971)
			(xy 42.973986 -77.560546) (xy 42.919627 -77.564424) (xy 42.865269 -77.560525) (xy 42.812019 -77.54893)
			(xy 42.760962 -77.529874) (xy 42.713137 -77.503744) (xy 42.69105 -77.48778) (xy 42.672038 -77.474184)
			(xy 42.630155 -77.453452) (xy 42.585187 -77.440726) (xy 42.53865 -77.436436) (xy 42.492113 -77.440726)
			(xy 42.447145 -77.453452) (xy 42.405262 -77.474184) (xy 42.38625 -77.48778) (xy 42.364187 -77.503782)
			(xy 42.316356 -77.529914) (xy 42.265293 -77.548973) (xy 42.212037 -77.56057) (xy 42.157673 -77.564469)
			(xy 42.103308 -77.560591) (xy 42.050047 -77.549014) (xy 41.998977 -77.529975) (xy 41.951136 -77.503861)
			(xy 41.9075 -77.471204) (xy 41.868955 -77.432669) (xy 41.836288 -77.389039) (xy 41.810162 -77.341205)
			(xy 41.791111 -77.290139) (xy 41.779522 -77.236882) (xy 41.775631 -77.182517) (xy 20.384516 -77.182517)
			(xy 20.384516 -78.293484) (xy 29.519874 -78.293484) (xy 29.519874 -78.206584) (xy 29.527892 -78.120055)
			(xy 29.54386 -78.034635) (xy 29.567641 -77.951053) (xy 29.599033 -77.870021) (xy 29.637767 -77.792232)
			(xy 29.683514 -77.718348) (xy 29.735883 -77.649001) (xy 29.794427 -77.584781) (xy 29.858647 -77.526237)
			(xy 29.927994 -77.473868) (xy 30.001878 -77.428121) (xy 30.079667 -77.389387) (xy 30.160699 -77.357995)
			(xy 30.244281 -77.334214) (xy 30.329701 -77.318246) (xy 30.41623 -77.310228) (xy 30.50313 -77.310228)
			(xy 30.589659 -77.318246) (xy 30.675079 -77.334214) (xy 30.758661 -77.357995) (xy 30.839693 -77.389387)
			(xy 30.917482 -77.428121) (xy 30.991366 -77.473868) (xy 31.060713 -77.526237) (xy 31.124933 -77.584781)
			(xy 31.183477 -77.649001) (xy 31.235846 -77.718348) (xy 31.281593 -77.792232) (xy 31.320327 -77.870021)
			(xy 31.351719 -77.951053) (xy 31.3755 -78.034635) (xy 31.391468 -78.120055) (xy 31.399486 -78.206584)
			(xy 31.399988 -78.250034) (xy 31.399486 -78.293484) (xy 34.599874 -78.293484) (xy 34.599874 -78.206584)
			(xy 34.607892 -78.120055) (xy 34.62386 -78.034635) (xy 34.647641 -77.951053) (xy 34.679033 -77.870021)
			(xy 34.717767 -77.792232) (xy 34.763514 -77.718348) (xy 34.815883 -77.649001) (xy 34.874427 -77.584781)
			(xy 34.938647 -77.526237) (xy 35.007994 -77.473868) (xy 35.081878 -77.428121) (xy 35.159667 -77.389387)
			(xy 35.240699 -77.357995) (xy 35.324281 -77.334214) (xy 35.409701 -77.318246) (xy 35.49623 -77.310228)
			(xy 35.58313 -77.310228) (xy 35.669659 -77.318246) (xy 35.755079 -77.334214) (xy 35.838661 -77.357995)
			(xy 35.919693 -77.389387) (xy 35.997482 -77.428121) (xy 36.071366 -77.473868) (xy 36.140713 -77.526237)
			(xy 36.204933 -77.584781) (xy 36.263477 -77.649001) (xy 36.315846 -77.718348) (xy 36.361593 -77.792232)
			(xy 36.400327 -77.870021) (xy 36.431719 -77.951053) (xy 36.4555 -78.034635) (xy 36.471468 -78.120055)
			(xy 36.479486 -78.206584) (xy 36.479988 -78.250034) (xy 36.479486 -78.293484) (xy 36.471468 -78.380013)
			(xy 36.4555 -78.465433) (xy 36.431719 -78.549015) (xy 36.400327 -78.630047) (xy 36.361593 -78.707836)
			(xy 36.315846 -78.78172) (xy 36.263477 -78.851067) (xy 36.204933 -78.915287) (xy 36.140713 -78.973831)
			(xy 36.071366 -79.0262) (xy 35.997482 -79.071947) (xy 35.919693 -79.110681) (xy 35.838661 -79.142073)
			(xy 35.755079 -79.165854) (xy 35.669659 -79.181822) (xy 35.58313 -79.18984) (xy 35.49623 -79.18984)
			(xy 35.409701 -79.181822) (xy 35.324281 -79.165854) (xy 35.240699 -79.142073) (xy 35.159667 -79.110681)
			(xy 35.081878 -79.071947) (xy 35.007994 -79.0262) (xy 34.938647 -78.973831) (xy 34.874427 -78.915287)
			(xy 34.815883 -78.851067) (xy 34.763514 -78.78172) (xy 34.717767 -78.707836) (xy 34.679033 -78.630047)
			(xy 34.647641 -78.549015) (xy 34.62386 -78.465433) (xy 34.607892 -78.380013) (xy 34.599874 -78.293484)
			(xy 31.399486 -78.293484) (xy 31.391468 -78.380013) (xy 31.3755 -78.465433) (xy 31.351719 -78.549015)
			(xy 31.320327 -78.630047) (xy 31.281593 -78.707836) (xy 31.235846 -78.78172) (xy 31.183477 -78.851067)
			(xy 31.124933 -78.915287) (xy 31.060713 -78.973831) (xy 30.991366 -79.0262) (xy 30.917482 -79.071947)
			(xy 30.839693 -79.110681) (xy 30.758661 -79.142073) (xy 30.675079 -79.165854) (xy 30.589659 -79.181822)
			(xy 30.50313 -79.18984) (xy 30.41623 -79.18984) (xy 30.329701 -79.181822) (xy 30.244281 -79.165854)
			(xy 30.160699 -79.142073) (xy 30.079667 -79.110681) (xy 30.001878 -79.071947) (xy 29.927994 -79.0262)
			(xy 29.858647 -78.973831) (xy 29.794427 -78.915287) (xy 29.735883 -78.851067) (xy 29.683514 -78.78172)
			(xy 29.637767 -78.707836) (xy 29.599033 -78.630047) (xy 29.567641 -78.549015) (xy 29.54386 -78.465433)
			(xy 29.527892 -78.380013) (xy 29.519874 -78.293484) (xy 20.384516 -78.293484) (xy 20.384516 -79.326013)
			(xy 41.775636 -79.326013) (xy 41.779523 -79.271649) (xy 41.791107 -79.218391) (xy 41.810154 -79.167324)
			(xy 41.836275 -79.119488) (xy 41.868939 -79.075857) (xy 41.90748 -79.037319) (xy 41.951114 -79.004659)
			(xy 41.998952 -78.978542) (xy 42.05002 -78.959499) (xy 42.103279 -78.947918) (xy 42.157643 -78.944036)
			(xy 42.212007 -78.947931) (xy 42.265263 -78.959523) (xy 42.316327 -78.978578) (xy 42.364159 -79.004706)
			(xy 42.38625 -79.02067) (xy 42.405262 -79.034266) (xy 42.447145 -79.054998) (xy 42.492113 -79.067724)
			(xy 42.53865 -79.072014) (xy 42.585187 -79.067724) (xy 42.630155 -79.054998) (xy 42.672038 -79.034266)
			(xy 42.69105 -79.02067) (xy 42.71316 -79.004735) (xy 42.760988 -78.97861) (xy 42.812047 -78.959557)
			(xy 42.865298 -78.947965) (xy 42.919657 -78.944071) (xy 42.974016 -78.947953) (xy 43.02727 -78.959533)
			(xy 43.078334 -78.978574) (xy 43.126167 -79.004689) (xy 43.169797 -79.037346) (xy 43.208334 -79.07588)
			(xy 43.240995 -79.119507) (xy 43.267114 -79.167339) (xy 43.286159 -79.218401) (xy 43.297743 -79.271654)
			(xy 43.301629 -79.326013) (xy 43.297739 -79.380372) (xy 43.286151 -79.433624) (xy 43.267103 -79.484685)
			(xy 43.240981 -79.532515) (xy 43.208317 -79.57614) (xy 43.169777 -79.614671) (xy 43.126145 -79.647326)
			(xy 43.07831 -79.673437) (xy 43.027245 -79.692475) (xy 42.97399 -79.704051) (xy 42.91963 -79.707929)
			(xy 42.865272 -79.704031) (xy 42.812021 -79.692436) (xy 42.760964 -79.673379) (xy 42.713138 -79.64725)
			(xy 42.69105 -79.631286) (xy 42.672038 -79.61769) (xy 42.630155 -79.596958) (xy 42.585187 -79.584232)
			(xy 42.53865 -79.579942) (xy 42.492113 -79.584232) (xy 42.447145 -79.596958) (xy 42.405262 -79.61769)
			(xy 42.38625 -79.631286) (xy 42.364181 -79.64728) (xy 42.316351 -79.673411) (xy 42.265288 -79.692469)
			(xy 42.212033 -79.704066) (xy 42.15767 -79.707964) (xy 42.103305 -79.704085) (xy 42.050045 -79.692509)
			(xy 41.998976 -79.673469) (xy 41.951136 -79.647355) (xy 41.9075 -79.614698) (xy 41.868956 -79.576163)
			(xy 41.83629 -79.532534) (xy 41.810165 -79.4847) (xy 41.791115 -79.433634) (xy 41.779526 -79.380377)
			(xy 41.775636 -79.326013) (xy 20.384516 -79.326013) (xy 20.384516 -80.833484) (xy 29.519874 -80.833484)
			(xy 29.519874 -80.746584) (xy 29.527892 -80.660055) (xy 29.54386 -80.574635) (xy 29.567641 -80.491053)
			(xy 29.599033 -80.410021) (xy 29.637767 -80.332232) (xy 29.683514 -80.258348) (xy 29.735883 -80.189001)
			(xy 29.794427 -80.124781) (xy 29.858647 -80.066237) (xy 29.927994 -80.013868) (xy 30.001878 -79.968121)
			(xy 30.079667 -79.929387) (xy 30.160699 -79.897995) (xy 30.244281 -79.874214) (xy 30.329701 -79.858246)
			(xy 30.41623 -79.850228) (xy 30.50313 -79.850228) (xy 30.589659 -79.858246) (xy 30.675079 -79.874214)
			(xy 30.758661 -79.897995) (xy 30.839693 -79.929387) (xy 30.917482 -79.968121) (xy 30.991366 -80.013868)
			(xy 31.060713 -80.066237) (xy 31.124933 -80.124781) (xy 31.183477 -80.189001) (xy 31.235846 -80.258348)
			(xy 31.281593 -80.332232) (xy 31.320327 -80.410021) (xy 31.351719 -80.491053) (xy 31.3755 -80.574635)
			(xy 31.391468 -80.660055) (xy 31.399486 -80.746584) (xy 31.399988 -80.790034) (xy 31.399486 -80.833484)
			(xy 34.599874 -80.833484) (xy 34.599874 -80.746584) (xy 34.607892 -80.660055) (xy 34.62386 -80.574635)
			(xy 34.647641 -80.491053) (xy 34.679033 -80.410021) (xy 34.717767 -80.332232) (xy 34.763514 -80.258348)
			(xy 34.815883 -80.189001) (xy 34.874427 -80.124781) (xy 34.938647 -80.066237) (xy 35.007994 -80.013868)
			(xy 35.081878 -79.968121) (xy 35.159667 -79.929387) (xy 35.240699 -79.897995) (xy 35.324281 -79.874214)
			(xy 35.409701 -79.858246) (xy 35.49623 -79.850228) (xy 35.58313 -79.850228) (xy 35.669659 -79.858246)
			(xy 35.755079 -79.874214) (xy 35.838661 -79.897995) (xy 35.919693 -79.929387) (xy 35.997482 -79.968121)
			(xy 36.071366 -80.013868) (xy 36.140713 -80.066237) (xy 36.204933 -80.124781) (xy 36.263477 -80.189001)
			(xy 36.315846 -80.258348) (xy 36.361593 -80.332232) (xy 36.400327 -80.410021) (xy 36.431719 -80.491053)
			(xy 36.4555 -80.574635) (xy 36.471468 -80.660055) (xy 36.479486 -80.746584) (xy 36.479988 -80.790034)
			(xy 36.479486 -80.833484) (xy 36.471468 -80.920013) (xy 36.4555 -81.005433) (xy 36.431719 -81.089015)
			(xy 36.400327 -81.170047) (xy 36.361593 -81.247836) (xy 36.315846 -81.32172) (xy 36.263477 -81.391067)
			(xy 36.204933 -81.455287) (xy 36.140713 -81.513831) (xy 36.071366 -81.5662) (xy 35.997482 -81.611947)
			(xy 35.919693 -81.650681) (xy 35.838661 -81.682073) (xy 35.755079 -81.705854) (xy 35.669659 -81.721822)
			(xy 35.58313 -81.72984) (xy 35.49623 -81.72984) (xy 35.409701 -81.721822) (xy 35.324281 -81.705854)
			(xy 35.240699 -81.682073) (xy 35.159667 -81.650681) (xy 35.081878 -81.611947) (xy 35.007994 -81.5662)
			(xy 34.938647 -81.513831) (xy 34.874427 -81.455287) (xy 34.815883 -81.391067) (xy 34.763514 -81.32172)
			(xy 34.717767 -81.247836) (xy 34.679033 -81.170047) (xy 34.647641 -81.089015) (xy 34.62386 -81.005433)
			(xy 34.607892 -80.920013) (xy 34.599874 -80.833484) (xy 31.399486 -80.833484) (xy 31.391468 -80.920013)
			(xy 31.3755 -81.005433) (xy 31.351719 -81.089015) (xy 31.320327 -81.170047) (xy 31.281593 -81.247836)
			(xy 31.235846 -81.32172) (xy 31.183477 -81.391067) (xy 31.124933 -81.455287) (xy 31.060713 -81.513831)
			(xy 30.991366 -81.5662) (xy 30.917482 -81.611947) (xy 30.839693 -81.650681) (xy 30.758661 -81.682073)
			(xy 30.675079 -81.705854) (xy 30.589659 -81.721822) (xy 30.50313 -81.72984) (xy 30.41623 -81.72984)
			(xy 30.329701 -81.721822) (xy 30.244281 -81.705854) (xy 30.160699 -81.682073) (xy 30.079667 -81.650681)
			(xy 30.001878 -81.611947) (xy 29.927994 -81.5662) (xy 29.858647 -81.513831) (xy 29.794427 -81.455287)
			(xy 29.735883 -81.391067) (xy 29.683514 -81.32172) (xy 29.637767 -81.247836) (xy 29.599033 -81.170047)
			(xy 29.567641 -81.089015) (xy 29.54386 -81.005433) (xy 29.527892 -80.920013) (xy 29.519874 -80.833484)
			(xy 20.384516 -80.833484) (xy 20.384516 -83.373484) (xy 29.519874 -83.373484) (xy 29.519874 -83.286584)
			(xy 29.527892 -83.200055) (xy 29.54386 -83.114635) (xy 29.567641 -83.031053) (xy 29.599033 -82.950021)
			(xy 29.637767 -82.872232) (xy 29.683514 -82.798348) (xy 29.735883 -82.729001) (xy 29.794427 -82.664781)
			(xy 29.858647 -82.606237) (xy 29.927994 -82.553868) (xy 30.001878 -82.508121) (xy 30.079667 -82.469387)
			(xy 30.160699 -82.437995) (xy 30.244281 -82.414214) (xy 30.329701 -82.398246) (xy 30.41623 -82.390228)
			(xy 30.50313 -82.390228) (xy 30.589659 -82.398246) (xy 30.675079 -82.414214) (xy 30.758661 -82.437995)
			(xy 30.839693 -82.469387) (xy 30.917482 -82.508121) (xy 30.991366 -82.553868) (xy 31.060713 -82.606237)
			(xy 31.124933 -82.664781) (xy 31.183477 -82.729001) (xy 31.235846 -82.798348) (xy 31.281593 -82.872232)
			(xy 31.320327 -82.950021) (xy 31.351719 -83.031053) (xy 31.3755 -83.114635) (xy 31.391468 -83.200055)
			(xy 31.399486 -83.286584) (xy 31.399988 -83.330034) (xy 31.399486 -83.373484) (xy 34.599874 -83.373484)
			(xy 34.599874 -83.286584) (xy 34.607892 -83.200055) (xy 34.62386 -83.114635) (xy 34.647641 -83.031053)
			(xy 34.679033 -82.950021) (xy 34.717767 -82.872232) (xy 34.763514 -82.798348) (xy 34.815883 -82.729001)
			(xy 34.874427 -82.664781) (xy 34.938647 -82.606237) (xy 35.007994 -82.553868) (xy 35.081878 -82.508121)
			(xy 35.159667 -82.469387) (xy 35.240699 -82.437995) (xy 35.324281 -82.414214) (xy 35.409701 -82.398246)
			(xy 35.49623 -82.390228) (xy 35.58313 -82.390228) (xy 35.669659 -82.398246) (xy 35.755079 -82.414214)
			(xy 35.838661 -82.437995) (xy 35.919693 -82.469387) (xy 35.997482 -82.508121) (xy 36.071366 -82.553868)
			(xy 36.140713 -82.606237) (xy 36.204933 -82.664781) (xy 36.263477 -82.729001) (xy 36.315846 -82.798348)
			(xy 36.361593 -82.872232) (xy 36.400327 -82.950021) (xy 36.431719 -83.031053) (xy 36.4555 -83.114635)
			(xy 36.471468 -83.200055) (xy 36.479486 -83.286584) (xy 36.479988 -83.330034) (xy 36.479486 -83.373484)
			(xy 36.471468 -83.460013) (xy 36.4555 -83.545433) (xy 36.431719 -83.629015) (xy 36.400327 -83.710047)
			(xy 36.361593 -83.787836) (xy 36.315846 -83.86172) (xy 36.263477 -83.931067) (xy 36.204933 -83.995287)
			(xy 36.140713 -84.053831) (xy 36.071366 -84.1062) (xy 35.997482 -84.151947) (xy 35.919693 -84.190681)
			(xy 35.838661 -84.222073) (xy 35.755079 -84.245854) (xy 35.669659 -84.261822) (xy 35.58313 -84.26984)
			(xy 35.49623 -84.26984) (xy 35.409701 -84.261822) (xy 35.324281 -84.245854) (xy 35.240699 -84.222073)
			(xy 35.159667 -84.190681) (xy 35.081878 -84.151947) (xy 35.007994 -84.1062) (xy 34.938647 -84.053831)
			(xy 34.874427 -83.995287) (xy 34.815883 -83.931067) (xy 34.763514 -83.86172) (xy 34.717767 -83.787836)
			(xy 34.679033 -83.710047) (xy 34.647641 -83.629015) (xy 34.62386 -83.545433) (xy 34.607892 -83.460013)
			(xy 34.599874 -83.373484) (xy 31.399486 -83.373484) (xy 31.391468 -83.460013) (xy 31.3755 -83.545433)
			(xy 31.351719 -83.629015) (xy 31.320327 -83.710047) (xy 31.281593 -83.787836) (xy 31.235846 -83.86172)
			(xy 31.183477 -83.931067) (xy 31.124933 -83.995287) (xy 31.060713 -84.053831) (xy 30.991366 -84.1062)
			(xy 30.917482 -84.151947) (xy 30.839693 -84.190681) (xy 30.758661 -84.222073) (xy 30.675079 -84.245854)
			(xy 30.589659 -84.261822) (xy 30.50313 -84.26984) (xy 30.41623 -84.26984) (xy 30.329701 -84.261822)
			(xy 30.244281 -84.245854) (xy 30.160699 -84.222073) (xy 30.079667 -84.190681) (xy 30.001878 -84.151947)
			(xy 29.927994 -84.1062) (xy 29.858647 -84.053831) (xy 29.794427 -83.995287) (xy 29.735883 -83.931067)
			(xy 29.683514 -83.86172) (xy 29.637767 -83.787836) (xy 29.599033 -83.710047) (xy 29.567641 -83.629015)
			(xy 29.54386 -83.545433) (xy 29.527892 -83.460013) (xy 29.519874 -83.373484) (xy 20.384516 -83.373484)
			(xy 20.384516 -84.314199) (xy 47.642008 -84.314199) (xy 47.642008 -84.233089) (xy 47.649958 -84.15237)
			(xy 47.665781 -84.072819) (xy 47.689326 -83.995203) (xy 47.720365 -83.920267) (xy 47.7586 -83.848735)
			(xy 47.803662 -83.781295) (xy 47.855117 -83.718596) (xy 47.91247 -83.661243) (xy 47.975169 -83.609788)
			(xy 48.042609 -83.564726) (xy 48.114141 -83.526491) (xy 48.189077 -83.495452) (xy 48.266693 -83.471907)
			(xy 48.346244 -83.456084) (xy 48.426963 -83.448134) (xy 48.508073 -83.448134) (xy 48.588792 -83.456084)
			(xy 48.668343 -83.471907) (xy 48.745959 -83.495452) (xy 48.820895 -83.526491) (xy 48.892427 -83.564726)
			(xy 48.959867 -83.609788) (xy 49.022566 -83.661243) (xy 49.079919 -83.718596) (xy 49.131374 -83.781295)
			(xy 49.176436 -83.848735) (xy 49.214671 -83.920267) (xy 49.24571 -83.995203) (xy 49.269255 -84.072819)
			(xy 49.285078 -84.15237) (xy 49.293028 -84.233089) (xy 49.293526 -84.273644) (xy 49.293028 -84.314199)
			(xy 49.285078 -84.394918) (xy 49.269255 -84.474469) (xy 49.24571 -84.552085) (xy 49.214671 -84.627021)
			(xy 49.176436 -84.698553) (xy 49.131374 -84.765993) (xy 49.079919 -84.828692) (xy 49.022566 -84.886045)
			(xy 48.959867 -84.9375) (xy 48.892427 -84.982562) (xy 48.820895 -85.020797) (xy 48.745959 -85.051836)
			(xy 48.668343 -85.075381) (xy 48.588792 -85.091204) (xy 48.508073 -85.099154) (xy 48.426963 -85.099154)
			(xy 48.346244 -85.091204) (xy 48.266693 -85.075381) (xy 48.189077 -85.051836) (xy 48.114141 -85.020797)
			(xy 48.042609 -84.982562) (xy 47.975169 -84.9375) (xy 47.91247 -84.886045) (xy 47.855117 -84.828692)
			(xy 47.803662 -84.765993) (xy 47.7586 -84.698553) (xy 47.720365 -84.627021) (xy 47.689326 -84.552085)
			(xy 47.665781 -84.474469) (xy 47.649958 -84.394918) (xy 47.642008 -84.314199) (xy 20.384516 -84.314199)
			(xy 20.384516 -87.49792) (xy 12.607544 -95.274892) (xy 12.607544 -96.687555) (xy 15.679156 -96.687555)
			(xy 15.679156 -96.606445) (xy 15.687106 -96.525726) (xy 15.702929 -96.446175) (xy 15.726474 -96.368559)
			(xy 15.757513 -96.293623) (xy 15.795748 -96.222091) (xy 15.84081 -96.154651) (xy 15.892265 -96.091952)
			(xy 15.949618 -96.034599) (xy 16.012317 -95.983144) (xy 16.079757 -95.938082) (xy 16.151289 -95.899847)
			(xy 16.226225 -95.868808) (xy 16.303841 -95.845263) (xy 16.383392 -95.82944) (xy 16.464111 -95.82149)
			(xy 16.545221 -95.82149) (xy 16.62594 -95.82944) (xy 16.705491 -95.845263) (xy 16.783107 -95.868808)
			(xy 16.858043 -95.899847) (xy 16.929575 -95.938082) (xy 16.997015 -95.983144) (xy 17.059714 -96.034599)
			(xy 17.117067 -96.091952) (xy 17.168522 -96.154651) (xy 17.213584 -96.222091) (xy 17.251819 -96.293623)
			(xy 17.282858 -96.368559) (xy 17.306403 -96.446175) (xy 17.322226 -96.525726) (xy 17.330176 -96.606445)
			(xy 17.330674 -96.647) (xy 17.330176 -96.687555) (xy 17.322226 -96.768274) (xy 17.306403 -96.847825)
			(xy 17.282858 -96.925441) (xy 17.251819 -97.000377) (xy 17.213584 -97.071909) (xy 17.168522 -97.139349)
			(xy 17.117067 -97.202048) (xy 17.059714 -97.259401) (xy 16.997015 -97.310856) (xy 16.929575 -97.355918)
			(xy 16.858043 -97.394153) (xy 16.783107 -97.425192) (xy 16.705491 -97.448737) (xy 16.62594 -97.46456)
			(xy 16.545221 -97.47251) (xy 16.464111 -97.47251) (xy 16.383392 -97.46456) (xy 16.303841 -97.448737)
			(xy 16.226225 -97.425192) (xy 16.151289 -97.394153) (xy 16.079757 -97.355918) (xy 16.012317 -97.310856)
			(xy 15.949618 -97.259401) (xy 15.892265 -97.202048) (xy 15.84081 -97.139349) (xy 15.795748 -97.071909)
			(xy 15.757513 -97.000377) (xy 15.726474 -96.925441) (xy 15.702929 -96.847825) (xy 15.687106 -96.768274)
			(xy 15.679156 -96.687555) (xy 12.607544 -96.687555) (xy 12.607544 -97.957555) (xy 13.139156 -97.957555)
			(xy 13.139156 -97.876445) (xy 13.147106 -97.795726) (xy 13.162929 -97.716175) (xy 13.186474 -97.638559)
			(xy 13.217513 -97.563623) (xy 13.255748 -97.492091) (xy 13.30081 -97.424651) (xy 13.352265 -97.361952)
			(xy 13.409618 -97.304599) (xy 13.472317 -97.253144) (xy 13.539757 -97.208082) (xy 13.611289 -97.169847)
			(xy 13.686225 -97.138808) (xy 13.763841 -97.115263) (xy 13.843392 -97.09944) (xy 13.924111 -97.09149)
			(xy 14.005221 -97.09149) (xy 14.08594 -97.09944) (xy 14.165491 -97.115263) (xy 14.243107 -97.138808)
			(xy 14.318043 -97.169847) (xy 14.389575 -97.208082) (xy 14.457015 -97.253144) (xy 14.519714 -97.304599)
			(xy 14.577067 -97.361952) (xy 14.628522 -97.424651) (xy 14.673584 -97.492091) (xy 14.711819 -97.563623)
			(xy 14.742858 -97.638559) (xy 14.766403 -97.716175) (xy 14.782226 -97.795726) (xy 14.790176 -97.876445)
			(xy 14.790674 -97.917) (xy 14.790176 -97.957555) (xy 14.782226 -98.038274) (xy 14.766403 -98.117825)
			(xy 14.742858 -98.195441) (xy 14.711819 -98.270377) (xy 14.673584 -98.341909) (xy 14.628522 -98.409349)
			(xy 14.577067 -98.472048) (xy 14.519714 -98.529401) (xy 14.457015 -98.580856) (xy 14.389575 -98.625918)
			(xy 14.318043 -98.664153) (xy 14.243107 -98.695192) (xy 14.165491 -98.718737) (xy 14.08594 -98.73456)
			(xy 14.005221 -98.74251) (xy 13.924111 -98.74251) (xy 13.843392 -98.73456) (xy 13.763841 -98.718737)
			(xy 13.686225 -98.695192) (xy 13.611289 -98.664153) (xy 13.539757 -98.625918) (xy 13.472317 -98.580856)
			(xy 13.409618 -98.529401) (xy 13.352265 -98.472048) (xy 13.30081 -98.409349) (xy 13.255748 -98.341909)
			(xy 13.217513 -98.270377) (xy 13.186474 -98.195441) (xy 13.162929 -98.117825) (xy 13.147106 -98.038274)
			(xy 13.139156 -97.957555) (xy 12.607544 -97.957555) (xy 12.607544 -99.227555) (xy 15.679156 -99.227555)
			(xy 15.679156 -99.146445) (xy 15.687106 -99.065726) (xy 15.702929 -98.986175) (xy 15.726474 -98.908559)
			(xy 15.757513 -98.833623) (xy 15.795748 -98.762091) (xy 15.84081 -98.694651) (xy 15.892265 -98.631952)
			(xy 15.949618 -98.574599) (xy 16.012317 -98.523144) (xy 16.079757 -98.478082) (xy 16.151289 -98.439847)
			(xy 16.226225 -98.408808) (xy 16.303841 -98.385263) (xy 16.383392 -98.36944) (xy 16.464111 -98.36149)
			(xy 16.545221 -98.36149) (xy 16.62594 -98.36944) (xy 16.705491 -98.385263) (xy 16.783107 -98.408808)
			(xy 16.858043 -98.439847) (xy 16.929575 -98.478082) (xy 16.997015 -98.523144) (xy 17.059714 -98.574599)
			(xy 17.117067 -98.631952) (xy 17.168522 -98.694651) (xy 17.213584 -98.762091) (xy 17.251819 -98.833623)
			(xy 17.282858 -98.908559) (xy 17.306403 -98.986175) (xy 17.322226 -99.065726) (xy 17.330176 -99.146445)
			(xy 17.330674 -99.187) (xy 17.330176 -99.227555) (xy 17.322226 -99.308274) (xy 17.306403 -99.387825)
			(xy 17.282858 -99.465441) (xy 17.251819 -99.540377) (xy 17.213584 -99.611909) (xy 17.168522 -99.679349)
			(xy 17.117067 -99.742048) (xy 17.059714 -99.799401) (xy 16.997015 -99.850856) (xy 16.929575 -99.895918)
			(xy 16.858043 -99.934153) (xy 16.783107 -99.965192) (xy 16.705491 -99.988737) (xy 16.62594 -100.00456)
			(xy 16.545221 -100.01251) (xy 16.464111 -100.01251) (xy 16.383392 -100.00456) (xy 16.303841 -99.988737)
			(xy 16.226225 -99.965192) (xy 16.151289 -99.934153) (xy 16.079757 -99.895918) (xy 16.012317 -99.850856)
			(xy 15.949618 -99.799401) (xy 15.892265 -99.742048) (xy 15.84081 -99.679349) (xy 15.795748 -99.611909)
			(xy 15.757513 -99.540377) (xy 15.726474 -99.465441) (xy 15.702929 -99.387825) (xy 15.687106 -99.308274)
			(xy 15.679156 -99.227555) (xy 12.607544 -99.227555) (xy 12.607544 -101.767555) (xy 15.679156 -101.767555)
			(xy 15.679156 -101.686445) (xy 15.687106 -101.605726) (xy 15.702929 -101.526175) (xy 15.726474 -101.448559)
			(xy 15.757513 -101.373623) (xy 15.795748 -101.302091) (xy 15.84081 -101.234651) (xy 15.892265 -101.171952)
			(xy 15.949618 -101.114599) (xy 16.012317 -101.063144) (xy 16.079757 -101.018082) (xy 16.151289 -100.979847)
			(xy 16.226225 -100.948808) (xy 16.303841 -100.925263) (xy 16.383392 -100.90944) (xy 16.464111 -100.90149)
			(xy 16.545221 -100.90149) (xy 16.62594 -100.90944) (xy 16.705491 -100.925263) (xy 16.783107 -100.948808)
			(xy 16.858043 -100.979847) (xy 16.929575 -101.018082) (xy 16.997015 -101.063144) (xy 17.059714 -101.114599)
			(xy 17.117067 -101.171952) (xy 17.168522 -101.234651) (xy 17.213584 -101.302091) (xy 17.251819 -101.373623)
			(xy 17.282858 -101.448559) (xy 17.306403 -101.526175) (xy 17.322226 -101.605726) (xy 17.330176 -101.686445)
			(xy 17.330674 -101.727) (xy 17.330176 -101.767555) (xy 17.322226 -101.848274) (xy 17.306403 -101.927825)
			(xy 17.282858 -102.005441) (xy 17.251819 -102.080377) (xy 17.213584 -102.151909) (xy 17.168522 -102.219349)
			(xy 17.117067 -102.282048) (xy 17.059714 -102.339401) (xy 16.997015 -102.390856) (xy 16.929575 -102.435918)
			(xy 16.858043 -102.474153) (xy 16.783107 -102.505192) (xy 16.705491 -102.528737) (xy 16.62594 -102.54456)
			(xy 16.545221 -102.55251) (xy 16.464111 -102.55251) (xy 16.383392 -102.54456) (xy 16.303841 -102.528737)
			(xy 16.226225 -102.505192) (xy 16.151289 -102.474153) (xy 16.079757 -102.435918) (xy 16.012317 -102.390856)
			(xy 15.949618 -102.339401) (xy 15.892265 -102.282048) (xy 15.84081 -102.219349) (xy 15.795748 -102.151909)
			(xy 15.757513 -102.080377) (xy 15.726474 -102.005441) (xy 15.702929 -101.927825) (xy 15.687106 -101.848274)
			(xy 15.679156 -101.767555) (xy 12.607544 -101.767555) (xy 12.607544 -103.037555) (xy 13.139156 -103.037555)
			(xy 13.139156 -102.956445) (xy 13.147106 -102.875726) (xy 13.162929 -102.796175) (xy 13.186474 -102.718559)
			(xy 13.217513 -102.643623) (xy 13.255748 -102.572091) (xy 13.30081 -102.504651) (xy 13.352265 -102.441952)
			(xy 13.409618 -102.384599) (xy 13.472317 -102.333144) (xy 13.539757 -102.288082) (xy 13.611289 -102.249847)
			(xy 13.686225 -102.218808) (xy 13.763841 -102.195263) (xy 13.843392 -102.17944) (xy 13.924111 -102.17149)
			(xy 14.005221 -102.17149) (xy 14.08594 -102.17944) (xy 14.165491 -102.195263) (xy 14.243107 -102.218808)
			(xy 14.318043 -102.249847) (xy 14.389575 -102.288082) (xy 14.457015 -102.333144) (xy 14.519714 -102.384599)
			(xy 14.577067 -102.441952) (xy 14.628522 -102.504651) (xy 14.673584 -102.572091) (xy 14.711819 -102.643623)
			(xy 14.742858 -102.718559) (xy 14.766403 -102.796175) (xy 14.782226 -102.875726) (xy 14.790176 -102.956445)
			(xy 14.790674 -102.997) (xy 14.790176 -103.037555) (xy 14.782226 -103.118274) (xy 14.766403 -103.197825)
			(xy 14.742858 -103.275441) (xy 14.711819 -103.350377) (xy 14.673584 -103.421909) (xy 14.628522 -103.489349)
			(xy 14.577067 -103.552048) (xy 14.519714 -103.609401) (xy 14.457015 -103.660856) (xy 14.389575 -103.705918)
			(xy 14.318043 -103.744153) (xy 14.243107 -103.775192) (xy 14.165491 -103.798737) (xy 14.08594 -103.81456)
			(xy 14.005221 -103.82251) (xy 13.924111 -103.82251) (xy 13.843392 -103.81456) (xy 13.763841 -103.798737)
			(xy 13.686225 -103.775192) (xy 13.611289 -103.744153) (xy 13.539757 -103.705918) (xy 13.472317 -103.660856)
			(xy 13.409618 -103.609401) (xy 13.352265 -103.552048) (xy 13.30081 -103.489349) (xy 13.255748 -103.421909)
			(xy 13.217513 -103.350377) (xy 13.186474 -103.275441) (xy 13.162929 -103.197825) (xy 13.147106 -103.118274)
			(xy 13.139156 -103.037555) (xy 12.607544 -103.037555) (xy 12.607544 -104.307555) (xy 15.679156 -104.307555)
			(xy 15.679156 -104.226445) (xy 15.687106 -104.145726) (xy 15.702929 -104.066175) (xy 15.726474 -103.988559)
			(xy 15.757513 -103.913623) (xy 15.795748 -103.842091) (xy 15.84081 -103.774651) (xy 15.892265 -103.711952)
			(xy 15.949618 -103.654599) (xy 16.012317 -103.603144) (xy 16.079757 -103.558082) (xy 16.151289 -103.519847)
			(xy 16.226225 -103.488808) (xy 16.303841 -103.465263) (xy 16.383392 -103.44944) (xy 16.464111 -103.44149)
			(xy 16.545221 -103.44149) (xy 16.62594 -103.44944) (xy 16.705491 -103.465263) (xy 16.783107 -103.488808)
			(xy 16.858043 -103.519847) (xy 16.929575 -103.558082) (xy 16.997015 -103.603144) (xy 17.059714 -103.654599)
			(xy 17.117067 -103.711952) (xy 17.168522 -103.774651) (xy 17.213584 -103.842091) (xy 17.251819 -103.913623)
			(xy 17.282858 -103.988559) (xy 17.306403 -104.066175) (xy 17.322226 -104.145726) (xy 17.330176 -104.226445)
			(xy 17.330674 -104.267) (xy 17.330176 -104.307555) (xy 17.322226 -104.388274) (xy 17.306403 -104.467825)
			(xy 17.282858 -104.545441) (xy 17.251819 -104.620377) (xy 17.213584 -104.691909) (xy 17.168522 -104.759349)
			(xy 17.117067 -104.822048) (xy 17.059714 -104.879401) (xy 16.997015 -104.930856) (xy 16.929575 -104.975918)
			(xy 16.858043 -105.014153) (xy 16.783107 -105.045192) (xy 16.705491 -105.068737) (xy 16.62594 -105.08456)
			(xy 16.545221 -105.09251) (xy 16.464111 -105.09251) (xy 16.383392 -105.08456) (xy 16.303841 -105.068737)
			(xy 16.226225 -105.045192) (xy 16.151289 -105.014153) (xy 16.079757 -104.975918) (xy 16.012317 -104.930856)
			(xy 15.949618 -104.879401) (xy 15.892265 -104.822048) (xy 15.84081 -104.759349) (xy 15.795748 -104.691909)
			(xy 15.757513 -104.620377) (xy 15.726474 -104.545441) (xy 15.702929 -104.467825) (xy 15.687106 -104.388274)
			(xy 15.679156 -104.307555) (xy 12.607544 -104.307555) (xy 12.607544 -105.577555) (xy 13.139156 -105.577555)
			(xy 13.139156 -105.496445) (xy 13.147106 -105.415726) (xy 13.162929 -105.336175) (xy 13.186474 -105.258559)
			(xy 13.217513 -105.183623) (xy 13.255748 -105.112091) (xy 13.30081 -105.044651) (xy 13.352265 -104.981952)
			(xy 13.409618 -104.924599) (xy 13.472317 -104.873144) (xy 13.539757 -104.828082) (xy 13.611289 -104.789847)
			(xy 13.686225 -104.758808) (xy 13.763841 -104.735263) (xy 13.843392 -104.71944) (xy 13.924111 -104.71149)
			(xy 14.005221 -104.71149) (xy 14.08594 -104.71944) (xy 14.165491 -104.735263) (xy 14.243107 -104.758808)
			(xy 14.318043 -104.789847) (xy 14.389575 -104.828082) (xy 14.457015 -104.873144) (xy 14.519714 -104.924599)
			(xy 14.577067 -104.981952) (xy 14.628522 -105.044651) (xy 14.673584 -105.112091) (xy 14.711819 -105.183623)
			(xy 14.742858 -105.258559) (xy 14.766403 -105.336175) (xy 14.782226 -105.415726) (xy 14.790176 -105.496445)
			(xy 14.790674 -105.537) (xy 14.790176 -105.577555) (xy 14.782226 -105.658274) (xy 14.766403 -105.737825)
			(xy 14.742858 -105.815441) (xy 14.711819 -105.890377) (xy 14.673584 -105.961909) (xy 14.628522 -106.029349)
			(xy 14.577067 -106.092048) (xy 14.519714 -106.149401) (xy 14.457015 -106.200856) (xy 14.389575 -106.245918)
			(xy 14.318043 -106.284153) (xy 14.243107 -106.315192) (xy 14.165491 -106.338737) (xy 14.08594 -106.35456)
			(xy 14.005221 -106.36251) (xy 13.924111 -106.36251) (xy 13.843392 -106.35456) (xy 13.763841 -106.338737)
			(xy 13.686225 -106.315192) (xy 13.611289 -106.284153) (xy 13.539757 -106.245918) (xy 13.472317 -106.200856)
			(xy 13.409618 -106.149401) (xy 13.352265 -106.092048) (xy 13.30081 -106.029349) (xy 13.255748 -105.961909)
			(xy 13.217513 -105.890377) (xy 13.186474 -105.815441) (xy 13.162929 -105.737825) (xy 13.147106 -105.658274)
			(xy 13.139156 -105.577555) (xy 12.607544 -105.577555) (xy 12.607544 -114.067844) (xy 12.60922 -114.089927)
			(xy 12.61924 -114.13306) (xy 12.636581 -114.173806) (xy 12.66072 -114.21093) (xy 12.690926 -114.243311)
			(xy 12.726286 -114.269968) (xy 12.765729 -114.290096) (xy 12.808063 -114.303086) (xy 12.852008 -114.308544)
			(xy 12.896233 -114.306306) (xy 12.939402 -114.296439) (xy 12.980209 -114.279241) (xy 13.017419 -114.255234)
			(xy 13.03401 -114.240564) (xy 13.110116 -114.170931) (xy 13.267018 -114.036977) (xy 13.429057 -113.909283)
			(xy 13.595983 -113.788047) (xy 13.767538 -113.673456) (xy 13.943458 -113.565686) (xy 14.123472 -113.464902)
			(xy 14.307302 -113.371261) (xy 14.494666 -113.284907) (xy 14.685275 -113.205973) (xy 14.878834 -113.134579)
			(xy 15.075046 -113.070837) (xy 15.273609 -113.014845) (xy 15.474216 -112.966689) (xy 15.676559 -112.926442)
			(xy 15.880325 -112.894168) (xy 16.0852 -112.869915) (xy 16.29087 -112.853721) (xy 16.497017 -112.845612)
			(xy 16.60017 -112.845088) (xy 16.706436 -112.845627) (xy 16.918795 -112.85423) (xy 17.130632 -112.871415)
			(xy 17.3416 -112.897155) (xy 17.551355 -112.931406) (xy 17.759552 -112.974113) (xy 17.965852 -113.025206)
			(xy 18.068036 -113.054384) (xy 18.166338 -113.083501) (xy 18.360837 -113.148413) (xy 18.552656 -113.220864)
			(xy 18.741503 -113.300743) (xy 18.927089 -113.387928) (xy 19.109132 -113.482287) (xy 19.287356 -113.583677)
			(xy 19.461488 -113.691943) (xy 19.631265 -113.806919) (xy 19.796426 -113.928432) (xy 19.956721 -114.056296)
			(xy 20.111905 -114.190315) (xy 20.261743 -114.330288) (xy 20.406006 -114.475999) (xy 20.544474 -114.627227)
			(xy 20.676937 -114.783742) (xy 20.803193 -114.945307) (xy 20.92305 -115.111673) (xy 21.036325 -115.282589)
			(xy 21.142846 -115.457794) (xy 21.242451 -115.637022) (xy 21.334987 -115.819999) (xy 21.420315 -116.006447)
			(xy 21.498303 -116.196081) (xy 21.568834 -116.388614) (xy 21.6318 -116.583752) (xy 21.687105 -116.781198)
			(xy 21.734665 -116.980652) (xy 21.774407 -117.181808) (xy 21.806271 -117.384363) (xy 21.830209 -117.588006)
			(xy 21.846184 -117.792428) (xy 21.854171 -117.997317) (xy 21.854668 -118.09984) (xy 21.854162 -118.202981)
			(xy 21.846065 -118.409104) (xy 21.829885 -118.614751) (xy 21.805646 -118.819604) (xy 21.773386 -119.023349)
			(xy 21.733155 -119.22567) (xy 21.685015 -119.426256) (xy 21.629039 -119.624798) (xy 21.565314 -119.820991)
			(xy 21.493939 -120.014531) (xy 21.415022 -120.205122) (xy 21.328687 -120.392468) (xy 21.235065 -120.576281)
			(xy 21.134302 -120.756279) (xy 21.026552 -120.932183) (xy 20.911981 -121.103722) (xy 20.790766 -121.270634)
			(xy 20.663094 -121.432659) (xy 20.529161 -121.589549) (xy 20.389174 -121.741061) (xy 20.243349 -121.886963)
			(xy 20.09191 -122.027029) (xy 19.93509 -122.161044) (xy 19.773132 -122.288801) (xy 19.606284 -122.410103)
			(xy 19.434804 -122.524764) (xy 19.258956 -122.632606) (xy 19.079012 -122.733464) (xy 18.895247 -122.827182)
			(xy 18.707947 -122.913615) (xy 18.517398 -122.992632) (xy 18.323895 -123.064108) (xy 18.127735 -123.127936)
			(xy 17.929222 -123.184016) (xy 17.728661 -123.232261) (xy 17.526361 -123.272598) (xy 17.322634 -123.304965)
			(xy 17.117793 -123.32931) (xy 16.912155 -123.345598) (xy 16.706036 -123.353803) (xy 16.499754 -123.353912)
			(xy 16.293626 -123.345925) (xy 16.087971 -123.329854) (xy 15.883105 -123.305725) (xy 15.679344 -123.273574)
			(xy 15.578074 -123.254008) (xy 15.480007 -123.234107) (xy 15.285312 -123.187779) (xy 15.092525 -123.134068)
			(xy 14.901923 -123.07305) (xy 14.807692 -123.039378) (xy 14.78599 -123.032026) (xy 14.740816 -123.024379)
			(xy 14.695003 -123.024956) (xy 14.650035 -123.033738) (xy 14.607372 -123.050441) (xy 14.568394 -123.074522)
			(xy 14.534366 -123.105203) (xy 14.506391 -123.141487) (xy 14.485375 -123.1822) (xy 14.472 -123.226021)
			(xy 14.466699 -123.27153) (xy 14.469644 -123.317252) (xy 14.480739 -123.361705) (xy 14.499626 -123.403448)
			(xy 14.525691 -123.441128) (xy 14.5415 -123.457716) (xy 17.583404 -126.49962) (xy 19.140932 -126.49962)
			(xy 23.989792 -131.34848) (xy 24.006332 -131.36326) (xy 24.043515 -131.387438) (xy 24.08433 -131.404797)
			(xy 24.127537 -131.414811) (xy 24.171827 -131.417174) (xy 24.215855 -131.411816) (xy 24.258285 -131.3989)
			(xy 24.29783 -131.378816) (xy 24.33329 -131.352175) (xy 24.363589 -131.319785) (xy 24.387808 -131.282628)
			(xy 24.405211 -131.241833) (xy 24.415272 -131.198636) (xy 24.41702 -131.176522) (xy 24.41702 -116.667026)
			(xy 18.556224 -110.80623) (xy 18.556224 -92.880688) (xy 24.643334 -86.793324) (xy 50.899314 -86.793324)
			(xy 52.159408 -85.53323) (xy 52.175414 -85.516505) (xy 52.201679 -85.478389) (xy 52.220608 -85.436147)
			(xy 52.231575 -85.391176) (xy 52.234217 -85.344963) (xy 52.228447 -85.299035) (xy 52.214456 -85.254912)
			(xy 52.192705 -85.214051) (xy 52.163916 -85.177804) (xy 52.129038 -85.14737) (xy 52.089226 -85.123755)
			(xy 52.045796 -85.10774) (xy 52.000184 -85.099854) (xy 51.977036 -85.099652) (xy 51.936279 -85.099624)
			(xy 51.855081 -85.09252) (xy 51.774978 -85.077453) (xy 51.696748 -85.05457) (xy 51.621152 -85.024093)
			(xy 51.548925 -84.986319) (xy 51.48077 -84.941615) (xy 51.417349 -84.890416) (xy 51.359279 -84.83322)
			(xy 51.307124 -84.770583) (xy 51.261392 -84.703113) (xy 51.222527 -84.631467) (xy 51.190908 -84.556342)
			(xy 51.166841 -84.478468) (xy 51.150561 -84.398603) (xy 51.142226 -84.317522) (xy 51.141917 -84.236014)
			(xy 51.149638 -84.154873) (xy 51.165312 -84.074886) (xy 51.188788 -83.996832) (xy 51.219837 -83.921469)
			(xy 51.258158 -83.849531) (xy 51.303377 -83.781717) (xy 51.355056 -83.718686) (xy 51.412691 -83.661051)
			(xy 51.475722 -83.609373) (xy 51.543536 -83.564154) (xy 51.615475 -83.525834) (xy 51.690838 -83.494786)
			(xy 51.768892 -83.47131) (xy 51.848879 -83.455637) (xy 51.930021 -83.447917) (xy 52.011528 -83.448227)
			(xy 52.092609 -83.456562) (xy 52.172474 -83.472843) (xy 52.250348 -83.49691) (xy 52.325473 -83.52853)
			(xy 52.397118 -83.567395) (xy 52.464588 -83.613128) (xy 52.527225 -83.665283) (xy 52.584421 -83.723353)
			(xy 52.635619 -83.786775) (xy 52.680322 -83.85493) (xy 52.718095 -83.927157) (xy 52.748572 -84.002754)
			(xy 52.771454 -84.080984) (xy 52.786521 -84.161087) (xy 52.793625 -84.242285) (xy 52.793646 -84.283042)
			(xy 52.793896 -84.306192) (xy 52.801768 -84.35181) (xy 52.817773 -84.395247) (xy 52.84138 -84.435067)
			(xy 52.87181 -84.469952) (xy 52.908055 -84.498749) (xy 52.948916 -84.520504) (xy 52.993042 -84.534498)
			(xy 53.038973 -84.540268) (xy 53.085189 -84.537623) (xy 53.130162 -84.526651) (xy 53.172403 -84.507714)
			(xy 53.210516 -84.48144) (xy 53.227224 -84.465414) (xy 80.61198 -57.080912) (xy 81.161128 -57.080912)
			(xy 81.18983 -57.06491) (xy 81.206086 -57.056274) (xy 81.220056 -57.04967) (xy 81.232032 -57.044488)
			(xy 81.256564 -57.035588) (xy 81.269078 -57.03189) (xy 81.300828 -57.022746) (xy 83.43646 -54.887114)
			(xy 83.43646 -50.216562) (xy 85.847174 -47.805848) (xy 92.537788 -47.805848) (xy 93.53804 -48.8061)
			(xy 93.53804 -50.36312) (xy 93.39453 -50.50663) (xy 93.334586 -50.566574) (xy 92.858082 -51.042824)
			(xy 92.643198 -51.042824) (xy 92.620524 -51.044579) (xy 92.576291 -51.055119) (xy 92.534637 -51.073356)
			(xy 92.49689 -51.098711) (xy 92.464253 -51.130374) (xy 92.437768 -51.167336) (xy 92.418278 -51.208419)
			(xy 92.406405 -51.252314) (xy 92.402527 -51.29762) (xy 92.406767 -51.342894) (xy 92.418992 -51.386691)
			(xy 92.43881 -51.427617) (xy 92.465591 -51.464366) (xy 92.481654 -51.480466) (xy 92.508505 -51.506799)
			(xy 92.5571 -51.564202) (xy 92.599372 -51.626408) (xy 92.634849 -51.692725) (xy 92.663136 -51.762413)
			(xy 92.683917 -51.834696) (xy 92.696961 -51.908766) (xy 92.702123 -51.983799) (xy 92.699345 -52.058958)
			(xy 92.688657 -52.133405) (xy 92.670179 -52.20631) (xy 92.644118 -52.27686) (xy 92.610762 -52.344269)
			(xy 92.570486 -52.407786) (xy 92.523736 -52.466702) (xy 92.471035 -52.52036) (xy 92.412971 -52.568162)
			(xy 92.35019 -52.609576) (xy 92.283392 -52.644139) (xy 92.213322 -52.671467) (xy 92.140761 -52.691254)
			(xy 92.066519 -52.70328) (xy 91.991422 -52.707411) (xy 91.916308 -52.703601) (xy 91.842015 -52.691892)
			(xy 91.769371 -52.672415) (xy 91.734132 -52.65928) (xy 91.712034 -52.650644) (xy 91.602052 -52.650644)
			(xy 91.58015 -52.65232) (xy 91.537364 -52.662244) (xy 91.496919 -52.67937) (xy 91.460018 -52.70319)
			(xy 91.45256 -52.71008) (xy 93.154506 -52.71008) (xy 93.158522 -52.59381) (xy 93.170549 -52.478095)
			(xy 93.190531 -52.363485) (xy 93.218373 -52.250526) (xy 93.253942 -52.139758) (xy 93.297068 -52.031707)
			(xy 93.347545 -51.926889) (xy 93.405134 -51.825804) (xy 93.46956 -51.728932) (xy 93.540515 -51.636736)
			(xy 93.617662 -51.549655) (xy 93.700633 -51.468104) (xy 93.789033 -51.392472) (xy 93.88244 -51.323118)
			(xy 93.980409 -51.260375) (xy 94.082473 -51.204539) (xy 94.188147 -51.155878) (xy 94.296926 -51.114624)
			(xy 94.408291 -51.080973) (xy 94.521714 -51.055085) (xy 94.636651 -51.037084) (xy 94.752557 -51.027055)
			(xy 94.868879 -51.025047) (xy 94.985062 -51.031069) (xy 95.100553 -51.045092) (xy 95.214801 -51.06705)
			(xy 95.327262 -51.096837) (xy 95.4374 -51.134312) (xy 95.54469 -51.179297) (xy 95.648621 -51.231576)
			(xy 95.748697 -51.290901) (xy 95.844443 -51.356989) (xy 95.9354 -51.429525) (xy 96.021136 -51.508164)
			(xy 96.101243 -51.59253) (xy 96.175339 -51.682222) (xy 96.243069 -51.776812) (xy 96.304113 -51.87585)
			(xy 96.358178 -51.978863) (xy 96.405008 -52.08536) (xy 96.444379 -52.194835) (xy 96.476103 -52.306765)
			(xy 96.500029 -52.420617) (xy 96.516043 -52.535849) (xy 96.52407 -52.651911) (xy 96.524572 -52.71008)
			(xy 96.52407 -52.768249) (xy 96.516043 -52.884311) (xy 96.500029 -52.999543) (xy 96.476103 -53.113395)
			(xy 96.444379 -53.225325) (xy 96.405008 -53.3348) (xy 96.358178 -53.441297) (xy 96.304113 -53.54431)
			(xy 96.243069 -53.643348) (xy 96.175339 -53.737938) (xy 96.101243 -53.82763) (xy 96.021136 -53.911996)
			(xy 95.9354 -53.990635) (xy 95.844443 -54.063171) (xy 95.748697 -54.129259) (xy 95.648621 -54.188584)
			(xy 95.54469 -54.240863) (xy 95.4374 -54.285848) (xy 95.327262 -54.323323) (xy 95.214801 -54.35311)
			(xy 95.100553 -54.375068) (xy 94.985062 -54.389091) (xy 94.868879 -54.395113) (xy 94.752557 -54.393105)
			(xy 94.636651 -54.383076) (xy 94.521714 -54.365075) (xy 94.408291 -54.339187) (xy 94.296926 -54.305536)
			(xy 94.188147 -54.264282) (xy 94.082473 -54.215621) (xy 93.980409 -54.159785) (xy 93.88244 -54.097042)
			(xy 93.789033 -54.027688) (xy 93.700633 -53.952056) (xy 93.617662 -53.870505) (xy 93.540515 -53.783424)
			(xy 93.46956 -53.691228) (xy 93.405134 -53.594356) (xy 93.347545 -53.493271) (xy 93.297068 -53.388453)
			(xy 93.253942 -53.280402) (xy 93.218373 -53.169634) (xy 93.190531 -53.056675) (xy 93.170549 -52.942065)
			(xy 93.158522 -52.82635) (xy 93.154506 -52.71008) (xy 91.45256 -52.71008) (xy 91.427756 -52.732995)
			(xy 91.401094 -52.767899) (xy 91.380825 -52.806863) (xy 91.36755 -52.848731) (xy 91.361664 -52.892257)
			(xy 91.363344 -52.936146) (xy 91.372537 -52.979095) (xy 91.38031 -52.99964) (xy 91.394262 -53.035678)
			(xy 91.41517 -53.110079) (xy 91.427895 -53.186307) (xy 91.432286 -53.263464) (xy 91.428292 -53.340644)
			(xy 91.415961 -53.416936) (xy 91.395436 -53.491444) (xy 91.36696 -53.563289) (xy 91.330868 -53.631626)
			(xy 91.287585 -53.695651) (xy 91.237621 -53.75461) (xy 91.181562 -53.807808) (xy 91.120071 -53.85462)
			(xy 91.053869 -53.894495) (xy 90.983738 -53.926963) (xy 90.910501 -53.951641) (xy 90.835022 -53.96824)
			(xy 90.758189 -53.976564) (xy 90.680907 -53.976515) (xy 90.604084 -53.968093) (xy 90.56624 -53.960268)
			(xy 90.55989 -53.958744) (xy 90.546174 -53.956966) (xy 90.531807 -53.95565) (xy 90.503131 -53.958771)
			(xy 90.475887 -53.968244) (xy 90.451462 -53.983589) (xy 90.441018 -53.993542) (xy 87.34171 -57.092596)
			(xy 86.375748 -57.092596) (xy 85.033866 -58.434478) (xy 84.86521 -58.603388) (xy 84.461604 -59.006994)
			(xy 84.45246 -59.03849) (xy 84.444381 -59.064888) (xy 84.421673 -59.115206) (xy 84.39195 -59.161726)
			(xy 84.355833 -59.203477) (xy 84.314077 -59.239587) (xy 84.267552 -59.269302) (xy 84.21723 -59.292003)
			(xy 84.19084 -59.30011) (xy 84.159344 -59.309254) (xy 80.155796 -63.312802) (xy 80.140232 -63.329012)
			(xy 80.114505 -63.365852) (xy 80.095662 -63.406644) (xy 80.08429 -63.450115) (xy 80.080746 -63.494909)
			(xy 80.085138 -63.539628) (xy 80.097331 -63.582876) (xy 80.116943 -63.623304) (xy 80.143364 -63.65965)
			(xy 80.175767 -63.69078) (xy 80.19415 -63.703708) (xy 80.22288 -63.722204) (xy 80.273858 -63.767688)
			(xy 80.295496 -63.794132) (xy 80.311866 -63.815857) (xy 80.338939 -63.863035) (xy 80.359037 -63.913581)
			(xy 80.371752 -63.966469) (xy 80.376827 -64.020626) (xy 80.374159 -64.074956) (xy 80.363802 -64.128355)
			(xy 80.345965 -64.179743) (xy 80.321012 -64.228076) (xy 80.289446 -64.272375) (xy 80.251909 -64.311742)
			(xy 80.209162 -64.345379) (xy 80.16207 -64.372603) (xy 80.137 -64.383158) (xy 80.114499 -64.391753)
			(xy 80.067877 -64.403859) (xy 80.044036 -64.407288) (xy 80.016268 -64.41041) (xy 79.960399 -64.409462)
			(xy 79.905266 -64.400371) (xy 79.85205 -64.383333) (xy 79.801889 -64.358711) (xy 79.755858 -64.327035)
			(xy 79.714942 -64.28898) (xy 79.680016 -64.245363) (xy 79.651829 -64.197116) (xy 79.630984 -64.145273)
			(xy 79.62392 -64.118236) (xy 79.615538 -64.083438) (xy 79.590138 -64.058038) (xy 79.577967 -64.046685)
			(xy 79.549128 -64.030096) (xy 79.516984 -64.021511) (xy 79.483714 -64.021511) (xy 79.45157 -64.030096)
			(xy 79.422731 -64.046685) (xy 79.41056 -64.058038) (xy 79.264764 -64.203834) (xy 79.264764 -65.444116)
			(xy 78.319376 -66.38925) (xy 78.303442 -66.405899) (xy 78.277276 -66.443828) (xy 78.258377 -66.485853)
			(xy 78.247365 -66.530597) (xy 78.244601 -66.576594) (xy 78.250175 -66.622334) (xy 78.263906 -66.66632)
			(xy 78.285342 -66.70711) (xy 78.313781 -66.743366) (xy 78.348291 -66.773901) (xy 78.387741 -66.797712)
			(xy 78.430837 -66.814021) (xy 78.476168 -66.822292) (xy 78.499208 -66.822828) (xy 78.794356 -66.822828)
			(xy 81.37906 -64.238124) (xy 81.39361 -64.221364) (xy 81.417216 -64.183784) (xy 81.433936 -64.142675)
			(xy 81.443261 -64.099286) (xy 81.444909 -64.054938) (xy 81.438828 -64.010977) (xy 81.425204 -63.968741)
			(xy 81.404451 -63.929513) (xy 81.377199 -63.894486) (xy 81.344278 -63.864725) (xy 81.32572 -63.852552)
			(xy 81.302381 -63.83777) (xy 81.259831 -63.802536) (xy 81.222808 -63.761533) (xy 81.192086 -63.715619)
			(xy 81.168308 -63.665753) (xy 81.151972 -63.61298) (xy 81.143418 -63.558402) (xy 81.142827 -63.50316)
			(xy 81.150209 -63.448412) (xy 81.165411 -63.3953) (xy 81.188115 -63.344937) (xy 81.217847 -63.298375)
			(xy 81.253983 -63.256588) (xy 81.295768 -63.220451) (xy 81.34233 -63.190719) (xy 81.392692 -63.168014)
			(xy 81.445804 -63.152811) (xy 81.500552 -63.145427) (xy 81.555794 -63.146018) (xy 81.610372 -63.15457)
			(xy 81.663146 -63.170905) (xy 81.713012 -63.194682) (xy 81.758927 -63.225403) (xy 81.79993 -63.262425)
			(xy 81.835165 -63.304975) (xy 81.849976 -63.328296) (xy 81.862186 -63.346826) (xy 81.891953 -63.379733)
			(xy 81.926979 -63.406972) (xy 81.966203 -63.427719) (xy 82.008432 -63.441341) (xy 82.052385 -63.447427)
			(xy 82.096726 -63.44579) (xy 82.140111 -63.436482) (xy 82.181221 -63.419784) (xy 82.218809 -63.396203)
			(xy 82.235548 -63.381636) (xy 89.50706 -56.110124) (xy 94.398592 -56.110124) (xy 99.309682 -51.199034)
			(xy 99.309682 -43.086782) (xy 99.309936 -39.741348) (xy 99.309936 -21.593048) (xy 96.144588 -18.4277)
			(xy 96.128534 -18.412298) (xy 96.09208 -18.386801) (xy 96.051743 -18.368041) (xy 96.008756 -18.356592)
			(xy 95.964432 -18.352803) (xy 95.920125 -18.35679) (xy 95.87719 -18.368431) (xy 95.836937 -18.38737)
			(xy 95.800597 -18.41303) (xy 95.769281 -18.444625) (xy 95.743944 -18.481191) (xy 95.725362 -18.52161)
			(xy 95.714102 -18.564647) (xy 95.710508 -18.608987) (xy 95.71469 -18.653276) (xy 95.720154 -18.674842)
			(xy 95.747822 -18.766061) (xy 95.79639 -18.950413) (xy 95.837145 -19.136648) (xy 95.870016 -19.324435)
			(xy 95.894942 -19.513441) (xy 95.911881 -19.703329) (xy 95.920802 -19.893763) (xy 95.921689 -20.084403)
			(xy 95.914541 -20.274911) (xy 95.89937 -20.464949) (xy 95.876203 -20.654179) (xy 95.845081 -20.842264)
			(xy 95.80606 -21.02887) (xy 95.75921 -21.213666) (xy 95.704612 -21.396323) (xy 95.642365 -21.576517)
			(xy 95.572579 -21.753927) (xy 95.495378 -21.928239) (xy 95.410899 -22.099142) (xy 95.319292 -22.266332)
			(xy 95.220721 -22.429514) (xy 95.115359 -22.588396) (xy 95.003395 -22.742696) (xy 94.885028 -22.89214)
			(xy 94.760467 -23.036463) (xy 94.629934 -23.175408) (xy 94.493662 -23.308729) (xy 94.351891 -23.436187)
			(xy 94.204875 -23.557557) (xy 94.052874 -23.672624) (xy 93.896159 -23.781182) (xy 93.735008 -23.883038)
			(xy 93.569707 -23.978013) (xy 93.40055 -24.065936) (xy 93.227838 -24.146652) (xy 93.051878 -24.220017)
			(xy 92.872982 -24.285902) (xy 92.691468 -24.344187) (xy 92.507659 -24.394772) (xy 92.321881 -24.437564)
			(xy 92.134465 -24.472489) (xy 91.945744 -24.499484) (xy 91.756052 -24.518501) (xy 91.565728 -24.529507)
			(xy 91.375109 -24.532481) (xy 91.184534 -24.52742) (xy 90.994341 -24.514331) (xy 90.804869 -24.493237)
			(xy 90.616455 -24.464177) (xy 90.429432 -24.427202) (xy 90.244135 -24.382378) (xy 90.06089 -24.329784)
			(xy 89.880026 -24.269514) (xy 89.701862 -24.201675) (xy 89.526715 -24.126387) (xy 89.354898 -24.043785)
			(xy 89.186714 -23.954015) (xy 89.022463 -23.857236) (xy 88.862437 -23.753621) (xy 88.706919 -23.643353)
			(xy 88.556188 -23.526629) (xy 88.410509 -23.403656) (xy 88.270143 -23.274653) (xy 88.135339 -23.139849)
			(xy 88.006335 -22.999482) (xy 87.883362 -22.853804) (xy 87.766638 -22.703073) (xy 87.656371 -22.547556)
			(xy 87.552755 -22.387529) (xy 87.455977 -22.223278) (xy 87.366206 -22.055095) (xy 87.283604 -21.883277)
			(xy 87.208316 -21.70813) (xy 87.140477 -21.529967) (xy 87.080206 -21.349102) (xy 87.027612 -21.165858)
			(xy 86.982788 -20.98056) (xy 86.945813 -20.793538) (xy 86.916753 -20.605123) (xy 86.89566 -20.415651)
			(xy 86.88257 -20.225459) (xy 86.877509 -20.034884) (xy 86.880483 -19.844265) (xy 86.891489 -19.65394)
			(xy 86.910506 -19.464249) (xy 86.937501 -19.275527) (xy 86.972425 -19.088111) (xy 87.015218 -18.902333)
			(xy 87.065802 -18.718524) (xy 87.124088 -18.537011) (xy 87.189972 -18.358114) (xy 87.263337 -18.182154)
			(xy 87.344053 -18.009442) (xy 87.431976 -17.840285) (xy 87.52695 -17.674984) (xy 87.628807 -17.513833)
			(xy 87.737365 -17.357118) (xy 87.852431 -17.205117) (xy 87.973801 -17.058101) (xy 88.10126 -16.91633)
			(xy 88.23458 -16.780057) (xy 88.373525 -16.649525) (xy 88.517848 -16.524964) (xy 88.667292 -16.406596)
			(xy 88.821592 -16.294632) (xy 88.980474 -16.189271) (xy 89.143656 -16.090699) (xy 89.310846 -15.999092)
			(xy 89.481749 -15.914613) (xy 89.656061 -15.837412) (xy 89.833471 -15.767626) (xy 90.013665 -15.705378)
			(xy 90.196322 -15.650781) (xy 90.381118 -15.60393) (xy 90.567724 -15.564909) (xy 90.755809 -15.533788)
			(xy 90.945038 -15.510621) (xy 91.135076 -15.495449) (xy 91.325584 -15.488301) (xy 91.516225 -15.489188)
			(xy 91.706658 -15.498109) (xy 91.896547 -15.515047) (xy 92.085552 -15.539974) (xy 92.27334 -15.572844)
			(xy 92.459575 -15.6136) (xy 92.643927 -15.662168) (xy 92.735146 -15.689834) (xy 92.756711 -15.695307)
			(xy 92.801001 -15.699491) (xy 92.845344 -15.695898) (xy 92.888383 -15.684639) (xy 92.928804 -15.666057)
			(xy 92.965372 -15.64072) (xy 92.996968 -15.609402) (xy 93.022629 -15.573061) (xy 93.041569 -15.532807)
			(xy 93.05321 -15.489869) (xy 93.057196 -15.445561) (xy 93.053405 -15.401235) (xy 93.041953 -15.358246)
			(xy 93.023191 -15.317909) (xy 92.997691 -15.281455) (xy 92.982288 -15.2654) (xy 91.348814 -13.631926)
			(xy 91.317318 -13.622782) (xy 91.290919 -13.614704) (xy 91.240599 -13.591997) (xy 91.194076 -13.562276)
			(xy 91.152323 -13.52616) (xy 91.11621 -13.484404) (xy 91.086491 -13.437879) (xy 91.063787 -13.387558)
			(xy 91.055698 -13.361162) (xy 91.046554 -13.329666) (xy 90.64879 -12.931902) (xy 90.48242 -12.765532)
			(xy 89.16035 -11.443208) (xy 87.818722 -11.443208) (xy 86.486492 -10.111232) (xy 86.318852 -9.943592)
			(xy 85.918802 -9.543542) (xy 85.908362 -9.533577) (xy 85.883947 -9.518201) (xy 85.856698 -9.508714)
			(xy 85.828012 -9.505601) (xy 85.813646 -9.506966) (xy 85.79993 -9.508744) (xy 85.79358 -9.510268)
			(xy 85.756794 -9.517892) (xy 85.682135 -9.526273) (xy 85.607008 -9.526745) (xy 85.532249 -9.519303)
			(xy 85.458689 -9.50403) (xy 85.387147 -9.481095) (xy 85.318418 -9.450753) (xy 85.253267 -9.413342)
			(xy 85.192417 -9.369278) (xy 85.136546 -9.319052) (xy 85.086275 -9.26322) (xy 85.042163 -9.202406)
			(xy 85.004701 -9.137284) (xy 84.974305 -9.068579) (xy 84.951314 -8.997055) (xy 84.935982 -8.923507)
			(xy 84.928481 -8.848754) (xy 84.928894 -8.773627) (xy 84.937216 -8.69896) (xy 84.953355 -8.625586)
			(xy 84.977132 -8.554319) (xy 85.008281 -8.485952) (xy 85.046456 -8.421246) (xy 85.091234 -8.36092)
			(xy 85.142115 -8.305644) (xy 85.198535 -8.256035) (xy 85.259865 -8.212642) (xy 85.325424 -8.17595)
			(xy 85.394482 -8.146365) (xy 85.466272 -8.124218) (xy 85.539995 -8.109754) (xy 85.614831 -8.103134)
			(xy 85.689949 -8.104432) (xy 85.764512 -8.113633) (xy 85.837691 -8.130635) (xy 85.908673 -8.15525)
			(xy 85.976668 -8.187202) (xy 86.04092 -8.226137) (xy 86.100715 -8.271622) (xy 86.155387 -8.323151)
			(xy 86.204328 -8.380152) (xy 86.246995 -8.441989) (xy 86.282913 -8.507975) (xy 86.311682 -8.577377)
			(xy 86.332982 -8.649423) (xy 86.340188 -8.686292) (xy 86.343465 -8.701655) (xy 86.356484 -8.730233)
			(xy 86.376093 -8.754762) (xy 86.401104 -8.773752) (xy 86.429999 -8.786051) (xy 86.461024 -8.790914)
			(xy 86.492296 -8.788044) (xy 86.521918 -8.777616) (xy 86.548092 -8.760264) (xy 86.569229 -8.737039)
			(xy 86.584048 -8.709351) (xy 86.591648 -8.678881) (xy 86.592156 -8.663178) (xy 86.592156 -8.256016)
			(xy 86.591686 -8.239921) (xy 86.583628 -8.208756) (xy 86.568022 -8.180602) (xy 86.545862 -8.157254)
			(xy 86.532466 -8.14832) (xy 86.500921 -8.128012) (xy 86.441858 -8.081746) (xy 86.38799 -8.029522)
			(xy 86.339917 -7.97192) (xy 86.29817 -7.90958) (xy 86.263214 -7.843194) (xy 86.235437 -7.773498)
			(xy 86.215147 -7.701267) (xy 86.202569 -7.627302) (xy 86.197843 -7.552424) (xy 86.201021 -7.477464)
			(xy 86.212069 -7.403255) (xy 86.230863 -7.33062) (xy 86.257195 -7.260366) (xy 86.290772 -7.193272)
			(xy 86.331223 -7.130083) (xy 86.378097 -7.071501) (xy 86.430874 -7.018175) (xy 86.488969 -6.970699)
			(xy 86.551737 -6.929598) (xy 86.61848 -6.89533) (xy 86.688459 -6.868274) (xy 86.760896 -6.848731)
			(xy 86.834987 -6.836917) (xy 86.90991 -6.832965) (xy 86.984833 -6.836917) (xy 87.058924 -6.848731)
			(xy 87.131361 -6.868274) (xy 87.20134 -6.89533) (xy 87.268083 -6.929598) (xy 87.330851 -6.970699)
			(xy 87.388946 -7.018175) (xy 87.441723 -7.071501) (xy 87.488597 -7.130083) (xy 87.529048 -7.193272)
			(xy 87.562625 -7.260366) (xy 87.588957 -7.33062) (xy 87.607751 -7.403255) (xy 87.618799 -7.477464)
			(xy 87.621977 -7.552424) (xy 87.617251 -7.627302) (xy 87.604673 -7.701267) (xy 87.584383 -7.773498)
			(xy 87.556606 -7.843194) (xy 87.52165 -7.90958) (xy 87.479903 -7.97192) (xy 87.43183 -8.029522) (xy 87.377962 -8.081746)
			(xy 87.318899 -8.128012) (xy 87.287354 -8.14832) (xy 87.27396 -8.157253) (xy 87.251812 -8.180607)
			(xy 87.236216 -8.208761) (xy 87.228163 -8.239923) (xy 87.227664 -8.256016) (xy 87.227664 -8.62584)
			(xy 87.228131 -8.64187) (xy 87.236126 -8.672916) (xy 87.251604 -8.700992) (xy 87.273587 -8.724328)
			(xy 87.30069 -8.741452) (xy 87.331204 -8.751285) (xy 87.363206 -8.753208) (xy 87.394678 -8.747098)
			(xy 87.423636 -8.733341) (xy 87.436198 -8.723376) (xy 87.478108 -8.688324) (xy 87.488014 -8.64743)
			(xy 87.49712 -8.611935) (xy 87.521638 -8.542875) (xy 87.553112 -8.476696) (xy 87.591212 -8.414096)
			(xy 87.635534 -8.355736) (xy 87.660226 -8.32866) (xy 87.686838 -8.300991) (xy 87.745041 -8.250924)
			(xy 87.808294 -8.207412) (xy 87.875863 -8.17096) (xy 87.946962 -8.141992) (xy 88.020765 -8.120844)
			(xy 88.096416 -8.107761) (xy 88.173036 -8.102896) (xy 88.211406 -8.104124) (xy 88.249605 -8.106318)
			(xy 88.325243 -8.11788) (xy 88.399204 -8.137492) (xy 88.470633 -8.164927) (xy 88.538706 -8.199869)
			(xy 88.602635 -8.241915) (xy 88.661684 -8.290578) (xy 88.715169 -8.345297) (xy 88.762473 -8.405439)
			(xy 88.78316 -8.437626) (xy 88.79209 -8.451027) (xy 88.81544 -8.473189) (xy 88.843594 -8.488801)
			(xy 88.87476 -8.496869) (xy 88.890856 -8.497316) (xy 89.230454 -8.497316) (xy 89.47912 -8.745728)
			(xy 89.510362 -8.77697) (xy 89.585292 -8.8519) (xy 89.602051 -8.867933) (xy 89.640248 -8.894232)
			(xy 89.682583 -8.913165) (xy 89.72765 -8.924102) (xy 89.773953 -8.926681) (xy 89.819956 -8.920817)
			(xy 89.864131 -8.906703) (xy 89.905013 -8.884809) (xy 89.941244 -8.855861) (xy 89.971621 -8.82082)
			(xy 89.995137 -8.780849) (xy 90.01101 -8.737275) (xy 90.015314 -8.714486) (xy 90.018518 -8.693316)
			(xy 90.027161 -8.651378) (xy 90.032586 -8.630666) (xy 90.043085 -8.593575) (xy 90.071001 -8.521719)
			(xy 90.106513 -8.453298) (xy 90.149207 -8.389112) (xy 90.198582 -8.329911) (xy 90.254062 -8.276389)
			(xy 90.314997 -8.229171) (xy 90.347546 -8.208518) (xy 90.372692 -8.193786) (xy 90.392922 -8.181875)
			(xy 90.429012 -8.151861) (xy 90.458976 -8.11573) (xy 90.481796 -8.074711) (xy 90.496696 -8.030199)
			(xy 90.50317 -7.983708) (xy 90.500996 -7.936818) (xy 90.490249 -7.891126) (xy 90.471295 -7.848183)
			(xy 90.444778 -7.809451) (xy 90.428572 -7.792466) (xy 90.340688 -7.704582) (xy 90.328588 -7.693219)
			(xy 90.299878 -7.676584) (xy 90.267847 -7.667925) (xy 90.234667 -7.667832) (xy 90.202587 -7.676309)
			(xy 90.173784 -7.692782) (xy 90.161618 -7.704074) (xy 90.139012 -7.726426) (xy 90.129614 -7.756652)
			(xy 90.118006 -7.792323) (xy 90.088303 -7.861212) (xy 90.05152 -7.926594) (xy 90.008066 -7.987746)
			(xy 89.958421 -8.04399) (xy 89.903137 -8.0947) (xy 89.842827 -8.139316) (xy 89.77816 -8.177342) (xy 89.709852 -8.208357)
			(xy 89.638661 -8.232016) (xy 89.565377 -8.248058) (xy 89.490813 -8.256304) (xy 89.415795 -8.256663)
			(xy 89.341155 -8.249131) (xy 89.267721 -8.233791) (xy 89.196307 -8.210814) (xy 89.127705 -8.180454)
			(xy 89.062677 -8.143049) (xy 89.001943 -8.099012) (xy 88.946176 -8.048833) (xy 88.895996 -7.993067)
			(xy 88.851958 -7.932334) (xy 88.814552 -7.867306) (xy 88.784191 -7.798705) (xy 88.761212 -7.727292)
			(xy 88.745871 -7.653858) (xy 88.738338 -7.579218) (xy 88.738696 -7.5042) (xy 88.74694 -7.429635)
			(xy 88.76298 -7.356351) (xy 88.786638 -7.28516) (xy 88.817652 -7.216852) (xy 88.855677 -7.152184)
			(xy 88.900291 -7.091873) (xy 88.951001 -7.036588) (xy 89.007243 -6.986943) (xy 89.068394 -6.943487)
			(xy 89.133777 -6.906703) (xy 89.202664 -6.876999) (xy 89.238328 -6.865366) (xy 89.2683 -6.855968)
			(xy 89.290398 -6.83387) (xy 89.301751 -6.8217) (xy 89.318338 -6.792863) (xy 89.326921 -6.760721)
			(xy 89.326917 -6.727453) (xy 89.318328 -6.695312) (xy 89.301734 -6.666478) (xy 89.290398 -6.654292)
			(xy 89.277698 -6.641592) (xy 89.272364 -6.636258) (xy 89.229184 -6.592824) (xy 88.890856 -6.592824)
			(xy 88.874764 -6.593301) (xy 88.843608 -6.601369) (xy 88.815464 -6.616981) (xy 88.792125 -6.639141)
			(xy 88.78316 -6.652514) (xy 88.762854 -6.68406) (xy 88.71659 -6.743124) (xy 88.664369 -6.796994)
			(xy 88.60677 -6.84507) (xy 88.544432 -6.886818) (xy 88.478048 -6.921777) (xy 88.408354 -6.949557)
			(xy 88.336124 -6.96985) (xy 88.26216 -6.98243) (xy 88.187282 -6.987159) (xy 88.112323 -6.983984)
			(xy 88.038114 -6.972939) (xy 87.965479 -6.954148) (xy 87.895224 -6.927819) (xy 87.828129 -6.894245)
			(xy 87.764939 -6.853797) (xy 87.706356 -6.806926) (xy 87.653029 -6.754151) (xy 87.605551 -6.696058)
			(xy 87.564448 -6.633292) (xy 87.530177 -6.566551) (xy 87.503119 -6.496573) (xy 87.483573 -6.424138)
			(xy 87.471758 -6.350048) (xy 87.467802 -6.275125) (xy 87.471752 -6.200203) (xy 87.483563 -6.126112)
			(xy 87.503103 -6.053675) (xy 87.530157 -5.983696) (xy 87.564422 -5.916952) (xy 87.605521 -5.854183)
			(xy 87.652995 -5.796087) (xy 87.706318 -5.743308) (xy 87.764898 -5.696432) (xy 87.828085 -5.65598)
			(xy 87.895178 -5.622401) (xy 87.965431 -5.596067) (xy 88.038064 -5.577271) (xy 88.112273 -5.566221)
			(xy 88.187232 -5.56304) (xy 88.262109 -5.567764) (xy 88.336074 -5.580339) (xy 88.408305 -5.600627)
			(xy 88.478001 -5.628402) (xy 88.544388 -5.663355) (xy 88.606729 -5.7051) (xy 88.664331 -5.753172)
			(xy 88.716557 -5.807037) (xy 88.762824 -5.866099) (xy 88.78316 -5.897626) (xy 88.79209 -5.911027)
			(xy 88.81544 -5.933189) (xy 88.843594 -5.948801) (xy 88.87476 -5.956869) (xy 88.890856 -5.957316)
			(xy 89.261188 -5.957316) (xy 89.277211 -5.956844) (xy 89.308244 -5.948841) (xy 89.336305 -5.933362)
			(xy 89.359627 -5.911382) (xy 89.376741 -5.884287) (xy 89.386567 -5.853783) (xy 89.388487 -5.821793)
			(xy 89.38238 -5.790333) (xy 89.36863 -5.761385) (xy 89.358724 -5.748782) (xy 89.323672 -5.706872)
			(xy 89.282778 -5.696966) (xy 89.246523 -5.687716) (xy 89.176033 -5.662614) (xy 89.108565 -5.630254)
			(xy 89.044865 -5.590996) (xy 88.985634 -5.545271) (xy 88.931527 -5.493585) (xy 88.883142 -5.436507)
			(xy 88.841011 -5.374669) (xy 88.8056 -5.308752) (xy 88.777299 -5.239483) (xy 88.756422 -5.167628)
			(xy 88.743198 -5.09398) (xy 88.737773 -5.01935) (xy 88.740208 -4.944563) (xy 88.750475 -4.870444)
			(xy 88.768461 -4.797812) (xy 88.793968 -4.727467) (xy 88.826713 -4.660186) (xy 88.866337 -4.596711)
			(xy 88.9124 -4.537744) (xy 88.964396 -4.483935) (xy 89.02175 -4.435877) (xy 89.083829 -4.394101)
			(xy 89.149948 -4.359069) (xy 89.219378 -4.331166) (xy 89.291351 -4.310701) (xy 89.365074 -4.2979)
			(xy 89.439734 -4.292903) (xy 89.514506 -4.295767) (xy 89.588564 -4.306459) (xy 89.661093 -4.324861)
			(xy 89.73129 -4.350771) (xy 89.798382 -4.383902) (xy 89.861629 -4.423888) (xy 89.920331 -4.470289)
			(xy 89.973841 -4.522593) (xy 90.021569 -4.580221) (xy 90.062988 -4.642539) (xy 90.097641 -4.708858)
			(xy 90.125145 -4.778446) (xy 90.145197 -4.850536) (xy 90.157575 -4.924331) (xy 90.162143 -4.999018)
			(xy 90.161876 -5.00507) (xy 91.277697 -5.00507) (xy 91.281732 -4.929366) (xy 91.293791 -4.854521)
			(xy 91.313737 -4.78138) (xy 91.341344 -4.710775) (xy 91.3763 -4.643504) (xy 91.418208 -4.580329)
			(xy 91.466594 -4.521967) (xy 91.52091 -4.469079) (xy 91.580539 -4.422264) (xy 91.644807 -4.382052)
			(xy 91.712984 -4.3489) (xy 91.7843 -4.323182) (xy 91.857945 -4.30519) (xy 91.933085 -4.295128) (xy 92.008869 -4.293109)
			(xy 92.084439 -4.299158) (xy 92.158937 -4.313205) (xy 92.23152 -4.335091) (xy 92.301366 -4.364568)
			(xy 92.367683 -4.401303) (xy 92.429719 -4.444878) (xy 92.486772 -4.4948) (xy 92.538196 -4.550504)
			(xy 92.583407 -4.611359) (xy 92.621894 -4.676674) (xy 92.65322 -4.74571) (xy 92.67703 -4.817685)
			(xy 92.693055 -4.891783) (xy 92.701114 -4.967164) (xy 92.701618 -5.00507) (xy 92.701114 -5.042976)
			(xy 92.693055 -5.118357) (xy 92.67703 -5.192455) (xy 92.65322 -5.26443) (xy 92.621894 -5.333466)
			(xy 92.583407 -5.398781) (xy 92.538196 -5.459636) (xy 92.486772 -5.51534) (xy 92.429719 -5.565262)
			(xy 92.367683 -5.608837) (xy 92.301366 -5.645572) (xy 92.23152 -5.675049) (xy 92.158937 -5.696935)
			(xy 92.084439 -5.710982) (xy 92.008869 -5.717031) (xy 91.933085 -5.715012) (xy 91.857945 -5.70495)
			(xy 91.7843 -5.686958) (xy 91.712984 -5.66124) (xy 91.644807 -5.628088) (xy 91.580539 -5.587876)
			(xy 91.52091 -5.541061) (xy 91.466594 -5.488173) (xy 91.418208 -5.429811) (xy 91.3763 -5.366636)
			(xy 91.341344 -5.299365) (xy 91.313737 -5.22876) (xy 91.293791 -5.155619) (xy 91.281732 -5.080774)
			(xy 91.277697 -5.00507) (xy 90.161876 -5.00507) (xy 90.158851 -5.073772) (xy 90.147735 -5.147769)
			(xy 90.128917 -5.22019) (xy 90.102605 -5.290238) (xy 90.06909 -5.357139) (xy 90.028741 -5.420155)
			(xy 89.982004 -5.47859) (xy 89.929395 -5.5318) (xy 89.871493 -5.579196) (xy 89.808939 -5.620257)
			(xy 89.742423 -5.654529) (xy 89.70772 -5.668518) (xy 89.68652 -5.677284) (xy 89.647442 -5.701306)
			(xy 89.613311 -5.731954) (xy 89.585236 -5.76823) (xy 89.564131 -5.808958) (xy 89.55068 -5.852813)
			(xy 89.545321 -5.89837) (xy 89.548228 -5.944149) (xy 89.559306 -5.988663) (xy 89.578196 -6.030464)
			(xy 89.604283 -6.068195) (xy 89.62009 -6.084824) (xy 89.640156 -6.10489) (xy 89.656725 -6.120759)
			(xy 89.694464 -6.146843) (xy 89.736272 -6.165727) (xy 89.780791 -6.176798) (xy 89.826575 -6.179697)
			(xy 89.872135 -6.17433) (xy 89.915992 -6.16087) (xy 89.956719 -6.139755) (xy 89.992994 -6.111672)
			(xy 90.023638 -6.077532) (xy 90.047654 -6.038446) (xy 90.056462 -6.01726) (xy 90.070771 -5.981831)
			(xy 90.105921 -5.913984) (xy 90.148136 -5.850292) (xy 90.196931 -5.79149) (xy 90.251744 -5.738252)
			(xy 90.311945 -5.691192) (xy 90.376841 -5.650852) (xy 90.445684 -5.617695) (xy 90.517683 -5.592104)
			(xy 90.592009 -5.574372) (xy 90.667806 -5.564704) (xy 90.744204 -5.563212) (xy 90.820321 -5.569911)
			(xy 90.895283 -5.584726) (xy 90.968226 -5.607485) (xy 91.038312 -5.637927) (xy 91.104734 -5.675702)
			(xy 91.166727 -5.720374) (xy 91.223578 -5.77143) (xy 91.274633 -5.828282) (xy 91.319304 -5.890276)
			(xy 91.357078 -5.956698) (xy 91.387519 -6.026784) (xy 91.410277 -6.099728) (xy 91.42509 -6.17469)
			(xy 91.431789 -6.250808) (xy 91.430295 -6.327205) (xy 91.420626 -6.403003) (xy 91.402893 -6.477328)
			(xy 91.3773 -6.549327) (xy 91.344143 -6.618169) (xy 91.303801 -6.683064) (xy 91.256741 -6.743264)
			(xy 91.203502 -6.798077) (xy 91.144698 -6.846871) (xy 91.081006 -6.889085) (xy 91.013158 -6.924234)
			(xy 90.97772 -6.938518) (xy 90.95652 -6.947284) (xy 90.917442 -6.971306) (xy 90.883311 -7.001954)
			(xy 90.855236 -7.03823) (xy 90.834131 -7.078958) (xy 90.82068 -7.122813) (xy 90.815321 -7.16837)
			(xy 90.818228 -7.214149) (xy 90.829306 -7.258663) (xy 90.848196 -7.300464) (xy 90.874283 -7.338195)
			(xy 90.89009 -7.354824) (xy 90.910156 -7.37489) (xy 90.926725 -7.390759) (xy 90.964464 -7.416843)
			(xy 91.006272 -7.435727) (xy 91.050791 -7.446798) (xy 91.096575 -7.449697) (xy 91.142135 -7.44433)
			(xy 91.185992 -7.43087) (xy 91.226719 -7.409755) (xy 91.262994 -7.381672) (xy 91.293638 -7.347532)
			(xy 91.317654 -7.308446) (xy 91.326462 -7.28726) (xy 91.340771 -7.251831) (xy 91.375921 -7.183984)
			(xy 91.418136 -7.120292) (xy 91.466931 -7.06149) (xy 91.521744 -7.008252) (xy 91.581945 -6.961192)
			(xy 91.646841 -6.920852) (xy 91.715684 -6.887695) (xy 91.787683 -6.862104) (xy 91.862009 -6.844372)
			(xy 91.937806 -6.834704) (xy 92.014204 -6.833212) (xy 92.090321 -6.839911) (xy 92.165283 -6.854726)
			(xy 92.238226 -6.877485) (xy 92.308312 -6.907927) (xy 92.374734 -6.945702) (xy 92.436727 -6.990374)
			(xy 92.493578 -7.04143) (xy 92.544633 -7.098282) (xy 92.589304 -7.160276) (xy 92.627078 -7.226698)
			(xy 92.657519 -7.296784) (xy 92.680277 -7.369728) (xy 92.69509 -7.44469) (xy 92.701789 -7.520808)
			(xy 92.700295 -7.597205) (xy 92.690626 -7.673003) (xy 92.672893 -7.747328) (xy 92.6473 -7.819327)
			(xy 92.614143 -7.888169) (xy 92.573801 -7.953064) (xy 92.526741 -8.013264) (xy 92.473502 -8.068077)
			(xy 92.414698 -8.116871) (xy 92.351006 -8.159085) (xy 92.283158 -8.194234) (xy 92.24772 -8.208518)
			(xy 92.22652 -8.217284) (xy 92.187442 -8.241306) (xy 92.166534 -8.26008) (xy 93.154506 -8.26008)
			(xy 93.158522 -8.14381) (xy 93.170549 -8.028095) (xy 93.190531 -7.913485) (xy 93.218373 -7.800526)
			(xy 93.253942 -7.689758) (xy 93.297068 -7.581707) (xy 93.347545 -7.476889) (xy 93.405134 -7.375804)
			(xy 93.46956 -7.278932) (xy 93.540515 -7.186736) (xy 93.617662 -7.099655) (xy 93.700633 -7.018104)
			(xy 93.789033 -6.942472) (xy 93.88244 -6.873118) (xy 93.980409 -6.810375) (xy 94.082473 -6.754539)
			(xy 94.188147 -6.705878) (xy 94.296926 -6.664624) (xy 94.408291 -6.630973) (xy 94.521714 -6.605085)
			(xy 94.636651 -6.587084) (xy 94.752557 -6.577055) (xy 94.868879 -6.575047) (xy 94.985062 -6.581069)
			(xy 95.100553 -6.595092) (xy 95.214801 -6.61705) (xy 95.327262 -6.646837) (xy 95.4374 -6.684312)
			(xy 95.54469 -6.729297) (xy 95.648621 -6.781576) (xy 95.748697 -6.840901) (xy 95.844443 -6.906989)
			(xy 95.9354 -6.979525) (xy 96.021136 -7.058164) (xy 96.101243 -7.14253) (xy 96.175339 -7.232222)
			(xy 96.243069 -7.326812) (xy 96.304113 -7.42585) (xy 96.358178 -7.528863) (xy 96.405008 -7.63536)
			(xy 96.444379 -7.744835) (xy 96.476103 -7.856765) (xy 96.500029 -7.970617) (xy 96.516043 -8.085849)
			(xy 96.52407 -8.201911) (xy 96.524572 -8.26008) (xy 96.52407 -8.318249) (xy 96.516043 -8.434311)
			(xy 96.500029 -8.549543) (xy 96.476103 -8.663395) (xy 96.444379 -8.775325) (xy 96.405008 -8.8848)
			(xy 96.358178 -8.991297) (xy 96.304113 -9.09431) (xy 96.243069 -9.193348) (xy 96.175339 -9.287938)
			(xy 96.101243 -9.37763) (xy 96.021136 -9.461996) (xy 95.9354 -9.540635) (xy 95.844443 -9.613171)
			(xy 95.748697 -9.679259) (xy 95.648621 -9.738584) (xy 95.54469 -9.790863) (xy 95.4374 -9.835848)
			(xy 95.327262 -9.873323) (xy 95.214801 -9.90311) (xy 95.100553 -9.925068) (xy 94.985062 -9.939091)
			(xy 94.868879 -9.945113) (xy 94.752557 -9.943105) (xy 94.636651 -9.933076) (xy 94.521714 -9.915075)
			(xy 94.408291 -9.889187) (xy 94.296926 -9.855536) (xy 94.188147 -9.814282) (xy 94.082473 -9.765621)
			(xy 93.980409 -9.709785) (xy 93.88244 -9.647042) (xy 93.789033 -9.577688) (xy 93.700633 -9.502056)
			(xy 93.617662 -9.420505) (xy 93.540515 -9.333424) (xy 93.46956 -9.241228) (xy 93.405134 -9.144356)
			(xy 93.347545 -9.043271) (xy 93.297068 -8.938453) (xy 93.253942 -8.830402) (xy 93.218373 -8.719634)
			(xy 93.190531 -8.606675) (xy 93.170549 -8.492065) (xy 93.158522 -8.37635) (xy 93.154506 -8.26008)
			(xy 92.166534 -8.26008) (xy 92.153311 -8.271954) (xy 92.125236 -8.30823) (xy 92.104131 -8.348958)
			(xy 92.09068 -8.392813) (xy 92.085321 -8.43837) (xy 92.088228 -8.484149) (xy 92.099306 -8.528663)
			(xy 92.118196 -8.570464) (xy 92.144283 -8.608195) (xy 92.16009 -8.624824) (xy 96.40824 -12.872974)
			(xy 96.439228 -12.882118) (xy 96.465174 -12.890271) (xy 96.514625 -12.912905) (xy 96.560361 -12.942331)
			(xy 96.601456 -12.977953) (xy 96.637076 -13.019049) (xy 96.666501 -13.064786) (xy 96.689133 -13.114238)
			(xy 96.697292 -13.140182) (xy 96.706436 -13.17117) (xy 101.041454 -17.506188) (xy 101.058094 -17.522117)
			(xy 101.096002 -17.548277) (xy 101.138006 -17.567177) (xy 101.182727 -17.578196) (xy 101.228702 -17.580974)
			(xy 101.274425 -17.575419) (xy 101.318398 -17.561714) (xy 101.359181 -17.540308) (xy 101.395437 -17.511902)
			(xy 101.42598 -17.477426) (xy 101.449808 -17.43801) (xy 101.466141 -17.394944) (xy 101.474445 -17.34964)
			(xy 101.475032 -17.32661) (xy 101.475032 -1.999996) (xy 101.474545 -1.968897) (xy 101.466426 -1.907232)
			(xy 101.450326 -1.847155) (xy 101.426523 -1.789693) (xy 101.395422 -1.73583) (xy 101.357556 -1.686487)
			(xy 101.313574 -1.642509) (xy 101.264227 -1.604649) (xy 101.210361 -1.573554) (xy 101.152896 -1.549757)
			(xy 101.092817 -1.533664) (xy 101.031151 -1.525551) (xy 101.000052 -1.525016) (xy 26.651966 -1.525016)
			(xy 26.635321 -1.525563) (xy 26.603168 -1.534187) (xy 26.574342 -1.550838) (xy 26.550808 -1.574382)
			(xy 26.534168 -1.603215) (xy 26.525557 -1.635371) (xy 26.524966 -1.652016) (xy 26.524966 -2.500122)
			(xy 26.524481 -2.576763) (xy 26.516717 -2.729848) (xy 26.50121 -2.882343) (xy 26.477998 -3.033857)
			(xy 26.447143 -3.184001) (xy 26.408722 -3.33239) (xy 26.362835 -3.478642) (xy 26.3096 -3.622382)
			(xy 26.249152 -3.763241) (xy 26.181648 -3.900858) (xy 26.10726 -4.034879) (xy 26.026179 -4.164961)
			(xy 25.938614 -4.290769) (xy 25.84479 -4.41198) (xy 25.744946 -4.528284) (xy 25.644946 -4.633484)
			(xy 29.519874 -4.633484) (xy 29.519874 -4.546584) (xy 29.527892 -4.460055) (xy 29.54386 -4.374635)
			(xy 29.567641 -4.291053) (xy 29.599033 -4.210021) (xy 29.637767 -4.132232) (xy 29.683514 -4.058348)
			(xy 29.735883 -3.989001) (xy 29.794427 -3.924781) (xy 29.858647 -3.866237) (xy 29.927994 -3.813868)
			(xy 30.001878 -3.768121) (xy 30.079667 -3.729387) (xy 30.160699 -3.697995) (xy 30.244281 -3.674214)
			(xy 30.329701 -3.658246) (xy 30.41623 -3.650228) (xy 30.50313 -3.650228) (xy 30.589659 -3.658246)
			(xy 30.675079 -3.674214) (xy 30.758661 -3.697995) (xy 30.839693 -3.729387) (xy 30.917482 -3.768121)
			(xy 30.991366 -3.813868) (xy 31.060713 -3.866237) (xy 31.124933 -3.924781) (xy 31.183477 -3.989001)
			(xy 31.235846 -4.058348) (xy 31.281593 -4.132232) (xy 31.320327 -4.210021) (xy 31.351719 -4.291053)
			(xy 31.3755 -4.374635) (xy 31.391468 -4.460055) (xy 31.399486 -4.546584) (xy 31.399988 -4.590034)
			(xy 31.399486 -4.633484) (xy 34.599874 -4.633484) (xy 34.599874 -4.546584) (xy 34.607892 -4.460055)
			(xy 34.62386 -4.374635) (xy 34.647641 -4.291053) (xy 34.679033 -4.210021) (xy 34.717767 -4.132232)
			(xy 34.763514 -4.058348) (xy 34.815883 -3.989001) (xy 34.874427 -3.924781) (xy 34.938647 -3.866237)
			(xy 35.007994 -3.813868) (xy 35.081878 -3.768121) (xy 35.159667 -3.729387) (xy 35.240699 -3.697995)
			(xy 35.324281 -3.674214) (xy 35.409701 -3.658246) (xy 35.49623 -3.650228) (xy 35.58313 -3.650228)
			(xy 35.669659 -3.658246) (xy 35.755079 -3.674214) (xy 35.838661 -3.697995) (xy 35.919693 -3.729387)
			(xy 35.997482 -3.768121) (xy 36.071366 -3.813868) (xy 36.140713 -3.866237) (xy 36.204933 -3.924781)
			(xy 36.263477 -3.989001) (xy 36.315846 -4.058348) (xy 36.361593 -4.132232) (xy 36.400327 -4.210021)
			(xy 36.431719 -4.291053) (xy 36.4555 -4.374635) (xy 36.471468 -4.460055) (xy 36.479486 -4.546584)
			(xy 36.479988 -4.590034) (xy 36.479486 -4.633484) (xy 36.471468 -4.720013) (xy 36.4555 -4.805433)
			(xy 36.431719 -4.889015) (xy 36.400327 -4.970047) (xy 36.361593 -5.047836) (xy 36.315846 -5.12172)
			(xy 36.263477 -5.191067) (xy 36.204933 -5.255287) (xy 36.140713 -5.313831) (xy 36.071366 -5.3662)
			(xy 35.997482 -5.411947) (xy 35.919693 -5.450681) (xy 35.838661 -5.482073) (xy 35.755079 -5.505854)
			(xy 35.669659 -5.521822) (xy 35.58313 -5.52984) (xy 35.49623 -5.52984) (xy 35.409701 -5.521822) (xy 35.324281 -5.505854)
			(xy 35.240699 -5.482073) (xy 35.159667 -5.450681) (xy 35.081878 -5.411947) (xy 35.007994 -5.3662)
			(xy 34.938647 -5.313831) (xy 34.874427 -5.255287) (xy 34.815883 -5.191067) (xy 34.763514 -5.12172)
			(xy 34.717767 -5.047836) (xy 34.679033 -4.970047) (xy 34.647641 -4.889015) (xy 34.62386 -4.805433)
			(xy 34.607892 -4.720013) (xy 34.599874 -4.633484) (xy 31.399486 -4.633484) (xy 31.391468 -4.720013)
			(xy 31.3755 -4.805433) (xy 31.351719 -4.889015) (xy 31.320327 -4.970047) (xy 31.281593 -5.047836)
			(xy 31.235846 -5.12172) (xy 31.183477 -5.191067) (xy 31.124933 -5.255287) (xy 31.060713 -5.313831)
			(xy 30.991366 -5.3662) (xy 30.917482 -5.411947) (xy 30.839693 -5.450681) (xy 30.758661 -5.482073)
			(xy 30.675079 -5.505854) (xy 30.589659 -5.521822) (xy 30.50313 -5.52984) (xy 30.41623 -5.52984) (xy 30.329701 -5.521822)
			(xy 30.244281 -5.505854) (xy 30.160699 -5.482073) (xy 30.079667 -5.450681) (xy 30.001878 -5.411947)
			(xy 29.927994 -5.3662) (xy 29.858647 -5.313831) (xy 29.794427 -5.255287) (xy 29.735883 -5.191067)
			(xy 29.683514 -5.12172) (xy 29.637767 -5.047836) (xy 29.599033 -4.970047) (xy 29.567641 -4.889015)
			(xy 29.54386 -4.805433) (xy 29.527892 -4.720013) (xy 29.519874 -4.633484) (xy 25.644946 -4.633484)
			(xy 25.63934 -4.639381) (xy 25.528243 -4.744987) (xy 25.411939 -4.844831) (xy 25.290727 -4.938655)
			(xy 25.164919 -5.02622) (xy 25.034838 -5.107301) (xy 24.900816 -5.181689) (xy 24.763199 -5.249193)
			(xy 24.62234 -5.30964) (xy 24.4786 -5.362876) (xy 24.332348 -5.408763) (xy 24.183959 -5.447183) (xy 24.033815 -5.478039)
			(xy 23.882301 -5.50125) (xy 23.729806 -5.516757) (xy 23.576721 -5.524521) (xy 23.50008 -5.525008)
			(xy 8.875776 -5.525008) (xy 8.852421 -5.525531) (xy 8.806495 -5.534052) (xy 8.7629 -5.550823) (xy 8.723103 -5.575278)
			(xy 8.688446 -5.606592) (xy 8.660094 -5.643713) (xy 8.639002 -5.68539) (xy 8.625882 -5.730219) (xy 8.621174 -5.776691)
			(xy 8.625038 -5.823241) (xy 8.637343 -5.868301) (xy 8.657675 -5.910353) (xy 8.685349 -5.947982) (xy 8.719433 -5.979921)
			(xy 8.73887 -5.992876) (xy 8.792956 -6.028129) (xy 8.89714 -6.104397) (xy 8.996401 -6.18697) (xy 9.090358 -6.275532)
			(xy 9.178651 -6.369743) (xy 9.260939 -6.46924) (xy 9.336908 -6.573643) (xy 9.402344 -6.67639) (xy 26.785314 -6.67639)
			(xy 26.789385 -6.620768) (xy 26.801511 -6.566331) (xy 26.821434 -6.51424) (xy 26.84873 -6.465605)
			(xy 26.882816 -6.421462) (xy 26.922965 -6.382753) (xy 26.968323 -6.350302) (xy 27.017923 -6.324801)
			(xy 27.070707 -6.306794) (xy 27.12555 -6.296664) (xy 27.181284 -6.294627) (xy 27.236721 -6.300727)
			(xy 27.290678 -6.314833) (xy 27.342007 -6.336645) (xy 27.389613 -6.365699) (xy 27.432481 -6.401374)
			(xy 27.469698 -6.442911) (xy 27.500471 -6.489424) (xy 27.524143 -6.539921) (xy 27.540211 -6.593328)
			(xy 27.548331 -6.648504) (xy 27.54884 -6.67639) (xy 27.548331 -6.704276) (xy 27.540211 -6.759452)
			(xy 27.524143 -6.812859) (xy 27.500471 -6.863356) (xy 27.469698 -6.909869) (xy 27.432481 -6.951406)
			(xy 27.389613 -6.987081) (xy 27.342007 -7.016135) (xy 27.290678 -7.037947) (xy 27.236721 -7.052053)
			(xy 27.181284 -7.058153) (xy 27.12555 -7.056116) (xy 27.070707 -7.045986) (xy 27.017923 -7.027979)
			(xy 26.968323 -7.002478) (xy 26.922965 -6.970027) (xy 26.882816 -6.931318) (xy 26.84873 -6.887175)
			(xy 26.821434 -6.83854) (xy 26.801511 -6.786449) (xy 26.789385 -6.732012) (xy 26.785314 -6.67639)
			(xy 9.402344 -6.67639) (xy 9.406266 -6.682549) (xy 9.468746 -6.795542) (xy 9.524109 -6.912187) (xy 9.572143 -7.032037)
			(xy 9.612661 -7.154632) (xy 9.617621 -7.173484) (xy 29.519874 -7.173484) (xy 29.519874 -7.086584)
			(xy 29.527892 -7.000055) (xy 29.54386 -6.914635) (xy 29.567641 -6.831053) (xy 29.599033 -6.750021)
			(xy 29.637767 -6.672232) (xy 29.683514 -6.598348) (xy 29.735883 -6.529001) (xy 29.794427 -6.464781)
			(xy 29.858647 -6.406237) (xy 29.927994 -6.353868) (xy 30.001878 -6.308121) (xy 30.079667 -6.269387)
			(xy 30.160699 -6.237995) (xy 30.244281 -6.214214) (xy 30.329701 -6.198246) (xy 30.41623 -6.190228)
			(xy 30.50313 -6.190228) (xy 30.589659 -6.198246) (xy 30.675079 -6.214214) (xy 30.758661 -6.237995)
			(xy 30.839693 -6.269387) (xy 30.917482 -6.308121) (xy 30.991366 -6.353868) (xy 31.060713 -6.406237)
			(xy 31.124933 -6.464781) (xy 31.183477 -6.529001) (xy 31.235846 -6.598348) (xy 31.281593 -6.672232)
			(xy 31.320327 -6.750021) (xy 31.351719 -6.831053) (xy 31.3755 -6.914635) (xy 31.391468 -7.000055)
			(xy 31.399486 -7.086584) (xy 31.399988 -7.130034) (xy 31.399486 -7.173484) (xy 34.599874 -7.173484)
			(xy 34.599874 -7.086584) (xy 34.607892 -7.000055) (xy 34.62386 -6.914635) (xy 34.647641 -6.831053)
			(xy 34.679033 -6.750021) (xy 34.717767 -6.672232) (xy 34.763514 -6.598348) (xy 34.815883 -6.529001)
			(xy 34.874427 -6.464781) (xy 34.938647 -6.406237) (xy 35.007994 -6.353868) (xy 35.081878 -6.308121)
			(xy 35.159667 -6.269387) (xy 35.240699 -6.237995) (xy 35.324281 -6.214214) (xy 35.409701 -6.198246)
			(xy 35.49623 -6.190228) (xy 35.58313 -6.190228) (xy 35.669659 -6.198246) (xy 35.755079 -6.214214)
			(xy 35.838661 -6.237995) (xy 35.919693 -6.269387) (xy 35.997482 -6.308121) (xy 36.071366 -6.353868)
			(xy 36.140713 -6.406237) (xy 36.204933 -6.464781) (xy 36.263477 -6.529001) (xy 36.315846 -6.598348)
			(xy 36.361593 -6.672232) (xy 36.400327 -6.750021) (xy 36.431719 -6.831053) (xy 36.454201 -6.91007)
			(xy 39.818564 -6.91007) (xy 39.819054 -6.852663) (xy 39.826889 -6.738117) (xy 39.842523 -6.624372)
			(xy 39.865882 -6.51196) (xy 39.896859 -6.401403) (xy 39.935308 -6.293218) (xy 39.98105 -6.18791)
			(xy 40.033872 -6.085968) (xy 40.093527 -5.987869) (xy 40.159738 -5.894069) (xy 40.232196 -5.805007)
			(xy 40.310562 -5.721096) (xy 40.394473 -5.64273) (xy 40.483535 -5.570272) (xy 40.577335 -5.504061)
			(xy 40.675434 -5.444406) (xy 40.777376 -5.391584) (xy 40.882684 -5.345842) (xy 40.990869 -5.307393)
			(xy 41.101426 -5.276416) (xy 41.213838 -5.253057) (xy 41.327583 -5.237423) (xy 41.442129 -5.229588)
			(xy 41.556943 -5.229588) (xy 41.671489 -5.237423) (xy 41.785234 -5.253057) (xy 41.897646 -5.276416)
			(xy 42.008203 -5.307393) (xy 42.116388 -5.345842) (xy 42.221696 -5.391584) (xy 42.323638 -5.444406)
			(xy 42.421737 -5.504061) (xy 42.50107 -5.56006) (xy 63.647577 -5.56006) (xy 63.651612 -5.484356)
			(xy 63.663671 -5.409511) (xy 63.683617 -5.33637) (xy 63.711224 -5.265765) (xy 63.74618 -5.198494)
			(xy 63.788088 -5.135319) (xy 63.836474 -5.076957) (xy 63.89079 -5.024069) (xy 63.950419 -4.977254)
			(xy 64.014687 -4.937042) (xy 64.082864 -4.90389) (xy 64.15418 -4.878172) (xy 64.227825 -4.86018)
			(xy 64.302965 -4.850118) (xy 64.378749 -4.848099) (xy 64.454319 -4.854148) (xy 64.528817 -4.868195)
			(xy 64.6014 -4.890081) (xy 64.671246 -4.919558) (xy 64.737563 -4.956293) (xy 64.799599 -4.999868)
			(xy 64.856652 -5.04979) (xy 64.908076 -5.105494) (xy 64.953287 -5.166349) (xy 64.991774 -5.231664)
			(xy 65.0231 -5.3007) (xy 65.04691 -5.372675) (xy 65.062935 -5.446773) (xy 65.070994 -5.522154) (xy 65.071498 -5.56006)
			(xy 66.187577 -5.56006) (xy 66.191612 -5.484356) (xy 66.203671 -5.409511) (xy 66.223617 -5.33637)
			(xy 66.251224 -5.265765) (xy 66.28618 -5.198494) (xy 66.328088 -5.135319) (xy 66.376474 -5.076957)
			(xy 66.43079 -5.024069) (xy 66.490419 -4.977254) (xy 66.554687 -4.937042) (xy 66.622864 -4.90389)
			(xy 66.69418 -4.878172) (xy 66.767825 -4.86018) (xy 66.842965 -4.850118) (xy 66.918749 -4.848099)
			(xy 66.994319 -4.854148) (xy 67.068817 -4.868195) (xy 67.1414 -4.890081) (xy 67.211246 -4.919558)
			(xy 67.277563 -4.956293) (xy 67.339599 -4.999868) (xy 67.396652 -5.04979) (xy 67.448076 -5.105494)
			(xy 67.493287 -5.166349) (xy 67.531774 -5.231664) (xy 67.5631 -5.3007) (xy 67.58691 -5.372675) (xy 67.602935 -5.446773)
			(xy 67.610994 -5.522154) (xy 67.611498 -5.56006) (xy 68.727577 -5.56006) (xy 68.731612 -5.484356)
			(xy 68.743671 -5.409511) (xy 68.763617 -5.33637) (xy 68.791224 -5.265765) (xy 68.82618 -5.198494)
			(xy 68.868088 -5.135319) (xy 68.916474 -5.076957) (xy 68.97079 -5.024069) (xy 69.030419 -4.977254)
			(xy 69.094687 -4.937042) (xy 69.162864 -4.90389) (xy 69.23418 -4.878172) (xy 69.307825 -4.86018)
			(xy 69.382965 -4.850118) (xy 69.458749 -4.848099) (xy 69.534319 -4.854148) (xy 69.608817 -4.868195)
			(xy 69.6814 -4.890081) (xy 69.751246 -4.919558) (xy 69.817563 -4.956293) (xy 69.879599 -4.999868)
			(xy 69.936652 -5.04979) (xy 69.988076 -5.105494) (xy 70.033287 -5.166349) (xy 70.071774 -5.231664)
			(xy 70.1031 -5.3007) (xy 70.12691 -5.372675) (xy 70.142935 -5.446773) (xy 70.150994 -5.522154) (xy 70.151498 -5.56006)
			(xy 71.267577 -5.56006) (xy 71.271612 -5.484356) (xy 71.283671 -5.409511) (xy 71.303617 -5.33637)
			(xy 71.331224 -5.265765) (xy 71.36618 -5.198494) (xy 71.408088 -5.135319) (xy 71.456474 -5.076957)
			(xy 71.51079 -5.024069) (xy 71.570419 -4.977254) (xy 71.634687 -4.937042) (xy 71.702864 -4.90389)
			(xy 71.77418 -4.878172) (xy 71.847825 -4.86018) (xy 71.922965 -4.850118) (xy 71.998749 -4.848099)
			(xy 72.074319 -4.854148) (xy 72.148817 -4.868195) (xy 72.2214 -4.890081) (xy 72.291246 -4.919558)
			(xy 72.357563 -4.956293) (xy 72.419599 -4.999868) (xy 72.476652 -5.04979) (xy 72.528076 -5.105494)
			(xy 72.573287 -5.166349) (xy 72.611774 -5.231664) (xy 72.6431 -5.3007) (xy 72.66691 -5.372675) (xy 72.682935 -5.446773)
			(xy 72.690994 -5.522154) (xy 72.691498 -5.56006) (xy 73.807577 -5.56006) (xy 73.811612 -5.484356)
			(xy 73.823671 -5.409511) (xy 73.843617 -5.33637) (xy 73.871224 -5.265765) (xy 73.90618 -5.198494)
			(xy 73.948088 -5.135319) (xy 73.996474 -5.076957) (xy 74.05079 -5.024069) (xy 74.110419 -4.977254)
			(xy 74.174687 -4.937042) (xy 74.242864 -4.90389) (xy 74.31418 -4.878172) (xy 74.387825 -4.86018)
			(xy 74.462965 -4.850118) (xy 74.538749 -4.848099) (xy 74.614319 -4.854148) (xy 74.688817 -4.868195)
			(xy 74.7614 -4.890081) (xy 74.831246 -4.919558) (xy 74.897563 -4.956293) (xy 74.959599 -4.999868)
			(xy 75.016652 -5.04979) (xy 75.068076 -5.105494) (xy 75.113287 -5.166349) (xy 75.151774 -5.231664)
			(xy 75.1831 -5.3007) (xy 75.20691 -5.372675) (xy 75.222935 -5.446773) (xy 75.230994 -5.522154) (xy 75.231498 -5.56006)
			(xy 76.347577 -5.56006) (xy 76.351612 -5.484356) (xy 76.363671 -5.409511) (xy 76.383617 -5.33637)
			(xy 76.411224 -5.265765) (xy 76.44618 -5.198494) (xy 76.488088 -5.135319) (xy 76.536474 -5.076957)
			(xy 76.59079 -5.024069) (xy 76.650419 -4.977254) (xy 76.714687 -4.937042) (xy 76.782864 -4.90389)
			(xy 76.85418 -4.878172) (xy 76.927825 -4.86018) (xy 77.002965 -4.850118) (xy 77.078749 -4.848099)
			(xy 77.154319 -4.854148) (xy 77.228817 -4.868195) (xy 77.3014 -4.890081) (xy 77.371246 -4.919558)
			(xy 77.437563 -4.956293) (xy 77.499599 -4.999868) (xy 77.556652 -5.04979) (xy 77.608076 -5.105494)
			(xy 77.653287 -5.166349) (xy 77.691774 -5.231664) (xy 77.7231 -5.3007) (xy 77.74691 -5.372675) (xy 77.762935 -5.446773)
			(xy 77.770994 -5.522154) (xy 77.771498 -5.56006) (xy 78.887577 -5.56006) (xy 78.891612 -5.484356)
			(xy 78.903671 -5.409511) (xy 78.923617 -5.33637) (xy 78.951224 -5.265765) (xy 78.98618 -5.198494)
			(xy 79.028088 -5.135319) (xy 79.076474 -5.076957) (xy 79.13079 -5.024069) (xy 79.190419 -4.977254)
			(xy 79.254687 -4.937042) (xy 79.322864 -4.90389) (xy 79.39418 -4.878172) (xy 79.467825 -4.86018)
			(xy 79.542965 -4.850118) (xy 79.618749 -4.848099) (xy 79.694319 -4.854148) (xy 79.768817 -4.868195)
			(xy 79.8414 -4.890081) (xy 79.911246 -4.919558) (xy 79.977563 -4.956293) (xy 80.039599 -4.999868)
			(xy 80.096652 -5.04979) (xy 80.148076 -5.105494) (xy 80.193287 -5.166349) (xy 80.231774 -5.231664)
			(xy 80.2631 -5.3007) (xy 80.28691 -5.372675) (xy 80.302935 -5.446773) (xy 80.310994 -5.522154) (xy 80.311498 -5.56006)
			(xy 81.427577 -5.56006) (xy 81.431612 -5.484356) (xy 81.443671 -5.409511) (xy 81.463617 -5.33637)
			(xy 81.491224 -5.265765) (xy 81.52618 -5.198494) (xy 81.568088 -5.135319) (xy 81.616474 -5.076957)
			(xy 81.67079 -5.024069) (xy 81.730419 -4.977254) (xy 81.794687 -4.937042) (xy 81.862864 -4.90389)
			(xy 81.93418 -4.878172) (xy 82.007825 -4.86018) (xy 82.082965 -4.850118) (xy 82.158749 -4.848099)
			(xy 82.234319 -4.854148) (xy 82.308817 -4.868195) (xy 82.3814 -4.890081) (xy 82.451246 -4.919558)
			(xy 82.517563 -4.956293) (xy 82.579599 -4.999868) (xy 82.585544 -5.00507) (xy 86.197697 -5.00507)
			(xy 86.201732 -4.929366) (xy 86.213791 -4.854521) (xy 86.233737 -4.78138) (xy 86.261344 -4.710775)
			(xy 86.2963 -4.643504) (xy 86.338208 -4.580329) (xy 86.386594 -4.521967) (xy 86.44091 -4.469079)
			(xy 86.500539 -4.422264) (xy 86.564807 -4.382052) (xy 86.632984 -4.3489) (xy 86.7043 -4.323182) (xy 86.777945 -4.30519)
			(xy 86.853085 -4.295128) (xy 86.928869 -4.293109) (xy 87.004439 -4.299158) (xy 87.078937 -4.313205)
			(xy 87.15152 -4.335091) (xy 87.221366 -4.364568) (xy 87.287683 -4.401303) (xy 87.349719 -4.444878)
			(xy 87.406772 -4.4948) (xy 87.458196 -4.550504) (xy 87.503407 -4.611359) (xy 87.541894 -4.676674)
			(xy 87.57322 -4.74571) (xy 87.59703 -4.817685) (xy 87.613055 -4.891783) (xy 87.621114 -4.967164)
			(xy 87.621618 -5.00507) (xy 87.621114 -5.042976) (xy 87.613055 -5.118357) (xy 87.59703 -5.192455)
			(xy 87.57322 -5.26443) (xy 87.541894 -5.333466) (xy 87.503407 -5.398781) (xy 87.458196 -5.459636)
			(xy 87.406772 -5.51534) (xy 87.349719 -5.565262) (xy 87.287683 -5.608837) (xy 87.221366 -5.645572)
			(xy 87.15152 -5.675049) (xy 87.078937 -5.696935) (xy 87.004439 -5.710982) (xy 86.928869 -5.717031)
			(xy 86.853085 -5.715012) (xy 86.777945 -5.70495) (xy 86.7043 -5.686958) (xy 86.632984 -5.66124) (xy 86.564807 -5.628088)
			(xy 86.500539 -5.587876) (xy 86.44091 -5.541061) (xy 86.386594 -5.488173) (xy 86.338208 -5.429811)
			(xy 86.2963 -5.366636) (xy 86.261344 -5.299365) (xy 86.233737 -5.22876) (xy 86.213791 -5.155619)
			(xy 86.201732 -5.080774) (xy 86.197697 -5.00507) (xy 82.585544 -5.00507) (xy 82.636652 -5.04979)
			(xy 82.688076 -5.105494) (xy 82.733287 -5.166349) (xy 82.771774 -5.231664) (xy 82.8031 -5.3007) (xy 82.82691 -5.372675)
			(xy 82.842935 -5.446773) (xy 82.850994 -5.522154) (xy 82.851498 -5.56006) (xy 82.850994 -5.597966)
			(xy 82.842935 -5.673347) (xy 82.82691 -5.747445) (xy 82.8031 -5.81942) (xy 82.771774 -5.888456) (xy 82.733287 -5.953771)
			(xy 82.688076 -6.014626) (xy 82.636652 -6.07033) (xy 82.579599 -6.120252) (xy 82.517563 -6.163827)
			(xy 82.451246 -6.200562) (xy 82.3814 -6.230039) (xy 82.308817 -6.251925) (xy 82.234319 -6.265972)
			(xy 82.158749 -6.272021) (xy 82.082965 -6.270002) (xy 82.007825 -6.25994) (xy 81.93418 -6.241948)
			(xy 81.862864 -6.21623) (xy 81.794687 -6.183078) (xy 81.730419 -6.142866) (xy 81.67079 -6.096051)
			(xy 81.616474 -6.043163) (xy 81.568088 -5.984801) (xy 81.52618 -5.921626) (xy 81.491224 -5.854355)
			(xy 81.463617 -5.78375) (xy 81.443671 -5.710609) (xy 81.431612 -5.635764) (xy 81.427577 -5.56006)
			(xy 80.311498 -5.56006) (xy 80.310994 -5.597966) (xy 80.302935 -5.673347) (xy 80.28691 -5.747445)
			(xy 80.2631 -5.81942) (xy 80.231774 -5.888456) (xy 80.193287 -5.953771) (xy 80.148076 -6.014626)
			(xy 80.096652 -6.07033) (xy 80.039599 -6.120252) (xy 79.977563 -6.163827) (xy 79.911246 -6.200562)
			(xy 79.8414 -6.230039) (xy 79.768817 -6.251925) (xy 79.694319 -6.265972) (xy 79.618749 -6.272021)
			(xy 79.542965 -6.270002) (xy 79.467825 -6.25994) (xy 79.39418 -6.241948) (xy 79.322864 -6.21623)
			(xy 79.254687 -6.183078) (xy 79.190419 -6.142866) (xy 79.13079 -6.096051) (xy 79.076474 -6.043163)
			(xy 79.028088 -5.984801) (xy 78.98618 -5.921626) (xy 78.951224 -5.854355) (xy 78.923617 -5.78375)
			(xy 78.903671 -5.710609) (xy 78.891612 -5.635764) (xy 78.887577 -5.56006) (xy 77.771498 -5.56006)
			(xy 77.770994 -5.597966) (xy 77.762935 -5.673347) (xy 77.74691 -5.747445) (xy 77.7231 -5.81942) (xy 77.691774 -5.888456)
			(xy 77.653287 -5.953771) (xy 77.608076 -6.014626) (xy 77.556652 -6.07033) (xy 77.499599 -6.120252)
			(xy 77.437563 -6.163827) (xy 77.371246 -6.200562) (xy 77.3014 -6.230039) (xy 77.228817 -6.251925)
			(xy 77.154319 -6.265972) (xy 77.078749 -6.272021) (xy 77.002965 -6.270002) (xy 76.927825 -6.25994)
			(xy 76.85418 -6.241948) (xy 76.782864 -6.21623) (xy 76.714687 -6.183078) (xy 76.650419 -6.142866)
			(xy 76.59079 -6.096051) (xy 76.536474 -6.043163) (xy 76.488088 -5.984801) (xy 76.44618 -5.921626)
			(xy 76.411224 -5.854355) (xy 76.383617 -5.78375) (xy 76.363671 -5.710609) (xy 76.351612 -5.635764)
			(xy 76.347577 -5.56006) (xy 75.231498 -5.56006) (xy 75.230994 -5.597966) (xy 75.222935 -5.673347)
			(xy 75.20691 -5.747445) (xy 75.1831 -5.81942) (xy 75.151774 -5.888456) (xy 75.113287 -5.953771) (xy 75.068076 -6.014626)
			(xy 75.016652 -6.07033) (xy 74.959599 -6.120252) (xy 74.897563 -6.163827) (xy 74.831246 -6.200562)
			(xy 74.7614 -6.230039) (xy 74.688817 -6.251925) (xy 74.614319 -6.265972) (xy 74.538749 -6.272021)
			(xy 74.462965 -6.270002) (xy 74.387825 -6.25994) (xy 74.31418 -6.241948) (xy 74.242864 -6.21623)
			(xy 74.174687 -6.183078) (xy 74.110419 -6.142866) (xy 74.05079 -6.096051) (xy 73.996474 -6.043163)
			(xy 73.948088 -5.984801) (xy 73.90618 -5.921626) (xy 73.871224 -5.854355) (xy 73.843617 -5.78375)
			(xy 73.823671 -5.710609) (xy 73.811612 -5.635764) (xy 73.807577 -5.56006) (xy 72.691498 -5.56006)
			(xy 72.690994 -5.597966) (xy 72.682935 -5.673347) (xy 72.66691 -5.747445) (xy 72.6431 -5.81942) (xy 72.611774 -5.888456)
			(xy 72.573287 -5.953771) (xy 72.528076 -6.014626) (xy 72.476652 -6.07033) (xy 72.419599 -6.120252)
			(xy 72.357563 -6.163827) (xy 72.291246 -6.200562) (xy 72.2214 -6.230039) (xy 72.148817 -6.251925)
			(xy 72.074319 -6.265972) (xy 71.998749 -6.272021) (xy 71.922965 -6.270002) (xy 71.847825 -6.25994)
			(xy 71.77418 -6.241948) (xy 71.702864 -6.21623) (xy 71.634687 -6.183078) (xy 71.570419 -6.142866)
			(xy 71.51079 -6.096051) (xy 71.456474 -6.043163) (xy 71.408088 -5.984801) (xy 71.36618 -5.921626)
			(xy 71.331224 -5.854355) (xy 71.303617 -5.78375) (xy 71.283671 -5.710609) (xy 71.271612 -5.635764)
			(xy 71.267577 -5.56006) (xy 70.151498 -5.56006) (xy 70.150994 -5.597966) (xy 70.142935 -5.673347)
			(xy 70.12691 -5.747445) (xy 70.1031 -5.81942) (xy 70.071774 -5.888456) (xy 70.033287 -5.953771) (xy 69.988076 -6.014626)
			(xy 69.936652 -6.07033) (xy 69.879599 -6.120252) (xy 69.817563 -6.163827) (xy 69.751246 -6.200562)
			(xy 69.6814 -6.230039) (xy 69.608817 -6.251925) (xy 69.534319 -6.265972) (xy 69.458749 -6.272021)
			(xy 69.382965 -6.270002) (xy 69.307825 -6.25994) (xy 69.23418 -6.241948) (xy 69.162864 -6.21623)
			(xy 69.094687 -6.183078) (xy 69.030419 -6.142866) (xy 68.97079 -6.096051) (xy 68.916474 -6.043163)
			(xy 68.868088 -5.984801) (xy 68.82618 -5.921626) (xy 68.791224 -5.854355) (xy 68.763617 -5.78375)
			(xy 68.743671 -5.710609) (xy 68.731612 -5.635764) (xy 68.727577 -5.56006) (xy 67.611498 -5.56006)
			(xy 67.610994 -5.597966) (xy 67.602935 -5.673347) (xy 67.58691 -5.747445) (xy 67.5631 -5.81942) (xy 67.531774 -5.888456)
			(xy 67.493287 -5.953771) (xy 67.448076 -6.014626) (xy 67.396652 -6.07033) (xy 67.339599 -6.120252)
			(xy 67.277563 -6.163827) (xy 67.211246 -6.200562) (xy 67.1414 -6.230039) (xy 67.068817 -6.251925)
			(xy 66.994319 -6.265972) (xy 66.918749 -6.272021) (xy 66.842965 -6.270002) (xy 66.767825 -6.25994)
			(xy 66.69418 -6.241948) (xy 66.622864 -6.21623) (xy 66.554687 -6.183078) (xy 66.490419 -6.142866)
			(xy 66.43079 -6.096051) (xy 66.376474 -6.043163) (xy 66.328088 -5.984801) (xy 66.28618 -5.921626)
			(xy 66.251224 -5.854355) (xy 66.223617 -5.78375) (xy 66.203671 -5.710609) (xy 66.191612 -5.635764)
			(xy 66.187577 -5.56006) (xy 65.071498 -5.56006) (xy 65.070994 -5.597966) (xy 65.062935 -5.673347)
			(xy 65.04691 -5.747445) (xy 65.0231 -5.81942) (xy 64.991774 -5.888456) (xy 64.953287 -5.953771) (xy 64.908076 -6.014626)
			(xy 64.856652 -6.07033) (xy 64.799599 -6.120252) (xy 64.737563 -6.163827) (xy 64.671246 -6.200562)
			(xy 64.6014 -6.230039) (xy 64.528817 -6.251925) (xy 64.454319 -6.265972) (xy 64.378749 -6.272021)
			(xy 64.302965 -6.270002) (xy 64.227825 -6.25994) (xy 64.15418 -6.241948) (xy 64.082864 -6.21623)
			(xy 64.014687 -6.183078) (xy 63.950419 -6.142866) (xy 63.89079 -6.096051) (xy 63.836474 -6.043163)
			(xy 63.788088 -5.984801) (xy 63.74618 -5.921626) (xy 63.711224 -5.854355) (xy 63.683617 -5.78375)
			(xy 63.663671 -5.710609) (xy 63.651612 -5.635764) (xy 63.647577 -5.56006) (xy 42.50107 -5.56006)
			(xy 42.515537 -5.570272) (xy 42.604599 -5.64273) (xy 42.68851 -5.721096) (xy 42.766876 -5.805007)
			(xy 42.839334 -5.894069) (xy 42.905545 -5.987869) (xy 42.9652 -6.085968) (xy 43.018022 -6.18791)
			(xy 43.055881 -6.27507) (xy 84.927697 -6.27507) (xy 84.931732 -6.199366) (xy 84.943791 -6.124521)
			(xy 84.963737 -6.05138) (xy 84.991344 -5.980775) (xy 85.0263 -5.913504) (xy 85.068208 -5.850329)
			(xy 85.116594 -5.791967) (xy 85.17091 -5.739079) (xy 85.230539 -5.692264) (xy 85.294807 -5.652052)
			(xy 85.362984 -5.6189) (xy 85.4343 -5.593182) (xy 85.507945 -5.57519) (xy 85.583085 -5.565128) (xy 85.658869 -5.563109)
			(xy 85.734439 -5.569158) (xy 85.808937 -5.583205) (xy 85.88152 -5.605091) (xy 85.951366 -5.634568)
			(xy 86.017683 -5.671303) (xy 86.079719 -5.714878) (xy 86.136772 -5.7648) (xy 86.188196 -5.820504)
			(xy 86.233407 -5.881359) (xy 86.271894 -5.946674) (xy 86.30322 -6.01571) (xy 86.32703 -6.087685)
			(xy 86.343055 -6.161783) (xy 86.351114 -6.237164) (xy 86.351618 -6.27507) (xy 86.351114 -6.312976)
			(xy 86.343055 -6.388357) (xy 86.32703 -6.462455) (xy 86.30322 -6.53443) (xy 86.271894 -6.603466)
			(xy 86.233407 -6.668781) (xy 86.188196 -6.729636) (xy 86.136772 -6.78534) (xy 86.079719 -6.835262)
			(xy 86.017683 -6.878837) (xy 85.951366 -6.915572) (xy 85.88152 -6.945049) (xy 85.808937 -6.966935)
			(xy 85.734439 -6.980982) (xy 85.658869 -6.987031) (xy 85.583085 -6.985012) (xy 85.507945 -6.97495)
			(xy 85.4343 -6.956958) (xy 85.362984 -6.93124) (xy 85.294807 -6.898088) (xy 85.230539 -6.857876)
			(xy 85.17091 -6.811061) (xy 85.116594 -6.758173) (xy 85.068208 -6.699811) (xy 85.0263 -6.636636)
			(xy 84.991344 -6.569365) (xy 84.963737 -6.49876) (xy 84.943791 -6.425619) (xy 84.931732 -6.350774)
			(xy 84.927697 -6.27507) (xy 43.055881 -6.27507) (xy 43.063764 -6.293218) (xy 43.102213 -6.401403)
			(xy 43.13319 -6.51196) (xy 43.156549 -6.624372) (xy 43.172183 -6.738117) (xy 43.180018 -6.852663)
			(xy 43.180508 -6.91007) (xy 43.180381 -6.943251) (xy 43.177842 -7.009565) (xy 43.175428 -7.042658)
			(xy 43.170272 -7.100942) (xy 43.152948 -7.216671) (xy 43.127616 -7.330914) (xy 43.094401 -7.443119)
			(xy 43.053462 -7.552742) (xy 43.004999 -7.659253) (xy 42.949245 -7.762135) (xy 42.886471 -7.860891)
			(xy 42.816981 -7.955042) (xy 42.741111 -8.044132) (xy 42.659229 -8.127729) (xy 42.571732 -8.20543)
			(xy 42.500813 -8.26008) (xy 63.647577 -8.26008) (xy 63.651612 -8.184376) (xy 63.663671 -8.109531)
			(xy 63.683617 -8.03639) (xy 63.711224 -7.965785) (xy 63.74618 -7.898514) (xy 63.788088 -7.835339)
			(xy 63.836474 -7.776977) (xy 63.89079 -7.724089) (xy 63.950419 -7.677274) (xy 64.014687 -7.637062)
			(xy 64.082864 -7.60391) (xy 64.15418 -7.578192) (xy 64.227825 -7.5602) (xy 64.302965 -7.550138) (xy 64.378749 -7.548119)
			(xy 64.454319 -7.554168) (xy 64.528817 -7.568215) (xy 64.6014 -7.590101) (xy 64.671246 -7.619578)
			(xy 64.737563 -7.656313) (xy 64.799599 -7.699888) (xy 64.856652 -7.74981) (xy 64.908076 -7.805514)
			(xy 64.953287 -7.866369) (xy 64.991774 -7.931684) (xy 65.0231 -8.00072) (xy 65.04691 -8.072695) (xy 65.062935 -8.146793)
			(xy 65.070994 -8.222174) (xy 65.071498 -8.26008) (xy 66.187577 -8.26008) (xy 66.191612 -8.184376)
			(xy 66.203671 -8.109531) (xy 66.223617 -8.03639) (xy 66.251224 -7.965785) (xy 66.28618 -7.898514)
			(xy 66.328088 -7.835339) (xy 66.376474 -7.776977) (xy 66.43079 -7.724089) (xy 66.490419 -7.677274)
			(xy 66.554687 -7.637062) (xy 66.622864 -7.60391) (xy 66.69418 -7.578192) (xy 66.767825 -7.5602) (xy 66.842965 -7.550138)
			(xy 66.918749 -7.548119) (xy 66.994319 -7.554168) (xy 67.068817 -7.568215) (xy 67.1414 -7.590101)
			(xy 67.211246 -7.619578) (xy 67.277563 -7.656313) (xy 67.339599 -7.699888) (xy 67.396652 -7.74981)
			(xy 67.448076 -7.805514) (xy 67.493287 -7.866369) (xy 67.531774 -7.931684) (xy 67.5631 -8.00072)
			(xy 67.58691 -8.072695) (xy 67.602935 -8.146793) (xy 67.610994 -8.222174) (xy 67.611498 -8.26008)
			(xy 68.727577 -8.26008) (xy 68.731612 -8.184376) (xy 68.743671 -8.109531) (xy 68.763617 -8.03639)
			(xy 68.791224 -7.965785) (xy 68.82618 -7.898514) (xy 68.868088 -7.835339) (xy 68.916474 -7.776977)
			(xy 68.97079 -7.724089) (xy 69.030419 -7.677274) (xy 69.094687 -7.637062) (xy 69.162864 -7.60391)
			(xy 69.23418 -7.578192) (xy 69.307825 -7.5602) (xy 69.382965 -7.550138) (xy 69.458749 -7.548119)
			(xy 69.534319 -7.554168) (xy 69.608817 -7.568215) (xy 69.6814 -7.590101) (xy 69.751246 -7.619578)
			(xy 69.817563 -7.656313) (xy 69.879599 -7.699888) (xy 69.936652 -7.74981) (xy 69.988076 -7.805514)
			(xy 70.033287 -7.866369) (xy 70.071774 -7.931684) (xy 70.1031 -8.00072) (xy 70.12691 -8.072695) (xy 70.142935 -8.146793)
			(xy 70.150994 -8.222174) (xy 70.151498 -8.26008) (xy 71.267577 -8.26008) (xy 71.271612 -8.184376)
			(xy 71.283671 -8.109531) (xy 71.303617 -8.03639) (xy 71.331224 -7.965785) (xy 71.36618 -7.898514)
			(xy 71.408088 -7.835339) (xy 71.456474 -7.776977) (xy 71.51079 -7.724089) (xy 71.570419 -7.677274)
			(xy 71.634687 -7.637062) (xy 71.702864 -7.60391) (xy 71.77418 -7.578192) (xy 71.847825 -7.5602) (xy 71.922965 -7.550138)
			(xy 71.998749 -7.548119) (xy 72.074319 -7.554168) (xy 72.148817 -7.568215) (xy 72.2214 -7.590101)
			(xy 72.291246 -7.619578) (xy 72.357563 -7.656313) (xy 72.419599 -7.699888) (xy 72.476652 -7.74981)
			(xy 72.528076 -7.805514) (xy 72.573287 -7.866369) (xy 72.611774 -7.931684) (xy 72.6431 -8.00072)
			(xy 72.66691 -8.072695) (xy 72.682935 -8.146793) (xy 72.690994 -8.222174) (xy 72.691498 -8.26008)
			(xy 73.807577 -8.26008) (xy 73.811612 -8.184376) (xy 73.823671 -8.109531) (xy 73.843617 -8.03639)
			(xy 73.871224 -7.965785) (xy 73.90618 -7.898514) (xy 73.948088 -7.835339) (xy 73.996474 -7.776977)
			(xy 74.05079 -7.724089) (xy 74.110419 -7.677274) (xy 74.174687 -7.637062) (xy 74.242864 -7.60391)
			(xy 74.31418 -7.578192) (xy 74.387825 -7.5602) (xy 74.462965 -7.550138) (xy 74.538749 -7.548119)
			(xy 74.614319 -7.554168) (xy 74.688817 -7.568215) (xy 74.7614 -7.590101) (xy 74.831246 -7.619578)
			(xy 74.897563 -7.656313) (xy 74.959599 -7.699888) (xy 75.016652 -7.74981) (xy 75.068076 -7.805514)
			(xy 75.113287 -7.866369) (xy 75.151774 -7.931684) (xy 75.1831 -8.00072) (xy 75.20691 -8.072695) (xy 75.222935 -8.146793)
			(xy 75.230994 -8.222174) (xy 75.231498 -8.26008) (xy 76.347577 -8.26008) (xy 76.351612 -8.184376)
			(xy 76.363671 -8.109531) (xy 76.383617 -8.03639) (xy 76.411224 -7.965785) (xy 76.44618 -7.898514)
			(xy 76.488088 -7.835339) (xy 76.536474 -7.776977) (xy 76.59079 -7.724089) (xy 76.650419 -7.677274)
			(xy 76.714687 -7.637062) (xy 76.782864 -7.60391) (xy 76.85418 -7.578192) (xy 76.927825 -7.5602) (xy 77.002965 -7.550138)
			(xy 77.078749 -7.548119) (xy 77.154319 -7.554168) (xy 77.228817 -7.568215) (xy 77.3014 -7.590101)
			(xy 77.371246 -7.619578) (xy 77.437563 -7.656313) (xy 77.499599 -7.699888) (xy 77.556652 -7.74981)
			(xy 77.608076 -7.805514) (xy 77.653287 -7.866369) (xy 77.691774 -7.931684) (xy 77.7231 -8.00072)
			(xy 77.74691 -8.072695) (xy 77.762935 -8.146793) (xy 77.770994 -8.222174) (xy 77.771498 -8.26008)
			(xy 78.887577 -8.26008) (xy 78.891612 -8.184376) (xy 78.903671 -8.109531) (xy 78.923617 -8.03639)
			(xy 78.951224 -7.965785) (xy 78.98618 -7.898514) (xy 79.028088 -7.835339) (xy 79.076474 -7.776977)
			(xy 79.13079 -7.724089) (xy 79.190419 -7.677274) (xy 79.254687 -7.637062) (xy 79.322864 -7.60391)
			(xy 79.39418 -7.578192) (xy 79.467825 -7.5602) (xy 79.542965 -7.550138) (xy 79.618749 -7.548119)
			(xy 79.694319 -7.554168) (xy 79.768817 -7.568215) (xy 79.8414 -7.590101) (xy 79.911246 -7.619578)
			(xy 79.977563 -7.656313) (xy 80.039599 -7.699888) (xy 80.096652 -7.74981) (xy 80.148076 -7.805514)
			(xy 80.193287 -7.866369) (xy 80.231774 -7.931684) (xy 80.2631 -8.00072) (xy 80.28691 -8.072695) (xy 80.302935 -8.146793)
			(xy 80.310994 -8.222174) (xy 80.311498 -8.26008) (xy 81.427577 -8.26008) (xy 81.431612 -8.184376)
			(xy 81.443671 -8.109531) (xy 81.463617 -8.03639) (xy 81.491224 -7.965785) (xy 81.52618 -7.898514)
			(xy 81.568088 -7.835339) (xy 81.616474 -7.776977) (xy 81.67079 -7.724089) (xy 81.730419 -7.677274)
			(xy 81.794687 -7.637062) (xy 81.862864 -7.60391) (xy 81.93418 -7.578192) (xy 82.007825 -7.5602) (xy 82.082965 -7.550138)
			(xy 82.158749 -7.548119) (xy 82.234319 -7.554168) (xy 82.308817 -7.568215) (xy 82.3814 -7.590101)
			(xy 82.451246 -7.619578) (xy 82.517563 -7.656313) (xy 82.579599 -7.699888) (xy 82.636652 -7.74981)
			(xy 82.688076 -7.805514) (xy 82.733287 -7.866369) (xy 82.771774 -7.931684) (xy 82.8031 -8.00072)
			(xy 82.82691 -8.072695) (xy 82.842935 -8.146793) (xy 82.850994 -8.222174) (xy 82.851498 -8.26008)
			(xy 82.850994 -8.297986) (xy 82.842935 -8.373367) (xy 82.82691 -8.447465) (xy 82.8031 -8.51944) (xy 82.771774 -8.588476)
			(xy 82.733287 -8.653791) (xy 82.688076 -8.714646) (xy 82.636652 -8.77035) (xy 82.579599 -8.820272)
			(xy 82.517563 -8.863847) (xy 82.451246 -8.900582) (xy 82.3814 -8.930059) (xy 82.308817 -8.951945)
			(xy 82.234319 -8.965992) (xy 82.158749 -8.972041) (xy 82.082965 -8.970022) (xy 82.007825 -8.95996)
			(xy 81.93418 -8.941968) (xy 81.862864 -8.91625) (xy 81.794687 -8.883098) (xy 81.730419 -8.842886)
			(xy 81.67079 -8.796071) (xy 81.616474 -8.743183) (xy 81.568088 -8.684821) (xy 81.52618 -8.621646)
			(xy 81.491224 -8.554375) (xy 81.463617 -8.48377) (xy 81.443671 -8.410629) (xy 81.431612 -8.335784)
			(xy 81.427577 -8.26008) (xy 80.311498 -8.26008) (xy 80.310994 -8.297986) (xy 80.302935 -8.373367)
			(xy 80.28691 -8.447465) (xy 80.2631 -8.51944) (xy 80.231774 -8.588476) (xy 80.193287 -8.653791) (xy 80.148076 -8.714646)
			(xy 80.096652 -8.77035) (xy 80.039599 -8.820272) (xy 79.977563 -8.863847) (xy 79.911246 -8.900582)
			(xy 79.8414 -8.930059) (xy 79.768817 -8.951945) (xy 79.694319 -8.965992) (xy 79.618749 -8.972041)
			(xy 79.542965 -8.970022) (xy 79.467825 -8.95996) (xy 79.39418 -8.941968) (xy 79.322864 -8.91625)
			(xy 79.254687 -8.883098) (xy 79.190419 -8.842886) (xy 79.13079 -8.796071) (xy 79.076474 -8.743183)
			(xy 79.028088 -8.684821) (xy 78.98618 -8.621646) (xy 78.951224 -8.554375) (xy 78.923617 -8.48377)
			(xy 78.903671 -8.410629) (xy 78.891612 -8.335784) (xy 78.887577 -8.26008) (xy 77.771498 -8.26008)
			(xy 77.770994 -8.297986) (xy 77.762935 -8.373367) (xy 77.74691 -8.447465) (xy 77.7231 -8.51944) (xy 77.691774 -8.588476)
			(xy 77.653287 -8.653791) (xy 77.608076 -8.714646) (xy 77.556652 -8.77035) (xy 77.499599 -8.820272)
			(xy 77.437563 -8.863847) (xy 77.371246 -8.900582) (xy 77.3014 -8.930059) (xy 77.228817 -8.951945)
			(xy 77.154319 -8.965992) (xy 77.078749 -8.972041) (xy 77.002965 -8.970022) (xy 76.927825 -8.95996)
			(xy 76.85418 -8.941968) (xy 76.782864 -8.91625) (xy 76.714687 -8.883098) (xy 76.650419 -8.842886)
			(xy 76.59079 -8.796071) (xy 76.536474 -8.743183) (xy 76.488088 -8.684821) (xy 76.44618 -8.621646)
			(xy 76.411224 -8.554375) (xy 76.383617 -8.48377) (xy 76.363671 -8.410629) (xy 76.351612 -8.335784)
			(xy 76.347577 -8.26008) (xy 75.231498 -8.26008) (xy 75.230994 -8.297986) (xy 75.222935 -8.373367)
			(xy 75.20691 -8.447465) (xy 75.1831 -8.51944) (xy 75.151774 -8.588476) (xy 75.113287 -8.653791) (xy 75.068076 -8.714646)
			(xy 75.016652 -8.77035) (xy 74.959599 -8.820272) (xy 74.897563 -8.863847) (xy 74.831246 -8.900582)
			(xy 74.7614 -8.930059) (xy 74.688817 -8.951945) (xy 74.614319 -8.965992) (xy 74.538749 -8.972041)
			(xy 74.462965 -8.970022) (xy 74.387825 -8.95996) (xy 74.31418 -8.941968) (xy 74.242864 -8.91625)
			(xy 74.174687 -8.883098) (xy 74.110419 -8.842886) (xy 74.05079 -8.796071) (xy 73.996474 -8.743183)
			(xy 73.948088 -8.684821) (xy 73.90618 -8.621646) (xy 73.871224 -8.554375) (xy 73.843617 -8.48377)
			(xy 73.823671 -8.410629) (xy 73.811612 -8.335784) (xy 73.807577 -8.26008) (xy 72.691498 -8.26008)
			(xy 72.690994 -8.297986) (xy 72.682935 -8.373367) (xy 72.66691 -8.447465) (xy 72.6431 -8.51944) (xy 72.611774 -8.588476)
			(xy 72.573287 -8.653791) (xy 72.528076 -8.714646) (xy 72.476652 -8.77035) (xy 72.419599 -8.820272)
			(xy 72.357563 -8.863847) (xy 72.291246 -8.900582) (xy 72.2214 -8.930059) (xy 72.148817 -8.951945)
			(xy 72.074319 -8.965992) (xy 71.998749 -8.972041) (xy 71.922965 -8.970022) (xy 71.847825 -8.95996)
			(xy 71.77418 -8.941968) (xy 71.702864 -8.91625) (xy 71.634687 -8.883098) (xy 71.570419 -8.842886)
			(xy 71.51079 -8.796071) (xy 71.456474 -8.743183) (xy 71.408088 -8.684821) (xy 71.36618 -8.621646)
			(xy 71.331224 -8.554375) (xy 71.303617 -8.48377) (xy 71.283671 -8.410629) (xy 71.271612 -8.335784)
			(xy 71.267577 -8.26008) (xy 70.151498 -8.26008) (xy 70.150994 -8.297986) (xy 70.142935 -8.373367)
			(xy 70.12691 -8.447465) (xy 70.1031 -8.51944) (xy 70.071774 -8.588476) (xy 70.033287 -8.653791) (xy 69.988076 -8.714646)
			(xy 69.936652 -8.77035) (xy 69.879599 -8.820272) (xy 69.817563 -8.863847) (xy 69.751246 -8.900582)
			(xy 69.6814 -8.930059) (xy 69.608817 -8.951945) (xy 69.534319 -8.965992) (xy 69.458749 -8.972041)
			(xy 69.382965 -8.970022) (xy 69.307825 -8.95996) (xy 69.23418 -8.941968) (xy 69.162864 -8.91625)
			(xy 69.094687 -8.883098) (xy 69.030419 -8.842886) (xy 68.97079 -8.796071) (xy 68.916474 -8.743183)
			(xy 68.868088 -8.684821) (xy 68.82618 -8.621646) (xy 68.791224 -8.554375) (xy 68.763617 -8.48377)
			(xy 68.743671 -8.410629) (xy 68.731612 -8.335784) (xy 68.727577 -8.26008) (xy 67.611498 -8.26008)
			(xy 67.610994 -8.297986) (xy 67.602935 -8.373367) (xy 67.58691 -8.447465) (xy 67.5631 -8.51944) (xy 67.531774 -8.588476)
			(xy 67.493287 -8.653791) (xy 67.448076 -8.714646) (xy 67.396652 -8.77035) (xy 67.339599 -8.820272)
			(xy 67.277563 -8.863847) (xy 67.211246 -8.900582) (xy 67.1414 -8.930059) (xy 67.068817 -8.951945)
			(xy 66.994319 -8.965992) (xy 66.918749 -8.972041) (xy 66.842965 -8.970022) (xy 66.767825 -8.95996)
			(xy 66.69418 -8.941968) (xy 66.622864 -8.91625) (xy 66.554687 -8.883098) (xy 66.490419 -8.842886)
			(xy 66.43079 -8.796071) (xy 66.376474 -8.743183) (xy 66.328088 -8.684821) (xy 66.28618 -8.621646)
			(xy 66.251224 -8.554375) (xy 66.223617 -8.48377) (xy 66.203671 -8.410629) (xy 66.191612 -8.335784)
			(xy 66.187577 -8.26008) (xy 65.071498 -8.26008) (xy 65.070994 -8.297986) (xy 65.062935 -8.373367)
			(xy 65.04691 -8.447465) (xy 65.0231 -8.51944) (xy 64.991774 -8.588476) (xy 64.953287 -8.653791) (xy 64.908076 -8.714646)
			(xy 64.856652 -8.77035) (xy 64.799599 -8.820272) (xy 64.737563 -8.863847) (xy 64.671246 -8.900582)
			(xy 64.6014 -8.930059) (xy 64.528817 -8.951945) (xy 64.454319 -8.965992) (xy 64.378749 -8.972041)
			(xy 64.302965 -8.970022) (xy 64.227825 -8.95996) (xy 64.15418 -8.941968) (xy 64.082864 -8.91625)
			(xy 64.014687 -8.883098) (xy 63.950419 -8.842886) (xy 63.89079 -8.796071) (xy 63.836474 -8.743183)
			(xy 63.788088 -8.684821) (xy 63.74618 -8.621646) (xy 63.711224 -8.554375) (xy 63.683617 -8.48377)
			(xy 63.663671 -8.410629) (xy 63.651612 -8.335784) (xy 63.647577 -8.26008) (xy 42.500813 -8.26008)
			(xy 42.479042 -8.276857) (xy 42.381609 -8.341665) (xy 42.279905 -8.39954) (xy 42.174422 -8.450202)
			(xy 42.065671 -8.493404) (xy 41.954179 -8.528939) (xy 41.840485 -8.556634) (xy 41.725141 -8.576354)
			(xy 41.608704 -8.588005) (xy 41.491739 -8.59153) (xy 41.374812 -8.586912) (xy 41.258489 -8.574173)
			(xy 41.143334 -8.553375) (xy 41.029905 -8.524618) (xy 40.91875 -8.488042) (xy 40.810407 -8.443825)
			(xy 40.705403 -8.392179) (xy 40.604244 -8.333356) (xy 40.507421 -8.26764) (xy 40.415403 -8.195349)
			(xy 40.328636 -8.116834) (xy 40.247539 -8.032474) (xy 40.172506 -7.942679) (xy 40.103899 -7.847883)
			(xy 40.042051 -7.748544) (xy 39.987262 -7.645145) (xy 39.939796 -7.538186) (xy 39.899884 -7.428185)
			(xy 39.86772 -7.315674) (xy 39.843457 -7.201199) (xy 39.827215 -7.085313) (xy 39.819072 -6.968579)
			(xy 39.818564 -6.91007) (xy 36.454201 -6.91007) (xy 36.4555 -6.914635) (xy 36.471468 -7.000055) (xy 36.479486 -7.086584)
			(xy 36.479988 -7.130034) (xy 36.479486 -7.173484) (xy 36.471468 -7.260013) (xy 36.4555 -7.345433)
			(xy 36.431719 -7.429015) (xy 36.400327 -7.510047) (xy 36.361593 -7.587836) (xy 36.315846 -7.66172)
			(xy 36.263477 -7.731067) (xy 36.204933 -7.795287) (xy 36.140713 -7.853831) (xy 36.071366 -7.9062)
			(xy 35.997482 -7.951947) (xy 35.919693 -7.990681) (xy 35.838661 -8.022073) (xy 35.755079 -8.045854)
			(xy 35.669659 -8.061822) (xy 35.58313 -8.06984) (xy 35.49623 -8.06984) (xy 35.409701 -8.061822) (xy 35.324281 -8.045854)
			(xy 35.240699 -8.022073) (xy 35.159667 -7.990681) (xy 35.081878 -7.951947) (xy 35.007994 -7.9062)
			(xy 34.938647 -7.853831) (xy 34.874427 -7.795287) (xy 34.815883 -7.731067) (xy 34.763514 -7.66172)
			(xy 34.717767 -7.587836) (xy 34.679033 -7.510047) (xy 34.647641 -7.429015) (xy 34.62386 -7.345433)
			(xy 34.607892 -7.260013) (xy 34.599874 -7.173484) (xy 31.399486 -7.173484) (xy 31.391468 -7.260013)
			(xy 31.3755 -7.345433) (xy 31.351719 -7.429015) (xy 31.320327 -7.510047) (xy 31.281593 -7.587836)
			(xy 31.235846 -7.66172) (xy 31.183477 -7.731067) (xy 31.124933 -7.795287) (xy 31.060713 -7.853831)
			(xy 30.991366 -7.9062) (xy 30.917482 -7.951947) (xy 30.839693 -7.990681) (xy 30.758661 -8.022073)
			(xy 30.675079 -8.045854) (xy 30.589659 -8.061822) (xy 30.50313 -8.06984) (xy 30.41623 -8.06984) (xy 30.329701 -8.061822)
			(xy 30.244281 -8.045854) (xy 30.160699 -8.022073) (xy 30.079667 -7.990681) (xy 30.001878 -7.951947)
			(xy 29.927994 -7.9062) (xy 29.858647 -7.853831) (xy 29.794427 -7.795287) (xy 29.735883 -7.731067)
			(xy 29.683514 -7.66172) (xy 29.637767 -7.587836) (xy 29.599033 -7.510047) (xy 29.567641 -7.429015)
			(xy 29.54386 -7.345433) (xy 29.527892 -7.260013) (xy 29.519874 -7.173484) (xy 9.617621 -7.173484)
			(xy 9.645511 -7.2795) (xy 9.670564 -7.406163) (xy 9.687725 -7.534134) (xy 9.696928 -7.662923) (xy 9.698139 -7.792034)
			(xy 9.691351 -7.920972) (xy 9.676591 -8.049243) (xy 9.653916 -8.176353) (xy 9.623413 -8.301815) (xy 9.585199 -8.425147)
			(xy 9.539421 -8.545876) (xy 9.486254 -8.663539) (xy 9.425903 -8.777683) (xy 9.358599 -8.88787) (xy 9.2846 -8.993678)
			(xy 9.233757 -9.057555) (xy 15.679156 -9.057555) (xy 15.679156 -8.976445) (xy 15.687106 -8.895726)
			(xy 15.702929 -8.816175) (xy 15.726474 -8.738559) (xy 15.757513 -8.663623) (xy 15.795748 -8.592091)
			(xy 15.84081 -8.524651) (xy 15.892265 -8.461952) (xy 15.949618 -8.404599) (xy 16.012317 -8.353144)
			(xy 16.079757 -8.308082) (xy 16.151289 -8.269847) (xy 16.226225 -8.238808) (xy 16.303841 -8.215263)
			(xy 16.383392 -8.19944) (xy 16.464111 -8.19149) (xy 16.545221 -8.19149) (xy 16.62594 -8.19944) (xy 16.705491 -8.215263)
			(xy 16.783107 -8.238808) (xy 16.858043 -8.269847) (xy 16.929575 -8.308082) (xy 16.997015 -8.353144)
			(xy 17.059714 -8.404599) (xy 17.117067 -8.461952) (xy 17.168522 -8.524651) (xy 17.213584 -8.592091)
			(xy 17.251819 -8.663623) (xy 17.282858 -8.738559) (xy 17.304681 -8.810498) (xy 26.80538 -8.810498)
			(xy 26.809451 -8.754876) (xy 26.821577 -8.700439) (xy 26.8415 -8.648348) (xy 26.868796 -8.599713)
			(xy 26.902882 -8.55557) (xy 26.943031 -8.516861) (xy 26.988389 -8.48441) (xy 27.037989 -8.458909)
			(xy 27.090773 -8.440902) (xy 27.145616 -8.430772) (xy 27.20135 -8.428735) (xy 27.256787 -8.434835)
			(xy 27.310744 -8.448941) (xy 27.362073 -8.470753) (xy 27.409679 -8.499807) (xy 27.452547 -8.535482)
			(xy 27.489764 -8.577019) (xy 27.520537 -8.623532) (xy 27.544209 -8.674029) (xy 27.560277 -8.727436)
			(xy 27.568397 -8.782612) (xy 27.568906 -8.810498) (xy 27.568397 -8.838384) (xy 27.560277 -8.89356)
			(xy 27.544209 -8.946967) (xy 27.520537 -8.997464) (xy 27.489764 -9.043977) (xy 27.452547 -9.085514)
			(xy 27.409679 -9.121189) (xy 27.362073 -9.150243) (xy 27.310744 -9.172055) (xy 27.256787 -9.186161)
			(xy 27.20135 -9.192261) (xy 27.145616 -9.190224) (xy 27.090773 -9.180094) (xy 27.037989 -9.162087)
			(xy 26.988389 -9.136586) (xy 26.943031 -9.104135) (xy 26.902882 -9.065426) (xy 26.868796 -9.021283)
			(xy 26.8415 -8.972648) (xy 26.821577 -8.920557) (xy 26.809451 -8.86612) (xy 26.80538 -8.810498) (xy 17.304681 -8.810498)
			(xy 17.306403 -8.816175) (xy 17.322226 -8.895726) (xy 17.330176 -8.976445) (xy 17.330674 -9.017)
			(xy 17.330176 -9.057555) (xy 17.322226 -9.138274) (xy 17.306403 -9.217825) (xy 17.282858 -9.295441)
			(xy 17.251819 -9.370377) (xy 17.213584 -9.441909) (xy 17.168522 -9.509349) (xy 17.117067 -9.572048)
			(xy 17.059714 -9.629401) (xy 16.997015 -9.680856) (xy 16.948184 -9.713484) (xy 29.519874 -9.713484)
			(xy 29.519874 -9.626584) (xy 29.527892 -9.540055) (xy 29.54386 -9.454635) (xy 29.567641 -9.371053)
			(xy 29.599033 -9.290021) (xy 29.637767 -9.212232) (xy 29.683514 -9.138348) (xy 29.735883 -9.069001)
			(xy 29.794427 -9.004781) (xy 29.858647 -8.946237) (xy 29.927994 -8.893868) (xy 30.001878 -8.848121)
			(xy 30.079667 -8.809387) (xy 30.160699 -8.777995) (xy 30.244281 -8.754214) (xy 30.329701 -8.738246)
			(xy 30.41623 -8.730228) (xy 30.50313 -8.730228) (xy 30.589659 -8.738246) (xy 30.675079 -8.754214)
			(xy 30.758661 -8.777995) (xy 30.839693 -8.809387) (xy 30.917482 -8.848121) (xy 30.991366 -8.893868)
			(xy 31.060713 -8.946237) (xy 31.124933 -9.004781) (xy 31.183477 -9.069001) (xy 31.235846 -9.138348)
			(xy 31.281593 -9.212232) (xy 31.320327 -9.290021) (xy 31.351719 -9.371053) (xy 31.3755 -9.454635)
			(xy 31.391468 -9.540055) (xy 31.399486 -9.626584) (xy 31.399988 -9.670034) (xy 31.399486 -9.713484)
			(xy 34.599874 -9.713484) (xy 34.599874 -9.626584) (xy 34.607892 -9.540055) (xy 34.62386 -9.454635)
			(xy 34.647641 -9.371053) (xy 34.679033 -9.290021) (xy 34.717767 -9.212232) (xy 34.763514 -9.138348)
			(xy 34.815883 -9.069001) (xy 34.874427 -9.004781) (xy 34.938647 -8.946237) (xy 35.007994 -8.893868)
			(xy 35.081878 -8.848121) (xy 35.159667 -8.809387) (xy 35.240699 -8.777995) (xy 35.324281 -8.754214)
			(xy 35.409701 -8.738246) (xy 35.49623 -8.730228) (xy 35.58313 -8.730228) (xy 35.669659 -8.738246)
			(xy 35.755079 -8.754214) (xy 35.838661 -8.777995) (xy 35.919693 -8.809387) (xy 35.997482 -8.848121)
			(xy 36.071366 -8.893868) (xy 36.140713 -8.946237) (xy 36.204933 -9.004781) (xy 36.263477 -9.069001)
			(xy 36.315846 -9.138348) (xy 36.361593 -9.212232) (xy 36.400327 -9.290021) (xy 36.431719 -9.371053)
			(xy 36.4555 -9.454635) (xy 36.471468 -9.540055) (xy 36.479486 -9.626584) (xy 36.479988 -9.670034)
			(xy 36.479486 -9.713484) (xy 36.471468 -9.800013) (xy 36.4555 -9.885433) (xy 36.431719 -9.969015)
			(xy 36.400327 -10.050047) (xy 36.361593 -10.127836) (xy 36.315846 -10.20172) (xy 36.263477 -10.271067)
			(xy 36.204933 -10.335287) (xy 36.140713 -10.393831) (xy 36.071366 -10.4462) (xy 35.997482 -10.491947)
			(xy 35.919693 -10.530681) (xy 35.838661 -10.562073) (xy 35.755079 -10.585854) (xy 35.669659 -10.601822)
			(xy 35.58313 -10.60984) (xy 35.49623 -10.60984) (xy 35.409701 -10.601822) (xy 35.324281 -10.585854)
			(xy 35.240699 -10.562073) (xy 35.159667 -10.530681) (xy 35.081878 -10.491947) (xy 35.007994 -10.4462)
			(xy 34.938647 -10.393831) (xy 34.874427 -10.335287) (xy 34.815883 -10.271067) (xy 34.763514 -10.20172)
			(xy 34.717767 -10.127836) (xy 34.679033 -10.050047) (xy 34.647641 -9.969015) (xy 34.62386 -9.885433)
			(xy 34.607892 -9.800013) (xy 34.599874 -9.713484) (xy 31.399486 -9.713484) (xy 31.391468 -9.800013)
			(xy 31.3755 -9.885433) (xy 31.351719 -9.969015) (xy 31.320327 -10.050047) (xy 31.281593 -10.127836)
			(xy 31.235846 -10.20172) (xy 31.183477 -10.271067) (xy 31.124933 -10.335287) (xy 31.060713 -10.393831)
			(xy 30.991366 -10.4462) (xy 30.917482 -10.491947) (xy 30.839693 -10.530681) (xy 30.758661 -10.562073)
			(xy 30.675079 -10.585854) (xy 30.589659 -10.601822) (xy 30.50313 -10.60984) (xy 30.41623 -10.60984)
			(xy 30.329701 -10.601822) (xy 30.244281 -10.585854) (xy 30.160699 -10.562073) (xy 30.079667 -10.530681)
			(xy 30.001878 -10.491947) (xy 29.927994 -10.4462) (xy 29.858647 -10.393831) (xy 29.794427 -10.335287)
			(xy 29.735883 -10.271067) (xy 29.683514 -10.20172) (xy 29.637767 -10.127836) (xy 29.599033 -10.050047)
			(xy 29.567641 -9.969015) (xy 29.54386 -9.885433) (xy 29.527892 -9.800013) (xy 29.519874 -9.713484)
			(xy 16.948184 -9.713484) (xy 16.929575 -9.725918) (xy 16.858043 -9.764153) (xy 16.783107 -9.795192)
			(xy 16.705491 -9.818737) (xy 16.62594 -9.83456) (xy 16.545221 -9.84251) (xy 16.464111 -9.84251) (xy 16.383392 -9.83456)
			(xy 16.303841 -9.818737) (xy 16.226225 -9.795192) (xy 16.151289 -9.764153) (xy 16.079757 -9.725918)
			(xy 16.012317 -9.680856) (xy 15.949618 -9.629401) (xy 15.892265 -9.572048) (xy 15.84081 -9.509349)
			(xy 15.795748 -9.441909) (xy 15.757513 -9.370377) (xy 15.726474 -9.295441) (xy 15.702929 -9.217825)
			(xy 15.687106 -9.138274) (xy 15.679156 -9.057555) (xy 9.233757 -9.057555) (xy 9.204191 -9.094701)
			(xy 9.11768 -9.19055) (xy 9.025399 -9.280857) (xy 8.927703 -9.365277) (xy 8.824967 -9.443484) (xy 8.717584 -9.515179)
			(xy 8.605968 -9.580087) (xy 8.490546 -9.637957) (xy 8.371762 -9.688569) (xy 8.250072 -9.731728) (xy 8.125943 -9.767268)
			(xy 7.999851 -9.795052) (xy 7.87228 -9.814975) (xy 7.743721 -9.826959) (xy 7.614666 -9.830959) (xy 7.485611 -9.826959)
			(xy 7.357052 -9.814975) (xy 7.229481 -9.795052) (xy 7.103389 -9.767268) (xy 6.97926 -9.731728) (xy 6.85757 -9.688569)
			(xy 6.738786 -9.637957) (xy 6.623364 -9.580087) (xy 6.511748 -9.515179) (xy 6.404365 -9.443484) (xy 6.301629 -9.365277)
			(xy 6.203933 -9.280857) (xy 6.111652 -9.19055) (xy 6.025141 -9.094701) (xy 5.944732 -8.993678) (xy 5.870733 -8.88787)
			(xy 5.803429 -8.777683) (xy 5.743078 -8.663539) (xy 5.689911 -8.545876) (xy 5.644133 -8.425147) (xy 5.605919 -8.301815)
			(xy 5.575416 -8.176353) (xy 5.552741 -8.049243) (xy 5.537981 -7.920972) (xy 5.531193 -7.792034) (xy 5.532404 -7.662923)
			(xy 5.541607 -7.534134) (xy 5.558768 -7.406163) (xy 5.583821 -7.2795) (xy 5.616671 -7.154632) (xy 5.657189 -7.032037)
			(xy 5.705223 -6.912187) (xy 5.760586 -6.795542) (xy 5.823066 -6.682549) (xy 5.892424 -6.573643) (xy 5.968393 -6.46924)
			(xy 6.050681 -6.369743) (xy 6.138974 -6.275532) (xy 6.232931 -6.18697) (xy 6.332192 -6.104397) (xy 6.436376 -6.028129)
			(xy 6.490462 -5.992876) (xy 6.509836 -5.979842) (xy 6.543893 -5.947905) (xy 6.571543 -5.910284) (xy 6.591855 -5.868246)
			(xy 6.604147 -5.823205) (xy 6.608005 -5.776676) (xy 6.603298 -5.730225) (xy 6.590186 -5.685416) (xy 6.569108 -5.643755)
			(xy 6.540776 -5.606646) (xy 6.506141 -5.575337) (xy 6.46637 -5.550881) (xy 6.422801 -5.534101) (xy 6.3769 -5.525562)
			(xy 6.353556 -5.525008) (xy 1.652016 -5.525008) (xy 1.63536 -5.525501) (xy 1.603183 -5.534119) (xy 1.574334 -5.550773)
			(xy 1.550778 -5.574327) (xy 1.534122 -5.603176) (xy 1.525502 -5.635352) (xy 1.525016 -5.652008) (xy 1.525016 -10.327555)
			(xy 13.139156 -10.327555) (xy 13.139156 -10.246445) (xy 13.147106 -10.165726) (xy 13.162929 -10.086175)
			(xy 13.186474 -10.008559) (xy 13.217513 -9.933623) (xy 13.255748 -9.862091) (xy 13.30081 -9.794651)
			(xy 13.352265 -9.731952) (xy 13.409618 -9.674599) (xy 13.472317 -9.623144) (xy 13.539757 -9.578082)
			(xy 13.611289 -9.539847) (xy 13.686225 -9.508808) (xy 13.763841 -9.485263) (xy 13.843392 -9.46944)
			(xy 13.924111 -9.46149) (xy 14.005221 -9.46149) (xy 14.08594 -9.46944) (xy 14.165491 -9.485263) (xy 14.243107 -9.508808)
			(xy 14.318043 -9.539847) (xy 14.389575 -9.578082) (xy 14.457015 -9.623144) (xy 14.519714 -9.674599)
			(xy 14.577067 -9.731952) (xy 14.628522 -9.794651) (xy 14.673584 -9.862091) (xy 14.711819 -9.933623)
			(xy 14.742858 -10.008559) (xy 14.766403 -10.086175) (xy 14.782226 -10.165726) (xy 14.790176 -10.246445)
			(xy 14.790674 -10.287) (xy 14.790176 -10.327555) (xy 14.782226 -10.408274) (xy 14.766403 -10.487825)
			(xy 14.742858 -10.565441) (xy 14.721103 -10.617962) (xy 25.381202 -10.617962) (xy 25.385273 -10.56234)
			(xy 25.397399 -10.507903) (xy 25.417322 -10.455812) (xy 25.444618 -10.407177) (xy 25.478704 -10.363034)
			(xy 25.518853 -10.324325) (xy 25.564211 -10.291874) (xy 25.613811 -10.266373) (xy 25.666595 -10.248366)
			(xy 25.721438 -10.238236) (xy 25.777172 -10.236199) (xy 25.832609 -10.242299) (xy 25.886566 -10.256405)
			(xy 25.937895 -10.278217) (xy 25.985501 -10.307271) (xy 26.028369 -10.342946) (xy 26.065586 -10.384483)
			(xy 26.096359 -10.430996) (xy 26.120031 -10.481493) (xy 26.136099 -10.5349) (xy 26.144219 -10.590076)
			(xy 26.144728 -10.617962) (xy 26.144219 -10.645848) (xy 26.136099 -10.701024) (xy 26.120031 -10.754431)
			(xy 26.096359 -10.804928) (xy 26.065586 -10.851441) (xy 26.028369 -10.892978) (xy 25.985501 -10.928653)
			(xy 25.937895 -10.957707) (xy 25.886566 -10.979519) (xy 25.832609 -10.993625) (xy 25.777172 -10.999725)
			(xy 25.721438 -10.997688) (xy 25.666595 -10.987558) (xy 25.613811 -10.969551) (xy 25.564211 -10.94405)
			(xy 25.518853 -10.911599) (xy 25.478704 -10.87289) (xy 25.444618 -10.828747) (xy 25.417322 -10.780112)
			(xy 25.397399 -10.728021) (xy 25.385273 -10.673584) (xy 25.381202 -10.617962) (xy 14.721103 -10.617962)
			(xy 14.711819 -10.640377) (xy 14.673584 -10.711909) (xy 14.628522 -10.779349) (xy 14.577067 -10.842048)
			(xy 14.519714 -10.899401) (xy 14.457015 -10.950856) (xy 14.389575 -10.995918) (xy 14.318043 -11.034153)
			(xy 14.243107 -11.065192) (xy 14.165491 -11.088737) (xy 14.08594 -11.10456) (xy 14.005221 -11.11251)
			(xy 13.924111 -11.11251) (xy 13.843392 -11.10456) (xy 13.763841 -11.088737) (xy 13.686225 -11.065192)
			(xy 13.611289 -11.034153) (xy 13.539757 -10.995918) (xy 13.472317 -10.950856) (xy 13.409618 -10.899401)
			(xy 13.352265 -10.842048) (xy 13.30081 -10.779349) (xy 13.255748 -10.711909) (xy 13.217513 -10.640377)
			(xy 13.186474 -10.565441) (xy 13.162929 -10.487825) (xy 13.147106 -10.408274) (xy 13.139156 -10.327555)
			(xy 1.525016 -10.327555) (xy 1.525016 -11.597555) (xy 15.679156 -11.597555) (xy 15.679156 -11.516445)
			(xy 15.687106 -11.435726) (xy 15.702929 -11.356175) (xy 15.726474 -11.278559) (xy 15.757513 -11.203623)
			(xy 15.795748 -11.132091) (xy 15.84081 -11.064651) (xy 15.892265 -11.001952) (xy 15.949618 -10.944599)
			(xy 16.012317 -10.893144) (xy 16.079757 -10.848082) (xy 16.151289 -10.809847) (xy 16.226225 -10.778808)
			(xy 16.303841 -10.755263) (xy 16.383392 -10.73944) (xy 16.464111 -10.73149) (xy 16.545221 -10.73149)
			(xy 16.62594 -10.73944) (xy 16.705491 -10.755263) (xy 16.783107 -10.778808) (xy 16.858043 -10.809847)
			(xy 16.929575 -10.848082) (xy 16.997015 -10.893144) (xy 17.059714 -10.944599) (xy 17.117067 -11.001952)
			(xy 17.168522 -11.064651) (xy 17.213584 -11.132091) (xy 17.251819 -11.203623) (xy 17.282858 -11.278559)
			(xy 17.306403 -11.356175) (xy 17.322226 -11.435726) (xy 17.330176 -11.516445) (xy 17.330674 -11.557)
			(xy 17.330176 -11.597555) (xy 17.322226 -11.678274) (xy 17.306403 -11.757825) (xy 17.282858 -11.835441)
			(xy 17.251819 -11.910377) (xy 17.213584 -11.981909) (xy 17.168522 -12.049349) (xy 17.117067 -12.112048)
			(xy 17.059714 -12.169401) (xy 16.997015 -12.220856) (xy 16.948184 -12.253484) (xy 29.519874 -12.253484)
			(xy 29.519874 -12.166584) (xy 29.527892 -12.080055) (xy 29.54386 -11.994635) (xy 29.567641 -11.911053)
			(xy 29.599033 -11.830021) (xy 29.637767 -11.752232) (xy 29.683514 -11.678348) (xy 29.735883 -11.609001)
			(xy 29.794427 -11.544781) (xy 29.858647 -11.486237) (xy 29.927994 -11.433868) (xy 30.001878 -11.388121)
			(xy 30.079667 -11.349387) (xy 30.160699 -11.317995) (xy 30.244281 -11.294214) (xy 30.329701 -11.278246)
			(xy 30.41623 -11.270228) (xy 30.50313 -11.270228) (xy 30.589659 -11.278246) (xy 30.675079 -11.294214)
			(xy 30.758661 -11.317995) (xy 30.839693 -11.349387) (xy 30.917482 -11.388121) (xy 30.991366 -11.433868)
			(xy 31.060713 -11.486237) (xy 31.124933 -11.544781) (xy 31.183477 -11.609001) (xy 31.235846 -11.678348)
			(xy 31.281593 -11.752232) (xy 31.320327 -11.830021) (xy 31.351719 -11.911053) (xy 31.3755 -11.994635)
			(xy 31.391468 -12.080055) (xy 31.399486 -12.166584) (xy 31.399988 -12.210034) (xy 31.399486 -12.253484)
			(xy 34.599874 -12.253484) (xy 34.599874 -12.166584) (xy 34.607892 -12.080055) (xy 34.62386 -11.994635)
			(xy 34.647641 -11.911053) (xy 34.679033 -11.830021) (xy 34.717767 -11.752232) (xy 34.763514 -11.678348)
			(xy 34.815883 -11.609001) (xy 34.874427 -11.544781) (xy 34.938647 -11.486237) (xy 35.007994 -11.433868)
			(xy 35.081878 -11.388121) (xy 35.159667 -11.349387) (xy 35.240699 -11.317995) (xy 35.324281 -11.294214)
			(xy 35.409701 -11.278246) (xy 35.49623 -11.270228) (xy 35.58313 -11.270228) (xy 35.669659 -11.278246)
			(xy 35.755079 -11.294214) (xy 35.838661 -11.317995) (xy 35.919693 -11.349387) (xy 35.997482 -11.388121)
			(xy 36.071366 -11.433868) (xy 36.140713 -11.486237) (xy 36.204933 -11.544781) (xy 36.263477 -11.609001)
			(xy 36.315846 -11.678348) (xy 36.361593 -11.752232) (xy 36.400327 -11.830021) (xy 36.431719 -11.911053)
			(xy 36.4555 -11.994635) (xy 36.471468 -12.080055) (xy 36.479486 -12.166584) (xy 36.479988 -12.210034)
			(xy 36.479486 -12.253484) (xy 36.471723 -12.33726) (xy 64.785847 -12.33726) (xy 64.789739 -12.282905)
			(xy 64.801327 -12.229658) (xy 64.820375 -12.178602) (xy 64.846496 -12.130776) (xy 64.862456 -12.108688)
			(xy 64.876065 -12.089684) (xy 64.8968 -12.0478) (xy 64.909527 -12.002829) (xy 64.913816 -11.95629)
			(xy 64.909523 -11.909752) (xy 64.896793 -11.864782) (xy 64.876055 -11.822899) (xy 64.862456 -11.803888)
			(xy 64.846496 -11.7818) (xy 64.820375 -11.733974) (xy 64.801327 -11.682918) (xy 64.789739 -11.629671)
			(xy 64.785847 -11.575316) (xy 64.789731 -11.520961) (xy 64.801311 -11.467712) (xy 64.820352 -11.416653)
			(xy 64.846466 -11.368823) (xy 64.879121 -11.325197) (xy 64.917652 -11.286663) (xy 64.961276 -11.254005)
			(xy 65.009103 -11.227888) (xy 65.060161 -11.208843) (xy 65.113409 -11.197259) (xy 65.167764 -11.193371)
			(xy 65.222119 -11.197259) (xy 65.275367 -11.208843) (xy 65.326425 -11.227888) (xy 65.374252 -11.254005)
			(xy 65.417876 -11.286663) (xy 65.456407 -11.325197) (xy 65.489062 -11.368823) (xy 65.515176 -11.416653)
			(xy 65.534217 -11.467712) (xy 65.545797 -11.520961) (xy 65.549681 -11.575316) (xy 65.545789 -11.629671)
			(xy 65.534201 -11.682918) (xy 65.515153 -11.733974) (xy 65.489032 -11.7818) (xy 65.473072 -11.803888)
			(xy 65.459489 -11.822908) (xy 65.438758 -11.86479) (xy 65.426032 -11.909756) (xy 65.421741 -11.95629)
			(xy 65.426029 -12.002825) (xy 65.438751 -12.047792) (xy 65.459479 -12.089675) (xy 65.473072 -12.108688)
			(xy 65.489032 -12.130776) (xy 65.515153 -12.178602) (xy 65.534201 -12.229658) (xy 65.545789 -12.282905)
			(xy 65.549681 -12.33726) (xy 66.700499 -12.33726) (xy 66.704391 -12.282905) (xy 66.715979 -12.229658)
			(xy 66.735027 -12.178602) (xy 66.761148 -12.130776) (xy 66.777108 -12.108688) (xy 66.790714 -12.089683)
			(xy 66.811445 -12.047798) (xy 66.824169 -12.002828) (xy 66.828458 -11.95629) (xy 66.824166 -11.909753)
			(xy 66.811438 -11.864784) (xy 66.790704 -11.8229) (xy 66.777108 -11.803888) (xy 66.761148 -11.7818)
			(xy 66.735027 -11.733974) (xy 66.715979 -11.682918) (xy 66.704391 -11.629671) (xy 66.700499 -11.575316)
			(xy 66.704383 -11.520961) (xy 66.715963 -11.467712) (xy 66.735004 -11.416653) (xy 66.761118 -11.368823)
			(xy 66.793773 -11.325197) (xy 66.832304 -11.286663) (xy 66.875928 -11.254005) (xy 66.923755 -11.227888)
			(xy 66.974813 -11.208843) (xy 67.028061 -11.197259) (xy 67.082416 -11.193371) (xy 67.136771 -11.197259)
			(xy 67.190019 -11.208843) (xy 67.241077 -11.227888) (xy 67.288904 -11.254005) (xy 67.332528 -11.286663)
			(xy 67.371059 -11.325197) (xy 67.403714 -11.368823) (xy 67.429828 -11.416653) (xy 67.448869 -11.467712)
			(xy 67.460449 -11.520961) (xy 67.464333 -11.575316) (xy 67.460441 -11.629671) (xy 67.448853 -11.682918)
			(xy 67.429805 -11.733974) (xy 67.403684 -11.7818) (xy 67.387724 -11.803888) (xy 67.374138 -11.822907)
			(xy 67.353403 -11.864788) (xy 67.340675 -11.909755) (xy 67.336382 -11.95629) (xy 67.340671 -12.002826)
			(xy 67.353396 -12.047794) (xy 67.374128 -12.089676) (xy 67.387724 -12.108688) (xy 67.403684 -12.130776)
			(xy 67.429805 -12.178602) (xy 67.448853 -12.229658) (xy 67.460441 -12.282905) (xy 67.464333 -12.33726)
			(xy 68.597371 -12.33726) (xy 68.601263 -12.282905) (xy 68.612851 -12.229658) (xy 68.631899 -12.178602)
			(xy 68.65802 -12.130776) (xy 68.67398 -12.108688) (xy 68.687588 -12.089684) (xy 68.708321 -12.047799)
			(xy 68.721046 -12.002829) (xy 68.725335 -11.95629) (xy 68.721043 -11.909752) (xy 68.708314 -11.864783)
			(xy 68.687578 -11.8229) (xy 68.67398 -11.803888) (xy 68.65802 -11.7818) (xy 68.631899 -11.733974)
			(xy 68.612851 -11.682918) (xy 68.601263 -11.629671) (xy 68.597371 -11.575316) (xy 68.601255 -11.520961)
			(xy 68.612835 -11.467712) (xy 68.631876 -11.416653) (xy 68.65799 -11.368823) (xy 68.690645 -11.325197)
			(xy 68.729176 -11.286663) (xy 68.7728 -11.254005) (xy 68.820627 -11.227888) (xy 68.871685 -11.208843)
			(xy 68.924933 -11.197259) (xy 68.979288 -11.193371) (xy 69.033643 -11.197259) (xy 69.086891 -11.208843)
			(xy 69.137949 -11.227888) (xy 69.185776 -11.254005) (xy 69.2294 -11.286663) (xy 69.267931 -11.325197)
			(xy 69.300586 -11.368823) (xy 69.3267 -11.416653) (xy 69.345741 -11.467712) (xy 69.357321 -11.520961)
			(xy 69.361205 -11.575316) (xy 69.357313 -11.629671) (xy 69.345725 -11.682918) (xy 69.326677 -11.733974)
			(xy 69.300556 -11.7818) (xy 69.284596 -11.803888) (xy 69.271012 -11.822908) (xy 69.250279 -11.864789)
			(xy 69.237552 -11.909755) (xy 69.23326 -11.95629) (xy 69.237548 -12.002826) (xy 69.250272 -12.047793)
			(xy 69.271002 -12.089676) (xy 69.284596 -12.108688) (xy 69.300556 -12.130776) (xy 69.326677 -12.178602)
			(xy 69.345725 -12.229658) (xy 69.357313 -12.282905) (xy 69.361205 -12.33726) (xy 70.675599 -12.33726)
			(xy 70.679491 -12.282905) (xy 70.691079 -12.229658) (xy 70.710127 -12.178602) (xy 70.736248 -12.130776)
			(xy 70.752208 -12.108688) (xy 70.765814 -12.089683) (xy 70.786545 -12.047798) (xy 70.799269 -12.002828)
			(xy 70.803558 -11.95629) (xy 70.799266 -11.909753) (xy 70.786538 -11.864784) (xy 70.765804 -11.8229)
			(xy 70.752208 -11.803888) (xy 70.736248 -11.7818) (xy 70.710127 -11.733974) (xy 70.691079 -11.682918)
			(xy 70.679491 -11.629671) (xy 70.675599 -11.575316) (xy 70.679483 -11.520961) (xy 70.691063 -11.467712)
			(xy 70.710104 -11.416653) (xy 70.736218 -11.368823) (xy 70.768873 -11.325197) (xy 70.807404 -11.286663)
			(xy 70.851028 -11.254005) (xy 70.898855 -11.227888) (xy 70.949913 -11.208843) (xy 71.003161 -11.197259)
			(xy 71.057516 -11.193371) (xy 71.111871 -11.197259) (xy 71.165119 -11.208843) (xy 71.216177 -11.227888)
			(xy 71.264004 -11.254005) (xy 71.307628 -11.286663) (xy 71.346159 -11.325197) (xy 71.378814 -11.368823)
			(xy 71.404928 -11.416653) (xy 71.423969 -11.467712) (xy 71.435549 -11.520961) (xy 71.439433 -11.575316)
			(xy 71.435541 -11.629671) (xy 71.423953 -11.682918) (xy 71.404905 -11.733974) (xy 71.378784 -11.7818)
			(xy 71.362824 -11.803888) (xy 71.349238 -11.822907) (xy 71.328503 -11.864788) (xy 71.315775 -11.909755)
			(xy 71.311482 -11.95629) (xy 71.315771 -12.002826) (xy 71.328496 -12.047794) (xy 71.349228 -12.089676)
			(xy 71.362824 -12.108688) (xy 71.378784 -12.130776) (xy 71.404905 -12.178602) (xy 71.423953 -12.229658)
			(xy 71.435541 -12.282905) (xy 71.439433 -12.33726) (xy 72.795991 -12.33726) (xy 72.799883 -12.282905)
			(xy 72.811471 -12.229658) (xy 72.830519 -12.178602) (xy 72.85664 -12.130776) (xy 72.8726 -12.108688)
			(xy 72.886207 -12.089684) (xy 72.906938 -12.047798) (xy 72.919663 -12.002828) (xy 72.923951 -11.95629)
			(xy 72.919659 -11.909753) (xy 72.906931 -11.864784) (xy 72.886197 -11.8229) (xy 72.8726 -11.803888)
			(xy 72.85664 -11.7818) (xy 72.830519 -11.733974) (xy 72.811471 -11.682918) (xy 72.799883 -11.629671)
			(xy 72.795991 -11.575316) (xy 72.799875 -11.520961) (xy 72.811455 -11.467712) (xy 72.830496 -11.416653)
			(xy 72.85661 -11.368823) (xy 72.889265 -11.325197) (xy 72.927796 -11.286663) (xy 72.97142 -11.254005)
			(xy 73.019247 -11.227888) (xy 73.070305 -11.208843) (xy 73.123553 -11.197259) (xy 73.177908 -11.193371)
			(xy 73.232263 -11.197259) (xy 73.285511 -11.208843) (xy 73.336569 -11.227888) (xy 73.384396 -11.254005)
			(xy 73.42802 -11.286663) (xy 73.466551 -11.325197) (xy 73.499206 -11.368823) (xy 73.52532 -11.416653)
			(xy 73.544361 -11.467712) (xy 73.555941 -11.520961) (xy 73.559825 -11.575316) (xy 73.555933 -11.629671)
			(xy 73.544345 -11.682918) (xy 73.525297 -11.733974) (xy 73.499176 -11.7818) (xy 73.483216 -11.803888)
			(xy 73.469631 -11.822907) (xy 73.448896 -11.864789) (xy 73.436168 -11.909755) (xy 73.431876 -11.95629)
			(xy 73.436165 -12.002826) (xy 73.448889 -12.047793) (xy 73.469621 -12.089676) (xy 73.483216 -12.108688)
			(xy 73.499176 -12.130776) (xy 73.525297 -12.178602) (xy 73.544345 -12.229658) (xy 73.555933 -12.282905)
			(xy 73.559825 -12.33726) (xy 73.555941 -12.391615) (xy 73.544361 -12.444864) (xy 73.52532 -12.495923)
			(xy 73.499206 -12.543753) (xy 73.466551 -12.587379) (xy 73.42802 -12.625913) (xy 73.384396 -12.658571)
			(xy 73.336569 -12.684688) (xy 73.285511 -12.703733) (xy 73.232263 -12.715317) (xy 73.177908 -12.719205)
			(xy 73.123553 -12.715317) (xy 73.070305 -12.703733) (xy 73.019247 -12.684688) (xy 72.97142 -12.658571)
			(xy 72.927796 -12.625913) (xy 72.889265 -12.587379) (xy 72.85661 -12.543753) (xy 72.830496 -12.495923)
			(xy 72.811455 -12.444864) (xy 72.799875 -12.391615) (xy 72.795991 -12.33726) (xy 71.439433 -12.33726)
			(xy 71.435549 -12.391615) (xy 71.423969 -12.444864) (xy 71.404928 -12.495923) (xy 71.378814 -12.543753)
			(xy 71.346159 -12.587379) (xy 71.307628 -12.625913) (xy 71.264004 -12.658571) (xy 71.216177 -12.684688)
			(xy 71.165119 -12.703733) (xy 71.111871 -12.715317) (xy 71.057516 -12.719205) (xy 71.003161 -12.715317)
			(xy 70.949913 -12.703733) (xy 70.898855 -12.684688) (xy 70.851028 -12.658571) (xy 70.807404 -12.625913)
			(xy 70.768873 -12.587379) (xy 70.736218 -12.543753) (xy 70.710104 -12.495923) (xy 70.691063 -12.444864)
			(xy 70.679483 -12.391615) (xy 70.675599 -12.33726) (xy 69.361205 -12.33726) (xy 69.357321 -12.391615)
			(xy 69.345741 -12.444864) (xy 69.3267 -12.495923) (xy 69.300586 -12.543753) (xy 69.267931 -12.587379)
			(xy 69.2294 -12.625913) (xy 69.185776 -12.658571) (xy 69.137949 -12.684688) (xy 69.086891 -12.703733)
			(xy 69.033643 -12.715317) (xy 68.979288 -12.719205) (xy 68.924933 -12.715317) (xy 68.871685 -12.703733)
			(xy 68.820627 -12.684688) (xy 68.7728 -12.658571) (xy 68.729176 -12.625913) (xy 68.690645 -12.587379)
			(xy 68.65799 -12.543753) (xy 68.631876 -12.495923) (xy 68.612835 -12.444864) (xy 68.601255 -12.391615)
			(xy 68.597371 -12.33726) (xy 67.464333 -12.33726) (xy 67.460449 -12.391615) (xy 67.448869 -12.444864)
			(xy 67.429828 -12.495923) (xy 67.403714 -12.543753) (xy 67.371059 -12.587379) (xy 67.332528 -12.625913)
			(xy 67.288904 -12.658571) (xy 67.241077 -12.684688) (xy 67.190019 -12.703733) (xy 67.136771 -12.715317)
			(xy 67.082416 -12.719205) (xy 67.028061 -12.715317) (xy 66.974813 -12.703733) (xy 66.923755 -12.684688)
			(xy 66.875928 -12.658571) (xy 66.832304 -12.625913) (xy 66.793773 -12.587379) (xy 66.761118 -12.543753)
			(xy 66.735004 -12.495923) (xy 66.715963 -12.444864) (xy 66.704383 -12.391615) (xy 66.700499 -12.33726)
			(xy 65.549681 -12.33726) (xy 65.545797 -12.391615) (xy 65.534217 -12.444864) (xy 65.515176 -12.495923)
			(xy 65.489062 -12.543753) (xy 65.456407 -12.587379) (xy 65.417876 -12.625913) (xy 65.374252 -12.658571)
			(xy 65.326425 -12.684688) (xy 65.275367 -12.703733) (xy 65.222119 -12.715317) (xy 65.167764 -12.719205)
			(xy 65.113409 -12.715317) (xy 65.060161 -12.703733) (xy 65.009103 -12.684688) (xy 64.961276 -12.658571)
			(xy 64.917652 -12.625913) (xy 64.879121 -12.587379) (xy 64.846466 -12.543753) (xy 64.820352 -12.495923)
			(xy 64.801311 -12.444864) (xy 64.789731 -12.391615) (xy 64.785847 -12.33726) (xy 36.471723 -12.33726)
			(xy 36.471468 -12.340013) (xy 36.4555 -12.425433) (xy 36.431719 -12.509015) (xy 36.400327 -12.590047)
			(xy 36.361593 -12.667836) (xy 36.315846 -12.74172) (xy 36.263477 -12.811067) (xy 36.204933 -12.875287)
			(xy 36.140713 -12.933831) (xy 36.071366 -12.9862) (xy 35.997482 -13.031947) (xy 35.936717 -13.062204)
			(xy 39.637714 -13.062204) (xy 39.641785 -13.006582) (xy 39.653911 -12.952145) (xy 39.673834 -12.900054)
			(xy 39.70113 -12.851419) (xy 39.735216 -12.807276) (xy 39.775365 -12.768567) (xy 39.820723 -12.736116)
			(xy 39.870323 -12.710615) (xy 39.923107 -12.692608) (xy 39.97795 -12.682478) (xy 40.033684 -12.680441)
			(xy 40.089121 -12.686541) (xy 40.143078 -12.700647) (xy 40.194407 -12.722459) (xy 40.242013 -12.751513)
			(xy 40.284881 -12.787188) (xy 40.322098 -12.828725) (xy 40.352871 -12.875238) (xy 40.376543 -12.925735)
			(xy 40.392611 -12.979142) (xy 40.400731 -13.034318) (xy 40.401161 -13.057886) (xy 83.794344 -13.057886)
			(xy 83.798415 -13.002264) (xy 83.810541 -12.947827) (xy 83.830464 -12.895736) (xy 83.85776 -12.847101)
			(xy 83.891846 -12.802958) (xy 83.931995 -12.764249) (xy 83.977353 -12.731798) (xy 84.026953 -12.706297)
			(xy 84.079737 -12.68829) (xy 84.13458 -12.67816) (xy 84.190314 -12.676123) (xy 84.245751 -12.682223)
			(xy 84.299708 -12.696329) (xy 84.351037 -12.718141) (xy 84.398643 -12.747195) (xy 84.441511 -12.78287)
			(xy 84.478728 -12.824407) (xy 84.509501 -12.87092) (xy 84.533173 -12.921417) (xy 84.549241 -12.974824)
			(xy 84.557361 -13.03) (xy 84.55787 -13.057886) (xy 84.557361 -13.085772) (xy 84.55511 -13.101066)
			(xy 86.072724 -13.101066) (xy 86.076795 -13.045444) (xy 86.088921 -12.991007) (xy 86.108844 -12.938916)
			(xy 86.13614 -12.890281) (xy 86.170226 -12.846138) (xy 86.210375 -12.807429) (xy 86.255733 -12.774978)
			(xy 86.305333 -12.749477) (xy 86.358117 -12.73147) (xy 86.41296 -12.72134) (xy 86.468694 -12.719303)
			(xy 86.524131 -12.725403) (xy 86.578088 -12.739509) (xy 86.629417 -12.761321) (xy 86.677023 -12.790375)
			(xy 86.719891 -12.82605) (xy 86.757108 -12.867587) (xy 86.787881 -12.9141) (xy 86.790273 -12.919202)
			(xy 88.083388 -12.919202) (xy 88.087459 -12.86358) (xy 88.099585 -12.809143) (xy 88.119508 -12.757052)
			(xy 88.146804 -12.708417) (xy 88.18089 -12.664274) (xy 88.221039 -12.625565) (xy 88.266397 -12.593114)
			(xy 88.315997 -12.567613) (xy 88.368781 -12.549606) (xy 88.423624 -12.539476) (xy 88.479358 -12.537439)
			(xy 88.534795 -12.543539) (xy 88.588752 -12.557645) (xy 88.640081 -12.579457) (xy 88.687687 -12.608511)
			(xy 88.730555 -12.644186) (xy 88.767772 -12.685723) (xy 88.798545 -12.732236) (xy 88.822217 -12.782733)
			(xy 88.838285 -12.83614) (xy 88.846405 -12.891316) (xy 88.846914 -12.919202) (xy 88.846405 -12.947088)
			(xy 88.838285 -13.002264) (xy 88.822217 -13.055671) (xy 88.798545 -13.106168) (xy 88.767772 -13.152681)
			(xy 88.730555 -13.194218) (xy 88.687687 -13.229893) (xy 88.640081 -13.258947) (xy 88.588752 -13.280759)
			(xy 88.534795 -13.294865) (xy 88.479358 -13.300965) (xy 88.423624 -13.298928) (xy 88.368781 -13.288798)
			(xy 88.315997 -13.270791) (xy 88.266397 -13.24529) (xy 88.221039 -13.212839) (xy 88.18089 -13.17413)
			(xy 88.146804 -13.129987) (xy 88.119508 -13.081352) (xy 88.099585 -13.029261) (xy 88.087459 -12.974824)
			(xy 88.083388 -12.919202) (xy 86.790273 -12.919202) (xy 86.811553 -12.964597) (xy 86.827621 -13.018004)
			(xy 86.835741 -13.07318) (xy 86.83625 -13.101066) (xy 86.835741 -13.128952) (xy 86.827621 -13.184128)
			(xy 86.811553 -13.237535) (xy 86.787881 -13.288032) (xy 86.757108 -13.334545) (xy 86.719891 -13.376082)
			(xy 86.677023 -13.411757) (xy 86.629417 -13.440811) (xy 86.578088 -13.462623) (xy 86.524131 -13.476729)
			(xy 86.468694 -13.482829) (xy 86.41296 -13.480792) (xy 86.358117 -13.470662) (xy 86.305333 -13.452655)
			(xy 86.255733 -13.427154) (xy 86.210375 -13.394703) (xy 86.170226 -13.355994) (xy 86.13614 -13.311851)
			(xy 86.108844 -13.263216) (xy 86.088921 -13.211125) (xy 86.076795 -13.156688) (xy 86.072724 -13.101066)
			(xy 84.55511 -13.101066) (xy 84.549241 -13.140948) (xy 84.533173 -13.194355) (xy 84.509501 -13.244852)
			(xy 84.478728 -13.291365) (xy 84.441511 -13.332902) (xy 84.398643 -13.368577) (xy 84.351037 -13.397631)
			(xy 84.299708 -13.419443) (xy 84.245751 -13.433549) (xy 84.190314 -13.439649) (xy 84.13458 -13.437612)
			(xy 84.079737 -13.427482) (xy 84.026953 -13.409475) (xy 83.977353 -13.383974) (xy 83.931995 -13.351523)
			(xy 83.891846 -13.312814) (xy 83.85776 -13.268671) (xy 83.830464 -13.220036) (xy 83.810541 -13.167945)
			(xy 83.798415 -13.113508) (xy 83.794344 -13.057886) (xy 40.401161 -13.057886) (xy 40.40124 -13.062204)
			(xy 40.400731 -13.09009) (xy 40.392611 -13.145266) (xy 40.376543 -13.198673) (xy 40.352871 -13.24917)
			(xy 40.322098 -13.295683) (xy 40.284881 -13.33722) (xy 40.242013 -13.372895) (xy 40.194407 -13.401949)
			(xy 40.143078 -13.423761) (xy 40.089121 -13.437867) (xy 40.033684 -13.443967) (xy 39.97795 -13.44193)
			(xy 39.923107 -13.4318) (xy 39.870323 -13.413793) (xy 39.820723 -13.388292) (xy 39.775365 -13.355841)
			(xy 39.735216 -13.317132) (xy 39.70113 -13.272989) (xy 39.673834 -13.224354) (xy 39.653911 -13.172263)
			(xy 39.641785 -13.117826) (xy 39.637714 -13.062204) (xy 35.936717 -13.062204) (xy 35.919693 -13.070681)
			(xy 35.838661 -13.102073) (xy 35.755079 -13.125854) (xy 35.669659 -13.141822) (xy 35.58313 -13.14984)
			(xy 35.49623 -13.14984) (xy 35.409701 -13.141822) (xy 35.324281 -13.125854) (xy 35.240699 -13.102073)
			(xy 35.159667 -13.070681) (xy 35.081878 -13.031947) (xy 35.007994 -12.9862) (xy 34.938647 -12.933831)
			(xy 34.874427 -12.875287) (xy 34.815883 -12.811067) (xy 34.763514 -12.74172) (xy 34.717767 -12.667836)
			(xy 34.679033 -12.590047) (xy 34.647641 -12.509015) (xy 34.62386 -12.425433) (xy 34.607892 -12.340013)
			(xy 34.599874 -12.253484) (xy 31.399486 -12.253484) (xy 31.391468 -12.340013) (xy 31.3755 -12.425433)
			(xy 31.351719 -12.509015) (xy 31.320327 -12.590047) (xy 31.281593 -12.667836) (xy 31.235846 -12.74172)
			(xy 31.183477 -12.811067) (xy 31.124933 -12.875287) (xy 31.060713 -12.933831) (xy 30.991366 -12.9862)
			(xy 30.917482 -13.031947) (xy 30.839693 -13.070681) (xy 30.758661 -13.102073) (xy 30.675079 -13.125854)
			(xy 30.589659 -13.141822) (xy 30.50313 -13.14984) (xy 30.41623 -13.14984) (xy 30.329701 -13.141822)
			(xy 30.244281 -13.125854) (xy 30.160699 -13.102073) (xy 30.079667 -13.070681) (xy 30.001878 -13.031947)
			(xy 29.927994 -12.9862) (xy 29.858647 -12.933831) (xy 29.794427 -12.875287) (xy 29.735883 -12.811067)
			(xy 29.683514 -12.74172) (xy 29.637767 -12.667836) (xy 29.599033 -12.590047) (xy 29.567641 -12.509015)
			(xy 29.54386 -12.425433) (xy 29.527892 -12.340013) (xy 29.519874 -12.253484) (xy 16.948184 -12.253484)
			(xy 16.929575 -12.265918) (xy 16.858043 -12.304153) (xy 16.783107 -12.335192) (xy 16.705491 -12.358737)
			(xy 16.62594 -12.37456) (xy 16.545221 -12.38251) (xy 16.464111 -12.38251) (xy 16.383392 -12.37456)
			(xy 16.303841 -12.358737) (xy 16.226225 -12.335192) (xy 16.151289 -12.304153) (xy 16.079757 -12.265918)
			(xy 16.012317 -12.220856) (xy 15.949618 -12.169401) (xy 15.892265 -12.112048) (xy 15.84081 -12.049349)
			(xy 15.795748 -11.981909) (xy 15.757513 -11.910377) (xy 15.726474 -11.835441) (xy 15.702929 -11.757825)
			(xy 15.687106 -11.678274) (xy 15.679156 -11.597555) (xy 1.525016 -11.597555) (xy 1.525016 -12.674092)
			(xy 26.898852 -12.674092) (xy 26.902923 -12.61847) (xy 26.915049 -12.564033) (xy 26.934972 -12.511942)
			(xy 26.962268 -12.463307) (xy 26.996354 -12.419164) (xy 27.036503 -12.380455) (xy 27.081861 -12.348004)
			(xy 27.131461 -12.322503) (xy 27.184245 -12.304496) (xy 27.239088 -12.294366) (xy 27.294822 -12.292329)
			(xy 27.350259 -12.298429) (xy 27.404216 -12.312535) (xy 27.455545 -12.334347) (xy 27.503151 -12.363401)
			(xy 27.546019 -12.399076) (xy 27.583236 -12.440613) (xy 27.614009 -12.487126) (xy 27.637681 -12.537623)
			(xy 27.653749 -12.59103) (xy 27.661869 -12.646206) (xy 27.662378 -12.674092) (xy 27.661869 -12.701978)
			(xy 27.653749 -12.757154) (xy 27.637681 -12.810561) (xy 27.614009 -12.861058) (xy 27.583236 -12.907571)
			(xy 27.546019 -12.949108) (xy 27.503151 -12.984783) (xy 27.455545 -13.013837) (xy 27.404216 -13.035649)
			(xy 27.350259 -13.049755) (xy 27.294822 -13.055855) (xy 27.239088 -13.053818) (xy 27.184245 -13.043688)
			(xy 27.131461 -13.025681) (xy 27.081861 -13.00018) (xy 27.036503 -12.967729) (xy 26.996354 -12.92902)
			(xy 26.962268 -12.884877) (xy 26.934972 -12.836242) (xy 26.915049 -12.784151) (xy 26.902923 -12.729714)
			(xy 26.898852 -12.674092) (xy 1.525016 -12.674092) (xy 1.525016 -15.407555) (xy 13.139156 -15.407555)
			(xy 13.139156 -15.326445) (xy 13.147106 -15.245726) (xy 13.162929 -15.166175) (xy 13.186474 -15.088559)
			(xy 13.217513 -15.013623) (xy 13.255748 -14.942091) (xy 13.30081 -14.874651) (xy 13.352265 -14.811952)
			(xy 13.409618 -14.754599) (xy 13.472317 -14.703144) (xy 13.539757 -14.658082) (xy 13.611289 -14.619847)
			(xy 13.686225 -14.588808) (xy 13.763841 -14.565263) (xy 13.843392 -14.54944) (xy 13.924111 -14.54149)
			(xy 14.005221 -14.54149) (xy 14.08594 -14.54944) (xy 14.165491 -14.565263) (xy 14.243107 -14.588808)
			(xy 14.318043 -14.619847) (xy 14.389575 -14.658082) (xy 14.457015 -14.703144) (xy 14.519714 -14.754599)
			(xy 14.560615 -14.7955) (xy 27.317698 -14.7955) (xy 27.321769 -14.739878) (xy 27.333895 -14.685441)
			(xy 27.353818 -14.63335) (xy 27.381114 -14.584715) (xy 27.4152 -14.540572) (xy 27.455349 -14.501863)
			(xy 27.500707 -14.469412) (xy 27.550307 -14.443911) (xy 27.603091 -14.425904) (xy 27.657934 -14.415774)
			(xy 27.713668 -14.413737) (xy 27.769105 -14.419837) (xy 27.823062 -14.433943) (xy 27.874391 -14.455755)
			(xy 27.921997 -14.484809) (xy 27.964865 -14.520484) (xy 28.002082 -14.562021) (xy 28.032855 -14.608534)
			(xy 28.056527 -14.659031) (xy 28.072595 -14.712438) (xy 28.080715 -14.767614) (xy 28.081187 -14.793484)
			(xy 29.519874 -14.793484) (xy 29.519874 -14.706584) (xy 29.527892 -14.620055) (xy 29.54386 -14.534635)
			(xy 29.567641 -14.451053) (xy 29.599033 -14.370021) (xy 29.637767 -14.292232) (xy 29.683514 -14.218348)
			(xy 29.735883 -14.149001) (xy 29.794427 -14.084781) (xy 29.858647 -14.026237) (xy 29.927994 -13.973868)
			(xy 30.001878 -13.928121) (xy 30.079667 -13.889387) (xy 30.160699 -13.857995) (xy 30.244281 -13.834214)
			(xy 30.329701 -13.818246) (xy 30.41623 -13.810228) (xy 30.50313 -13.810228) (xy 30.589659 -13.818246)
			(xy 30.675079 -13.834214) (xy 30.758661 -13.857995) (xy 30.839693 -13.889387) (xy 30.917482 -13.928121)
			(xy 30.991366 -13.973868) (xy 31.060713 -14.026237) (xy 31.124933 -14.084781) (xy 31.183477 -14.149001)
			(xy 31.235846 -14.218348) (xy 31.281593 -14.292232) (xy 31.320327 -14.370021) (xy 31.351719 -14.451053)
			(xy 31.3755 -14.534635) (xy 31.391468 -14.620055) (xy 31.399486 -14.706584) (xy 31.399988 -14.750034)
			(xy 31.399486 -14.793484) (xy 34.599874 -14.793484) (xy 34.599874 -14.706584) (xy 34.607892 -14.620055)
			(xy 34.62386 -14.534635) (xy 34.647641 -14.451053) (xy 34.679033 -14.370021) (xy 34.717767 -14.292232)
			(xy 34.763514 -14.218348) (xy 34.815883 -14.149001) (xy 34.874427 -14.084781) (xy 34.938647 -14.026237)
			(xy 35.007994 -13.973868) (xy 35.081878 -13.928121) (xy 35.159667 -13.889387) (xy 35.240699 -13.857995)
			(xy 35.324281 -13.834214) (xy 35.409701 -13.818246) (xy 35.49623 -13.810228) (xy 35.58313 -13.810228)
			(xy 35.669659 -13.818246) (xy 35.755079 -13.834214) (xy 35.838661 -13.857995) (xy 35.919693 -13.889387)
			(xy 35.997482 -13.928121) (xy 36.071366 -13.973868) (xy 36.140713 -14.026237) (xy 36.204933 -14.084781)
			(xy 36.263477 -14.149001) (xy 36.315846 -14.218348) (xy 36.361593 -14.292232) (xy 36.400327 -14.370021)
			(xy 36.431719 -14.451053) (xy 36.4555 -14.534635) (xy 36.471468 -14.620055) (xy 36.479486 -14.706584)
			(xy 36.479615 -14.717748) (xy 64.785847 -14.717748) (xy 64.789739 -14.663393) (xy 64.801327 -14.610146)
			(xy 64.820375 -14.55909) (xy 64.846496 -14.511264) (xy 64.862456 -14.489176) (xy 64.876076 -14.47018)
			(xy 64.89681 -14.428293) (xy 64.909536 -14.383321) (xy 64.913823 -14.336781) (xy 64.909529 -14.290241)
			(xy 64.896796 -14.245271) (xy 64.876056 -14.203387) (xy 64.862456 -14.184376) (xy 64.846496 -14.162288)
			(xy 64.820375 -14.114462) (xy 64.801327 -14.063406) (xy 64.789739 -14.010159) (xy 64.785847 -13.955804)
			(xy 64.789731 -13.901449) (xy 64.801311 -13.8482) (xy 64.820352 -13.797141) (xy 64.846466 -13.749311)
			(xy 64.879121 -13.705685) (xy 64.917652 -13.667151) (xy 64.961276 -13.634493) (xy 65.009103 -13.608376)
			(xy 65.060161 -13.589331) (xy 65.113409 -13.577747) (xy 65.167764 -13.573859) (xy 65.222119 -13.577747)
			(xy 65.275367 -13.589331) (xy 65.326425 -13.608376) (xy 65.374252 -13.634493) (xy 65.417876 -13.667151)
			(xy 65.456407 -13.705685) (xy 65.489062 -13.749311) (xy 65.515176 -13.797141) (xy 65.534217 -13.8482)
			(xy 65.545797 -13.901449) (xy 65.549681 -13.955804) (xy 65.545789 -14.010159) (xy 65.534201 -14.063406)
			(xy 65.515153 -14.114462) (xy 65.489032 -14.162288) (xy 65.473072 -14.184376) (xy 65.4595 -14.203404)
			(xy 65.438768 -14.245284) (xy 65.426041 -14.290248) (xy 65.421748 -14.336781) (xy 65.426034 -14.383314)
			(xy 65.438754 -14.42828) (xy 65.45948 -14.470163) (xy 65.473072 -14.489176) (xy 65.489032 -14.511264)
			(xy 65.515153 -14.55909) (xy 65.534201 -14.610146) (xy 65.545789 -14.663393) (xy 65.549681 -14.717748)
			(xy 66.700499 -14.717748) (xy 66.704391 -14.663393) (xy 66.715979 -14.610146) (xy 66.735027 -14.55909)
			(xy 66.761148 -14.511264) (xy 66.777108 -14.489176) (xy 66.790725 -14.470179) (xy 66.811455 -14.428291)
			(xy 66.824178 -14.38332) (xy 66.828465 -14.336781) (xy 66.824171 -14.290242) (xy 66.811442 -14.245273)
			(xy 66.790705 -14.203388) (xy 66.777108 -14.184376) (xy 66.761148 -14.162288) (xy 66.735027 -14.114462)
			(xy 66.715979 -14.063406) (xy 66.704391 -14.010159) (xy 66.700499 -13.955804) (xy 66.704383 -13.901449)
			(xy 66.715963 -13.8482) (xy 66.735004 -13.797141) (xy 66.761118 -13.749311) (xy 66.793773 -13.705685)
			(xy 66.832304 -13.667151) (xy 66.875928 -13.634493) (xy 66.923755 -13.608376) (xy 66.974813 -13.589331)
			(xy 67.028061 -13.577747) (xy 67.082416 -13.573859) (xy 67.136771 -13.577747) (xy 67.190019 -13.589331)
			(xy 67.241077 -13.608376) (xy 67.288904 -13.634493) (xy 67.332528 -13.667151) (xy 67.371059 -13.705685)
			(xy 67.403714 -13.749311) (xy 67.429828 -13.797141) (xy 67.448869 -13.8482) (xy 67.460449 -13.901449)
			(xy 67.464333 -13.955804) (xy 67.460441 -14.010159) (xy 67.448853 -14.063406) (xy 67.429805 -14.114462)
			(xy 67.403684 -14.162288) (xy 67.387724 -14.184376) (xy 67.37415 -14.203403) (xy 67.353413 -14.245282)
			(xy 67.340683 -14.290247) (xy 67.33639 -14.336781) (xy 67.340676 -14.383316) (xy 67.353399 -14.428282)
			(xy 67.374129 -14.470164) (xy 67.387724 -14.489176) (xy 67.403684 -14.511264) (xy 67.429805 -14.55909)
			(xy 67.448853 -14.610146) (xy 67.460441 -14.663393) (xy 67.464333 -14.717748) (xy 68.597371 -14.717748)
			(xy 68.601263 -14.663393) (xy 68.612851 -14.610146) (xy 68.631899 -14.55909) (xy 68.65802 -14.511264)
			(xy 68.67398 -14.489176) (xy 68.687599 -14.47018) (xy 68.708331 -14.428292) (xy 68.721055 -14.383321)
			(xy 68.725342 -14.336781) (xy 68.721048 -14.290241) (xy 68.708317 -14.245272) (xy 68.687579 -14.203388)
			(xy 68.67398 -14.184376) (xy 68.65802 -14.162288) (xy 68.631899 -14.114462) (xy 68.612851 -14.063406)
			(xy 68.601263 -14.010159) (xy 68.597371 -13.955804) (xy 68.601255 -13.901449) (xy 68.612835 -13.8482)
			(xy 68.631876 -13.797141) (xy 68.65799 -13.749311) (xy 68.690645 -13.705685) (xy 68.729176 -13.667151)
			(xy 68.7728 -13.634493) (xy 68.820627 -13.608376) (xy 68.871685 -13.589331) (xy 68.924933 -13.577747)
			(xy 68.979288 -13.573859) (xy 69.033643 -13.577747) (xy 69.086891 -13.589331) (xy 69.137949 -13.608376)
			(xy 69.185776 -13.634493) (xy 69.2294 -13.667151) (xy 69.267931 -13.705685) (xy 69.300586 -13.749311)
			(xy 69.3267 -13.797141) (xy 69.345741 -13.8482) (xy 69.357321 -13.901449) (xy 69.361205 -13.955804)
			(xy 69.357313 -14.010159) (xy 69.345725 -14.063406) (xy 69.326677 -14.114462) (xy 69.300556 -14.162288)
			(xy 69.284596 -14.184376) (xy 69.271023 -14.203403) (xy 69.250289 -14.245283) (xy 69.237561 -14.290247)
			(xy 69.233267 -14.336781) (xy 69.237554 -14.383315) (xy 69.250275 -14.428281) (xy 69.271003 -14.470164)
			(xy 69.284596 -14.489176) (xy 69.300556 -14.511264) (xy 69.326677 -14.55909) (xy 69.345725 -14.610146)
			(xy 69.357313 -14.663393) (xy 69.361205 -14.717748) (xy 70.675599 -14.717748) (xy 70.679491 -14.663393)
			(xy 70.691079 -14.610146) (xy 70.710127 -14.55909) (xy 70.736248 -14.511264) (xy 70.752208 -14.489176)
			(xy 70.765825 -14.470179) (xy 70.786555 -14.428291) (xy 70.799278 -14.38332) (xy 70.803565 -14.336781)
			(xy 70.799271 -14.290242) (xy 70.786542 -14.245273) (xy 70.765805 -14.203388) (xy 70.752208 -14.184376)
			(xy 70.736248 -14.162288) (xy 70.710127 -14.114462) (xy 70.691079 -14.063406) (xy 70.679491 -14.010159)
			(xy 70.675599 -13.955804) (xy 70.679483 -13.901449) (xy 70.691063 -13.8482) (xy 70.710104 -13.797141)
			(xy 70.736218 -13.749311) (xy 70.768873 -13.705685) (xy 70.807404 -13.667151) (xy 70.851028 -13.634493)
			(xy 70.898855 -13.608376) (xy 70.949913 -13.589331) (xy 71.003161 -13.577747) (xy 71.057516 -13.573859)
			(xy 71.111871 -13.577747) (xy 71.165119 -13.589331) (xy 71.216177 -13.608376) (xy 71.264004 -13.634493)
			(xy 71.307628 -13.667151) (xy 71.346159 -13.705685) (xy 71.378814 -13.749311) (xy 71.404928 -13.797141)
			(xy 71.423969 -13.8482) (xy 71.435549 -13.901449) (xy 71.439433 -13.955804) (xy 71.435541 -14.010159)
			(xy 71.423953 -14.063406) (xy 71.404905 -14.114462) (xy 71.378784 -14.162288) (xy 71.362824 -14.184376)
			(xy 71.34925 -14.203403) (xy 71.328513 -14.245282) (xy 71.315783 -14.290247) (xy 71.31149 -14.336781)
			(xy 71.315776 -14.383316) (xy 71.328499 -14.428282) (xy 71.349229 -14.470164) (xy 71.362824 -14.489176)
			(xy 71.378784 -14.511264) (xy 71.404905 -14.55909) (xy 71.423953 -14.610146) (xy 71.435541 -14.663393)
			(xy 71.439433 -14.717748) (xy 72.795991 -14.717748) (xy 72.799883 -14.663393) (xy 72.811471 -14.610146)
			(xy 72.830519 -14.55909) (xy 72.85664 -14.511264) (xy 72.8726 -14.489176) (xy 72.886218 -14.470179)
			(xy 72.906948 -14.428292) (xy 72.919672 -14.38332) (xy 72.923958 -14.336781) (xy 72.919664 -14.290242)
			(xy 72.906935 -14.245272) (xy 72.886198 -14.203388) (xy 72.8726 -14.184376) (xy 72.85664 -14.162288)
			(xy 72.830519 -14.114462) (xy 72.811471 -14.063406) (xy 72.799883 -14.010159) (xy 72.795991 -13.955804)
			(xy 72.799875 -13.901449) (xy 72.811455 -13.8482) (xy 72.830496 -13.797141) (xy 72.85661 -13.749311)
			(xy 72.889265 -13.705685) (xy 72.927796 -13.667151) (xy 72.97142 -13.634493) (xy 73.019247 -13.608376)
			(xy 73.070305 -13.589331) (xy 73.123553 -13.577747) (xy 73.177908 -13.573859) (xy 73.232263 -13.577747)
			(xy 73.285511 -13.589331) (xy 73.336569 -13.608376) (xy 73.384396 -13.634493) (xy 73.42802 -13.667151)
			(xy 73.466551 -13.705685) (xy 73.499206 -13.749311) (xy 73.52532 -13.797141) (xy 73.544361 -13.8482)
			(xy 73.555941 -13.901449) (xy 73.559825 -13.955804) (xy 73.555933 -14.010159) (xy 73.544345 -14.063406)
			(xy 73.525297 -14.114462) (xy 73.499176 -14.162288) (xy 73.483216 -14.184376) (xy 73.469642 -14.203403)
			(xy 73.456803 -14.229334) (xy 84.425788 -14.229334) (xy 84.429859 -14.173712) (xy 84.441985 -14.119275)
			(xy 84.461908 -14.067184) (xy 84.489204 -14.018549) (xy 84.52329 -13.974406) (xy 84.563439 -13.935697)
			(xy 84.608797 -13.903246) (xy 84.658397 -13.877745) (xy 84.711181 -13.859738) (xy 84.766024 -13.849608)
			(xy 84.821758 -13.847571) (xy 84.877195 -13.853671) (xy 84.931152 -13.867777) (xy 84.982481 -13.889589)
			(xy 85.030087 -13.918643) (xy 85.072955 -13.954318) (xy 85.110172 -13.995855) (xy 85.140945 -14.042368)
			(xy 85.164617 -14.092865) (xy 85.180685 -14.146272) (xy 85.188805 -14.201448) (xy 85.189314 -14.229334)
			(xy 85.188805 -14.25722) (xy 85.186592 -14.27226) (xy 87.270588 -14.27226) (xy 87.274659 -14.216638)
			(xy 87.286785 -14.162201) (xy 87.306708 -14.11011) (xy 87.334004 -14.061475) (xy 87.36809 -14.017332)
			(xy 87.408239 -13.978623) (xy 87.453597 -13.946172) (xy 87.503197 -13.920671) (xy 87.555981 -13.902664)
			(xy 87.610824 -13.892534) (xy 87.666558 -13.890497) (xy 87.721995 -13.896597) (xy 87.775952 -13.910703)
			(xy 87.827281 -13.932515) (xy 87.874887 -13.961569) (xy 87.917755 -13.997244) (xy 87.954972 -14.038781)
			(xy 87.985745 -14.085294) (xy 88.009417 -14.135791) (xy 88.025485 -14.189198) (xy 88.033605 -14.244374)
			(xy 88.034114 -14.27226) (xy 88.033605 -14.300146) (xy 88.025485 -14.355322) (xy 88.009417 -14.408729)
			(xy 87.985745 -14.459226) (xy 87.954972 -14.505739) (xy 87.917755 -14.547276) (xy 87.874887 -14.582951)
			(xy 87.827281 -14.612005) (xy 87.775952 -14.633817) (xy 87.721995 -14.647923) (xy 87.666558 -14.654023)
			(xy 87.610824 -14.651986) (xy 87.555981 -14.641856) (xy 87.503197 -14.623849) (xy 87.453597 -14.598348)
			(xy 87.408239 -14.565897) (xy 87.36809 -14.527188) (xy 87.334004 -14.483045) (xy 87.306708 -14.43441)
			(xy 87.286785 -14.382319) (xy 87.274659 -14.327882) (xy 87.270588 -14.27226) (xy 85.186592 -14.27226)
			(xy 85.180685 -14.312396) (xy 85.164617 -14.365803) (xy 85.140945 -14.4163) (xy 85.110172 -14.462813)
			(xy 85.072955 -14.50435) (xy 85.030087 -14.540025) (xy 84.982481 -14.569079) (xy 84.931152 -14.590891)
			(xy 84.877195 -14.604997) (xy 84.821758 -14.611097) (xy 84.766024 -14.60906) (xy 84.711181 -14.59893)
			(xy 84.658397 -14.580923) (xy 84.608797 -14.555422) (xy 84.563439 -14.522971) (xy 84.52329 -14.484262)
			(xy 84.489204 -14.440119) (xy 84.461908 -14.391484) (xy 84.441985 -14.339393) (xy 84.429859 -14.284956)
			(xy 84.425788 -14.229334) (xy 73.456803 -14.229334) (xy 73.448906 -14.245282) (xy 73.436177 -14.290247)
			(xy 73.431883 -14.336781) (xy 73.43617 -14.383315) (xy 73.448892 -14.428282) (xy 73.469622 -14.470164)
			(xy 73.483216 -14.489176) (xy 73.499176 -14.511264) (xy 73.525297 -14.55909) (xy 73.544345 -14.610146)
			(xy 73.555933 -14.663393) (xy 73.559825 -14.717748) (xy 73.555941 -14.772103) (xy 73.544361 -14.825352)
			(xy 73.52532 -14.876411) (xy 73.499206 -14.924241) (xy 73.466551 -14.967867) (xy 73.42802 -15.006401)
			(xy 73.384396 -15.039059) (xy 73.336569 -15.065176) (xy 73.285511 -15.084221) (xy 73.232263 -15.095805)
			(xy 73.177908 -15.099693) (xy 73.123553 -15.095805) (xy 73.070305 -15.084221) (xy 73.019247 -15.065176)
			(xy 72.97142 -15.039059) (xy 72.927796 -15.006401) (xy 72.889265 -14.967867) (xy 72.85661 -14.924241)
			(xy 72.830496 -14.876411) (xy 72.811455 -14.825352) (xy 72.799875 -14.772103) (xy 72.795991 -14.717748)
			(xy 71.439433 -14.717748) (xy 71.435549 -14.772103) (xy 71.423969 -14.825352) (xy 71.404928 -14.876411)
			(xy 71.378814 -14.924241) (xy 71.346159 -14.967867) (xy 71.307628 -15.006401) (xy 71.264004 -15.039059)
			(xy 71.216177 -15.065176) (xy 71.165119 -15.084221) (xy 71.111871 -15.095805) (xy 71.057516 -15.099693)
			(xy 71.003161 -15.095805) (xy 70.949913 -15.084221) (xy 70.898855 -15.065176) (xy 70.851028 -15.039059)
			(xy 70.807404 -15.006401) (xy 70.768873 -14.967867) (xy 70.736218 -14.924241) (xy 70.710104 -14.876411)
			(xy 70.691063 -14.825352) (xy 70.679483 -14.772103) (xy 70.675599 -14.717748) (xy 69.361205 -14.717748)
			(xy 69.357321 -14.772103) (xy 69.345741 -14.825352) (xy 69.3267 -14.876411) (xy 69.300586 -14.924241)
			(xy 69.267931 -14.967867) (xy 69.2294 -15.006401) (xy 69.185776 -15.039059) (xy 69.137949 -15.065176)
			(xy 69.086891 -15.084221) (xy 69.033643 -15.095805) (xy 68.979288 -15.099693) (xy 68.924933 -15.095805)
			(xy 68.871685 -15.084221) (xy 68.820627 -15.065176) (xy 68.7728 -15.039059) (xy 68.729176 -15.006401)
			(xy 68.690645 -14.967867) (xy 68.65799 -14.924241) (xy 68.631876 -14.876411) (xy 68.612835 -14.825352)
			(xy 68.601255 -14.772103) (xy 68.597371 -14.717748) (xy 67.464333 -14.717748) (xy 67.460449 -14.772103)
			(xy 67.448869 -14.825352) (xy 67.429828 -14.876411) (xy 67.403714 -14.924241) (xy 67.371059 -14.967867)
			(xy 67.332528 -15.006401) (xy 67.288904 -15.039059) (xy 67.241077 -15.065176) (xy 67.190019 -15.084221)
			(xy 67.136771 -15.095805) (xy 67.082416 -15.099693) (xy 67.028061 -15.095805) (xy 66.974813 -15.084221)
			(xy 66.923755 -15.065176) (xy 66.875928 -15.039059) (xy 66.832304 -15.006401) (xy 66.793773 -14.967867)
			(xy 66.761118 -14.924241) (xy 66.735004 -14.876411) (xy 66.715963 -14.825352) (xy 66.704383 -14.772103)
			(xy 66.700499 -14.717748) (xy 65.549681 -14.717748) (xy 65.545797 -14.772103) (xy 65.534217 -14.825352)
			(xy 65.515176 -14.876411) (xy 65.489062 -14.924241) (xy 65.456407 -14.967867) (xy 65.417876 -15.006401)
			(xy 65.374252 -15.039059) (xy 65.326425 -15.065176) (xy 65.275367 -15.084221) (xy 65.222119 -15.095805)
			(xy 65.167764 -15.099693) (xy 65.113409 -15.095805) (xy 65.060161 -15.084221) (xy 65.009103 -15.065176)
			(xy 64.961276 -15.039059) (xy 64.917652 -15.006401) (xy 64.879121 -14.967867) (xy 64.846466 -14.924241)
			(xy 64.820352 -14.876411) (xy 64.801311 -14.825352) (xy 64.789731 -14.772103) (xy 64.785847 -14.717748)
			(xy 36.479615 -14.717748) (xy 36.479988 -14.750034) (xy 36.479486 -14.793484) (xy 36.471468 -14.880013)
			(xy 36.4555 -14.965433) (xy 36.431719 -15.049015) (xy 36.400327 -15.130047) (xy 36.361593 -15.207836)
			(xy 36.315846 -15.28172) (xy 36.263477 -15.351067) (xy 36.204933 -15.415287) (xy 36.140713 -15.473831)
			(xy 36.071366 -15.5262) (xy 35.997482 -15.571947) (xy 35.919693 -15.610681) (xy 35.854373 -15.635986)
			(xy 85.52764 -15.635986) (xy 85.531711 -15.580364) (xy 85.543837 -15.525927) (xy 85.56376 -15.473836)
			(xy 85.591056 -15.425201) (xy 85.625142 -15.381058) (xy 85.665291 -15.342349) (xy 85.710649 -15.309898)
			(xy 85.760249 -15.284397) (xy 85.813033 -15.26639) (xy 85.867876 -15.25626) (xy 85.92361 -15.254223)
			(xy 85.979047 -15.260323) (xy 86.033004 -15.274429) (xy 86.084333 -15.296241) (xy 86.131939 -15.325295)
			(xy 86.174807 -15.36097) (xy 86.212024 -15.402507) (xy 86.242797 -15.44902) (xy 86.266469 -15.499517)
			(xy 86.282537 -15.552924) (xy 86.290657 -15.6081) (xy 86.291166 -15.635986) (xy 86.290657 -15.663872)
			(xy 86.282537 -15.719048) (xy 86.266469 -15.772455) (xy 86.242797 -15.822952) (xy 86.212024 -15.869465)
			(xy 86.174807 -15.911002) (xy 86.131939 -15.946677) (xy 86.084333 -15.975731) (xy 86.033004 -15.997543)
			(xy 85.979047 -16.011649) (xy 85.92361 -16.017749) (xy 85.867876 -16.015712) (xy 85.813033 -16.005582)
			(xy 85.760249 -15.987575) (xy 85.710649 -15.962074) (xy 85.665291 -15.929623) (xy 85.625142 -15.890914)
			(xy 85.591056 -15.846771) (xy 85.56376 -15.798136) (xy 85.543837 -15.746045) (xy 85.531711 -15.691608)
			(xy 85.52764 -15.635986) (xy 35.854373 -15.635986) (xy 35.838661 -15.642073) (xy 35.755079 -15.665854)
			(xy 35.669659 -15.681822) (xy 35.58313 -15.68984) (xy 35.49623 -15.68984) (xy 35.409701 -15.681822)
			(xy 35.324281 -15.665854) (xy 35.240699 -15.642073) (xy 35.159667 -15.610681) (xy 35.081878 -15.571947)
			(xy 35.007994 -15.5262) (xy 34.938647 -15.473831) (xy 34.874427 -15.415287) (xy 34.815883 -15.351067)
			(xy 34.763514 -15.28172) (xy 34.717767 -15.207836) (xy 34.679033 -15.130047) (xy 34.647641 -15.049015)
			(xy 34.62386 -14.965433) (xy 34.607892 -14.880013) (xy 34.599874 -14.793484) (xy 31.399486 -14.793484)
			(xy 31.391468 -14.880013) (xy 31.3755 -14.965433) (xy 31.351719 -15.049015) (xy 31.320327 -15.130047)
			(xy 31.281593 -15.207836) (xy 31.235846 -15.28172) (xy 31.183477 -15.351067) (xy 31.124933 -15.415287)
			(xy 31.060713 -15.473831) (xy 30.991366 -15.5262) (xy 30.917482 -15.571947) (xy 30.839693 -15.610681)
			(xy 30.758661 -15.642073) (xy 30.675079 -15.665854) (xy 30.589659 -15.681822) (xy 30.50313 -15.68984)
			(xy 30.41623 -15.68984) (xy 30.329701 -15.681822) (xy 30.244281 -15.665854) (xy 30.160699 -15.642073)
			(xy 30.079667 -15.610681) (xy 30.001878 -15.571947) (xy 29.927994 -15.5262) (xy 29.858647 -15.473831)
			(xy 29.794427 -15.415287) (xy 29.735883 -15.351067) (xy 29.683514 -15.28172) (xy 29.637767 -15.207836)
			(xy 29.599033 -15.130047) (xy 29.567641 -15.049015) (xy 29.54386 -14.965433) (xy 29.527892 -14.880013)
			(xy 29.519874 -14.793484) (xy 28.081187 -14.793484) (xy 28.081224 -14.7955) (xy 28.080715 -14.823386)
			(xy 28.072595 -14.878562) (xy 28.056527 -14.931969) (xy 28.032855 -14.982466) (xy 28.002082 -15.028979)
			(xy 27.964865 -15.070516) (xy 27.921997 -15.106191) (xy 27.874391 -15.135245) (xy 27.823062 -15.157057)
			(xy 27.769105 -15.171163) (xy 27.713668 -15.177263) (xy 27.657934 -15.175226) (xy 27.603091 -15.165096)
			(xy 27.550307 -15.147089) (xy 27.500707 -15.121588) (xy 27.455349 -15.089137) (xy 27.4152 -15.050428)
			(xy 27.381114 -15.006285) (xy 27.353818 -14.95765) (xy 27.333895 -14.905559) (xy 27.321769 -14.851122)
			(xy 27.317698 -14.7955) (xy 14.560615 -14.7955) (xy 14.577067 -14.811952) (xy 14.628522 -14.874651)
			(xy 14.673584 -14.942091) (xy 14.711819 -15.013623) (xy 14.742858 -15.088559) (xy 14.766403 -15.166175)
			(xy 14.782226 -15.245726) (xy 14.790176 -15.326445) (xy 14.790674 -15.367) (xy 14.790176 -15.407555)
			(xy 14.782226 -15.488274) (xy 14.766403 -15.567825) (xy 14.742858 -15.645441) (xy 14.711819 -15.720377)
			(xy 14.673584 -15.791909) (xy 14.628522 -15.859349) (xy 14.577067 -15.922048) (xy 14.519714 -15.979401)
			(xy 14.457015 -16.030856) (xy 14.389575 -16.075918) (xy 14.318043 -16.114153) (xy 14.243107 -16.145192)
			(xy 14.165491 -16.168737) (xy 14.08594 -16.18456) (xy 14.005221 -16.19251) (xy 13.924111 -16.19251)
			(xy 13.843392 -16.18456) (xy 13.763841 -16.168737) (xy 13.686225 -16.145192) (xy 13.611289 -16.114153)
			(xy 13.539757 -16.075918) (xy 13.472317 -16.030856) (xy 13.409618 -15.979401) (xy 13.352265 -15.922048)
			(xy 13.30081 -15.859349) (xy 13.255748 -15.791909) (xy 13.217513 -15.720377) (xy 13.186474 -15.645441)
			(xy 13.162929 -15.567825) (xy 13.147106 -15.488274) (xy 13.139156 -15.407555) (xy 1.525016 -15.407555)
			(xy 1.525016 -16.677555) (xy 15.679156 -16.677555) (xy 15.679156 -16.596445) (xy 15.687106 -16.515726)
			(xy 15.702929 -16.436175) (xy 15.726474 -16.358559) (xy 15.757513 -16.283623) (xy 15.795748 -16.212091)
			(xy 15.84081 -16.144651) (xy 15.892265 -16.081952) (xy 15.949618 -16.024599) (xy 16.012317 -15.973144)
			(xy 16.079757 -15.928082) (xy 16.151289 -15.889847) (xy 16.226225 -15.858808) (xy 16.303841 -15.835263)
			(xy 16.383392 -15.81944) (xy 16.464111 -15.81149) (xy 16.545221 -15.81149) (xy 16.62594 -15.81944)
			(xy 16.640932 -15.822422) (xy 26.122882 -15.822422) (xy 26.126953 -15.7668) (xy 26.139079 -15.712363)
			(xy 26.159002 -15.660272) (xy 26.186298 -15.611637) (xy 26.220384 -15.567494) (xy 26.260533 -15.528785)
			(xy 26.305891 -15.496334) (xy 26.355491 -15.470833) (xy 26.408275 -15.452826) (xy 26.463118 -15.442696)
			(xy 26.518852 -15.440659) (xy 26.574289 -15.446759) (xy 26.628246 -15.460865) (xy 26.679575 -15.482677)
			(xy 26.727181 -15.511731) (xy 26.770049 -15.547406) (xy 26.807266 -15.588943) (xy 26.838039 -15.635456)
			(xy 26.861711 -15.685953) (xy 26.877779 -15.73936) (xy 26.885899 -15.794536) (xy 26.886408 -15.822422)
			(xy 26.885899 -15.850308) (xy 26.877779 -15.905484) (xy 26.861711 -15.958891) (xy 26.838039 -16.009388)
			(xy 26.807266 -16.055901) (xy 26.770049 -16.097438) (xy 26.727181 -16.133113) (xy 26.679575 -16.162167)
			(xy 26.628246 -16.183979) (xy 26.574289 -16.198085) (xy 26.518852 -16.204185) (xy 26.463118 -16.202148)
			(xy 26.408275 -16.192018) (xy 26.355491 -16.174011) (xy 26.305891 -16.14851) (xy 26.260533 -16.116059)
			(xy 26.220384 -16.07735) (xy 26.186298 -16.033207) (xy 26.159002 -15.984572) (xy 26.139079 -15.932481)
			(xy 26.126953 -15.878044) (xy 26.122882 -15.822422) (xy 16.640932 -15.822422) (xy 16.705491 -15.835263)
			(xy 16.783107 -15.858808) (xy 16.858043 -15.889847) (xy 16.929575 -15.928082) (xy 16.997015 -15.973144)
			(xy 17.059714 -16.024599) (xy 17.117067 -16.081952) (xy 17.168522 -16.144651) (xy 17.213584 -16.212091)
			(xy 17.251819 -16.283623) (xy 17.282858 -16.358559) (xy 17.306403 -16.436175) (xy 17.322226 -16.515726)
			(xy 17.330176 -16.596445) (xy 17.330674 -16.637) (xy 17.330176 -16.677555) (xy 17.322226 -16.758274)
			(xy 17.306403 -16.837825) (xy 17.282858 -16.915441) (xy 17.251819 -16.990377) (xy 17.213584 -17.061909)
			(xy 17.168522 -17.129349) (xy 17.117067 -17.192048) (xy 17.059714 -17.249401) (xy 16.997015 -17.300856)
			(xy 16.929575 -17.345918) (xy 16.858043 -17.384153) (xy 16.783107 -17.415192) (xy 16.705491 -17.438737)
			(xy 16.62594 -17.45456) (xy 16.545221 -17.46251) (xy 16.464111 -17.46251) (xy 16.383392 -17.45456)
			(xy 16.303841 -17.438737) (xy 16.226225 -17.415192) (xy 16.151289 -17.384153) (xy 16.079757 -17.345918)
			(xy 16.012317 -17.300856) (xy 15.949618 -17.249401) (xy 15.892265 -17.192048) (xy 15.84081 -17.129349)
			(xy 15.795748 -17.061909) (xy 15.757513 -16.990377) (xy 15.726474 -16.915441) (xy 15.702929 -16.837825)
			(xy 15.687106 -16.758274) (xy 15.679156 -16.677555) (xy 1.525016 -16.677555) (xy 1.525016 -19.177)
			(xy 5.5306 -19.177) (xy 5.534631 -19.047434) (xy 5.54671 -18.91837) (xy 5.566789 -18.790306) (xy 5.594791 -18.663739)
			(xy 5.630608 -18.539156) (xy 5.6741 -18.417042) (xy 5.7251 -18.297868) (xy 5.783411 -18.182095) (xy 5.848806 -18.070171)
			(xy 5.921033 -17.962529) (xy 5.999813 -17.859586) (xy 6.08484 -17.76174) (xy 6.175785 -17.669368)
			(xy 6.272297 -17.58283) (xy 6.374003 -17.502459) (xy 6.480509 -17.428567) (xy 6.591402 -17.361439)
			(xy 6.706254 -17.301335) (xy 6.824621 -17.248488) (xy 6.946044 -17.203101) (xy 7.070054 -17.165352)
			(xy 7.196171 -17.135385) (xy 7.323907 -17.113316) (xy 7.452768 -17.099232) (xy 7.582255 -17.093186)
			(xy 7.711868 -17.095202) (xy 7.841104 -17.105272) (xy 7.969465 -17.123357) (xy 8.096453 -17.149387)
			(xy 8.221577 -17.183262) (xy 8.344353 -17.22485) (xy 8.464306 -17.273991) (xy 8.580971 -17.330494)
			(xy 8.693899 -17.394141) (xy 8.802651 -17.464685) (xy 8.906807 -17.541854) (xy 9.005964 -17.625349)
			(xy 9.099738 -17.714847) (xy 9.187767 -17.810002) (xy 9.26971 -17.910445) (xy 9.296321 -17.947555)
			(xy 13.139156 -17.947555) (xy 13.139156 -17.866445) (xy 13.147106 -17.785726) (xy 13.162929 -17.706175)
			(xy 13.186474 -17.628559) (xy 13.217513 -17.553623) (xy 13.255748 -17.482091) (xy 13.30081 -17.414651)
			(xy 13.352265 -17.351952) (xy 13.409618 -17.294599) (xy 13.472317 -17.243144) (xy 13.539757 -17.198082)
			(xy 13.611289 -17.159847) (xy 13.686225 -17.128808) (xy 13.763841 -17.105263) (xy 13.843392 -17.08944)
			(xy 13.924111 -17.08149) (xy 14.005221 -17.08149) (xy 14.08594 -17.08944) (xy 14.165491 -17.105263)
			(xy 14.243107 -17.128808) (xy 14.318043 -17.159847) (xy 14.389575 -17.198082) (xy 14.457015 -17.243144)
			(xy 14.519714 -17.294599) (xy 14.577067 -17.351952) (xy 14.628522 -17.414651) (xy 14.673584 -17.482091)
			(xy 14.711819 -17.553623) (xy 14.742858 -17.628559) (xy 14.766403 -17.706175) (xy 14.782226 -17.785726)
			(xy 14.790176 -17.866445) (xy 14.790674 -17.907) (xy 14.790176 -17.947555) (xy 14.782226 -18.028274)
			(xy 14.766403 -18.107825) (xy 14.742858 -18.185441) (xy 14.711819 -18.260377) (xy 14.673584 -18.331909)
			(xy 14.640359 -18.381634) (xy 26.762163 -18.381634) (xy 26.762163 -18.318366) (xy 26.770421 -18.25564)
			(xy 26.786796 -18.194528) (xy 26.811008 -18.136077) (xy 26.842641 -18.081285) (xy 26.881156 -18.031092)
			(xy 26.925893 -17.986355) (xy 26.976087 -17.94784) (xy 27.030878 -17.916207) (xy 27.08933 -17.891995)
			(xy 27.150442 -17.875621) (xy 27.213168 -17.867363) (xy 27.244802 -17.866868) (xy 28.989782 -17.866868)
			(xy 29.244544 -18.121884) (xy 29.41447 -18.121884) (xy 29.436456 -18.121402) (xy 29.479771 -18.113837)
			(xy 29.521137 -18.098928) (xy 29.559319 -18.07712) (xy 29.593176 -18.049064) (xy 29.621698 -18.015597)
			(xy 29.644032 -17.977721) (xy 29.659512 -17.936564) (xy 29.667675 -17.893358) (xy 29.668277 -17.849391)
			(xy 29.661301 -17.805976) (xy 29.646956 -17.764411) (xy 29.63672 -17.744948) (xy 29.616168 -17.706738)
			(xy 29.581366 -17.627257) (xy 29.554035 -17.544908) (xy 29.534406 -17.460391) (xy 29.522646 -17.374425)
			(xy 29.518856 -17.287741) (xy 29.523069 -17.201077) (xy 29.535247 -17.115169) (xy 29.555288 -17.030749)
			(xy 29.58302 -16.948534) (xy 29.618209 -16.869223) (xy 29.660555 -16.793492) (xy 29.709698 -16.721984)
			(xy 29.765219 -16.655307) (xy 29.826647 -16.594028) (xy 29.893459 -16.53867) (xy 29.965087 -16.489702)
			(xy 30.040921 -16.44754) (xy 30.120317 -16.412545) (xy 30.2026 -16.385012) (xy 30.287069 -16.365177)
			(xy 30.373006 -16.353209) (xy 30.45968 -16.349208) (xy 30.546354 -16.353209) (xy 30.632291 -16.365177)
			(xy 30.71676 -16.385012) (xy 30.799043 -16.412545) (xy 30.878439 -16.44754) (xy 30.954273 -16.489702)
			(xy 31.025901 -16.53867) (xy 31.092713 -16.594028) (xy 31.154141 -16.655307) (xy 31.209662 -16.721984)
			(xy 31.258805 -16.793492) (xy 31.301151 -16.869223) (xy 31.33634 -16.948534) (xy 31.364072 -17.030749)
			(xy 31.384113 -17.115169) (xy 31.396291 -17.201077) (xy 31.400504 -17.287741) (xy 31.398504 -17.333484)
			(xy 34.599874 -17.333484) (xy 34.599874 -17.246584) (xy 34.607892 -17.160055) (xy 34.62386 -17.074635)
			(xy 34.647641 -16.991053) (xy 34.679033 -16.910021) (xy 34.717767 -16.832232) (xy 34.763514 -16.758348)
			(xy 34.815883 -16.689001) (xy 34.874427 -16.624781) (xy 34.938647 -16.566237) (xy 35.007994 -16.513868)
			(xy 35.081878 -16.468121) (xy 35.159667 -16.429387) (xy 35.240699 -16.397995) (xy 35.324281 -16.374214)
			(xy 35.409701 -16.358246) (xy 35.49623 -16.350228) (xy 35.58313 -16.350228) (xy 35.669659 -16.358246)
			(xy 35.755079 -16.374214) (xy 35.838661 -16.397995) (xy 35.919693 -16.429387) (xy 35.997482 -16.468121)
			(xy 36.071366 -16.513868) (xy 36.140713 -16.566237) (xy 36.204933 -16.624781) (xy 36.263477 -16.689001)
			(xy 36.315846 -16.758348) (xy 36.361593 -16.832232) (xy 36.400327 -16.910021) (xy 36.431719 -16.991053)
			(xy 36.4555 -17.074635) (xy 36.471468 -17.160055) (xy 36.479486 -17.246584) (xy 36.479988 -17.290034)
			(xy 36.479486 -17.333484) (xy 36.474618 -17.386018) (xy 64.785847 -17.386018) (xy 64.789739 -17.331663)
			(xy 64.801327 -17.278416) (xy 64.820375 -17.22736) (xy 64.846496 -17.179534) (xy 64.862456 -17.157446)
			(xy 64.876011 -17.138406) (xy 64.896751 -17.09653) (xy 64.909484 -17.051569) (xy 64.913781 -17.005037)
			(xy 64.909497 -16.958504) (xy 64.896777 -16.913538) (xy 64.876049 -16.871657) (xy 64.862456 -16.852646)
			(xy 64.846496 -16.830558) (xy 64.820375 -16.782732) (xy 64.801327 -16.731676) (xy 64.789739 -16.678429)
			(xy 64.785847 -16.624074) (xy 64.789731 -16.569719) (xy 64.801311 -16.51647) (xy 64.820352 -16.465411)
			(xy 64.846466 -16.417581) (xy 64.879121 -16.373955) (xy 64.917652 -16.335421) (xy 64.961276 -16.302763)
			(xy 65.009103 -16.276646) (xy 65.060161 -16.257601) (xy 65.113409 -16.246017) (xy 65.167764 -16.242129)
			(xy 65.222119 -16.246017) (xy 65.275367 -16.257601) (xy 65.326425 -16.276646) (xy 65.374252 -16.302763)
			(xy 65.417876 -16.335421) (xy 65.456407 -16.373955) (xy 65.489062 -16.417581) (xy 65.515176 -16.465411)
			(xy 65.534217 -16.51647) (xy 65.545797 -16.569719) (xy 65.549681 -16.624074) (xy 65.545789 -16.678429)
			(xy 65.534201 -16.731676) (xy 65.515153 -16.782732) (xy 65.489032 -16.830558) (xy 65.473072 -16.852646)
			(xy 65.459435 -16.87163) (xy 65.438709 -16.913521) (xy 65.425989 -16.958495) (xy 65.421706 -17.005037)
			(xy 65.426003 -17.051577) (xy 65.438735 -17.096548) (xy 65.459474 -17.138433) (xy 65.473072 -17.157446)
			(xy 65.489032 -17.179534) (xy 65.515153 -17.22736) (xy 65.534201 -17.278416) (xy 65.545789 -17.331663)
			(xy 65.549681 -17.386018) (xy 66.700499 -17.386018) (xy 66.704391 -17.331663) (xy 66.715979 -17.278416)
			(xy 66.735027 -17.22736) (xy 66.761148 -17.179534) (xy 66.777108 -17.157446) (xy 66.79066 -17.138405)
			(xy 66.811396 -17.096529) (xy 66.824127 -17.051568) (xy 66.828423 -17.005037) (xy 66.82414 -16.958505)
			(xy 66.811423 -16.91354) (xy 66.790699 -16.871658) (xy 66.777108 -16.852646) (xy 66.761148 -16.830558)
			(xy 66.735027 -16.782732) (xy 66.715979 -16.731676) (xy 66.704391 -16.678429) (xy 66.700499 -16.624074)
			(xy 66.704383 -16.569719) (xy 66.715963 -16.51647) (xy 66.735004 -16.465411) (xy 66.761118 -16.417581)
			(xy 66.793773 -16.373955) (xy 66.832304 -16.335421) (xy 66.875928 -16.302763) (xy 66.923755 -16.276646)
			(xy 66.974813 -16.257601) (xy 67.028061 -16.246017) (xy 67.082416 -16.242129) (xy 67.136771 -16.246017)
			(xy 67.190019 -16.257601) (xy 67.241077 -16.276646) (xy 67.288904 -16.302763) (xy 67.332528 -16.335421)
			(xy 67.371059 -16.373955) (xy 67.403714 -16.417581) (xy 67.429828 -16.465411) (xy 67.448869 -16.51647)
			(xy 67.460449 -16.569719) (xy 67.464333 -16.624074) (xy 67.460441 -16.678429) (xy 67.448853 -16.731676)
			(xy 67.429805 -16.782732) (xy 67.403684 -16.830558) (xy 67.387724 -16.852646) (xy 67.374084 -16.871629)
			(xy 67.353354 -16.913519) (xy 67.340632 -16.958494) (xy 67.336348 -17.005037) (xy 67.340645 -17.051578)
			(xy 67.35338 -17.09655) (xy 67.374123 -17.138434) (xy 67.387724 -17.157446) (xy 67.403684 -17.179534)
			(xy 67.429805 -17.22736) (xy 67.448853 -17.278416) (xy 67.460441 -17.331663) (xy 67.464333 -17.386018)
			(xy 68.597371 -17.386018) (xy 68.601263 -17.331663) (xy 68.612851 -17.278416) (xy 68.631899 -17.22736)
			(xy 68.65802 -17.179534) (xy 68.67398 -17.157446) (xy 68.687534 -17.138405) (xy 68.708272 -17.09653)
			(xy 68.721004 -17.051568) (xy 68.7253 -17.005037) (xy 68.721017 -16.958504) (xy 68.708298 -16.913539)
			(xy 68.687572 -16.871658) (xy 68.67398 -16.852646) (xy 68.65802 -16.830558) (xy 68.631899 -16.782732)
			(xy 68.612851 -16.731676) (xy 68.601263 -16.678429) (xy 68.597371 -16.624074) (xy 68.601255 -16.569719)
			(xy 68.612835 -16.51647) (xy 68.631876 -16.465411) (xy 68.65799 -16.417581) (xy 68.690645 -16.373955)
			(xy 68.729176 -16.335421) (xy 68.7728 -16.302763) (xy 68.820627 -16.276646) (xy 68.871685 -16.257601)
			(xy 68.924933 -16.246017) (xy 68.979288 -16.242129) (xy 69.033643 -16.246017) (xy 69.086891 -16.257601)
			(xy 69.137949 -16.276646) (xy 69.185776 -16.302763) (xy 69.2294 -16.335421) (xy 69.267931 -16.373955)
			(xy 69.300586 -16.417581) (xy 69.3267 -16.465411) (xy 69.345741 -16.51647) (xy 69.357321 -16.569719)
			(xy 69.361205 -16.624074) (xy 69.357313 -16.678429) (xy 69.345725 -16.731676) (xy 69.326677 -16.782732)
			(xy 69.300556 -16.830558) (xy 69.284596 -16.852646) (xy 69.270958 -16.871629) (xy 69.250229 -16.91352)
			(xy 69.237509 -16.958495) (xy 69.233225 -17.005037) (xy 69.237522 -17.051578) (xy 69.250256 -17.096549)
			(xy 69.270996 -17.138434) (xy 69.284596 -17.157446) (xy 69.300556 -17.179534) (xy 69.326677 -17.22736)
			(xy 69.345725 -17.278416) (xy 69.357313 -17.331663) (xy 69.361205 -17.386018) (xy 70.675599 -17.386018)
			(xy 70.679491 -17.331663) (xy 70.691079 -17.278416) (xy 70.710127 -17.22736) (xy 70.736248 -17.179534)
			(xy 70.752208 -17.157446) (xy 70.76576 -17.138405) (xy 70.786496 -17.096529) (xy 70.799227 -17.051568)
			(xy 70.803523 -17.005037) (xy 70.79924 -16.958505) (xy 70.786523 -16.91354) (xy 70.765799 -16.871658)
			(xy 70.752208 -16.852646) (xy 70.736248 -16.830558) (xy 70.710127 -16.782732) (xy 70.691079 -16.731676)
			(xy 70.679491 -16.678429) (xy 70.675599 -16.624074) (xy 70.679483 -16.569719) (xy 70.691063 -16.51647)
			(xy 70.710104 -16.465411) (xy 70.736218 -16.417581) (xy 70.768873 -16.373955) (xy 70.807404 -16.335421)
			(xy 70.851028 -16.302763) (xy 70.898855 -16.276646) (xy 70.949913 -16.257601) (xy 71.003161 -16.246017)
			(xy 71.057516 -16.242129) (xy 71.111871 -16.246017) (xy 71.165119 -16.257601) (xy 71.216177 -16.276646)
			(xy 71.264004 -16.302763) (xy 71.307628 -16.335421) (xy 71.346159 -16.373955) (xy 71.378814 -16.417581)
			(xy 71.404928 -16.465411) (xy 71.423969 -16.51647) (xy 71.435549 -16.569719) (xy 71.439433 -16.624074)
			(xy 71.435541 -16.678429) (xy 71.423953 -16.731676) (xy 71.404905 -16.782732) (xy 71.378784 -16.830558)
			(xy 71.362824 -16.852646) (xy 71.349184 -16.871629) (xy 71.328454 -16.913519) (xy 71.315732 -16.958494)
			(xy 71.311448 -17.005037) (xy 71.315745 -17.051578) (xy 71.32848 -17.09655) (xy 71.349223 -17.138434)
			(xy 71.362824 -17.157446) (xy 71.378784 -17.179534) (xy 71.404905 -17.22736) (xy 71.423953 -17.278416)
			(xy 71.435541 -17.331663) (xy 71.439433 -17.386018) (xy 72.795991 -17.386018) (xy 72.799883 -17.331663)
			(xy 72.811471 -17.278416) (xy 72.830519 -17.22736) (xy 72.85664 -17.179534) (xy 72.8726 -17.157446)
			(xy 72.886153 -17.138405) (xy 72.906889 -17.096529) (xy 72.91962 -17.051568) (xy 72.923916 -17.005037)
			(xy 72.919633 -16.958505) (xy 72.906916 -16.91354) (xy 72.886191 -16.871658) (xy 72.8726 -16.852646)
			(xy 72.85664 -16.830558) (xy 72.830519 -16.782732) (xy 72.811471 -16.731676) (xy 72.799883 -16.678429)
			(xy 72.795991 -16.624074) (xy 72.799875 -16.569719) (xy 72.811455 -16.51647) (xy 72.830496 -16.465411)
			(xy 72.85661 -16.417581) (xy 72.889265 -16.373955) (xy 72.927796 -16.335421) (xy 72.97142 -16.302763)
			(xy 73.019247 -16.276646) (xy 73.070305 -16.257601) (xy 73.123553 -16.246017) (xy 73.177908 -16.242129)
			(xy 73.232263 -16.246017) (xy 73.285511 -16.257601) (xy 73.336569 -16.276646) (xy 73.384396 -16.302763)
			(xy 73.42802 -16.335421) (xy 73.466551 -16.373955) (xy 73.499206 -16.417581) (xy 73.52532 -16.465411)
			(xy 73.544361 -16.51647) (xy 73.555941 -16.569719) (xy 73.559825 -16.624074) (xy 73.555933 -16.678429)
			(xy 73.544345 -16.731676) (xy 73.525297 -16.782732) (xy 73.499176 -16.830558) (xy 73.483216 -16.852646)
			(xy 73.469577 -16.871629) (xy 73.448847 -16.913519) (xy 73.436125 -16.958494) (xy 73.431841 -17.005037)
			(xy 73.436139 -17.051578) (xy 73.448873 -17.096549) (xy 73.469616 -17.138434) (xy 73.483216 -17.157446)
			(xy 73.499176 -17.179534) (xy 73.525297 -17.22736) (xy 73.544345 -17.278416) (xy 73.555933 -17.331663)
			(xy 73.559825 -17.386018) (xy 73.555941 -17.440373) (xy 73.544361 -17.493622) (xy 73.52532 -17.544681)
			(xy 73.499206 -17.592511) (xy 73.466551 -17.636137) (xy 73.42802 -17.674671) (xy 73.384396 -17.707329)
			(xy 73.336569 -17.733446) (xy 73.285511 -17.752491) (xy 73.232263 -17.764075) (xy 73.177908 -17.767963)
			(xy 73.123553 -17.764075) (xy 73.070305 -17.752491) (xy 73.019247 -17.733446) (xy 72.97142 -17.707329)
			(xy 72.927796 -17.674671) (xy 72.889265 -17.636137) (xy 72.85661 -17.592511) (xy 72.830496 -17.544681)
			(xy 72.811455 -17.493622) (xy 72.799875 -17.440373) (xy 72.795991 -17.386018) (xy 71.439433 -17.386018)
			(xy 71.435549 -17.440373) (xy 71.423969 -17.493622) (xy 71.404928 -17.544681) (xy 71.378814 -17.592511)
			(xy 71.346159 -17.636137) (xy 71.307628 -17.674671) (xy 71.264004 -17.707329) (xy 71.216177 -17.733446)
			(xy 71.165119 -17.752491) (xy 71.111871 -17.764075) (xy 71.057516 -17.767963) (xy 71.003161 -17.764075)
			(xy 70.949913 -17.752491) (xy 70.898855 -17.733446) (xy 70.851028 -17.707329) (xy 70.807404 -17.674671)
			(xy 70.768873 -17.636137) (xy 70.736218 -17.592511) (xy 70.710104 -17.544681) (xy 70.691063 -17.493622)
			(xy 70.679483 -17.440373) (xy 70.675599 -17.386018) (xy 69.361205 -17.386018) (xy 69.357321 -17.440373)
			(xy 69.345741 -17.493622) (xy 69.3267 -17.544681) (xy 69.300586 -17.592511) (xy 69.267931 -17.636137)
			(xy 69.2294 -17.674671) (xy 69.185776 -17.707329) (xy 69.137949 -17.733446) (xy 69.086891 -17.752491)
			(xy 69.033643 -17.764075) (xy 68.979288 -17.767963) (xy 68.924933 -17.764075) (xy 68.871685 -17.752491)
			(xy 68.820627 -17.733446) (xy 68.7728 -17.707329) (xy 68.729176 -17.674671) (xy 68.690645 -17.636137)
			(xy 68.65799 -17.592511) (xy 68.631876 -17.544681) (xy 68.612835 -17.493622) (xy 68.601255 -17.440373)
			(xy 68.597371 -17.386018) (xy 67.464333 -17.386018) (xy 67.460449 -17.440373) (xy 67.448869 -17.493622)
			(xy 67.429828 -17.544681) (xy 67.403714 -17.592511) (xy 67.371059 -17.636137) (xy 67.332528 -17.674671)
			(xy 67.288904 -17.707329) (xy 67.241077 -17.733446) (xy 67.190019 -17.752491) (xy 67.136771 -17.764075)
			(xy 67.082416 -17.767963) (xy 67.028061 -17.764075) (xy 66.974813 -17.752491) (xy 66.923755 -17.733446)
			(xy 66.875928 -17.707329) (xy 66.832304 -17.674671) (xy 66.793773 -17.636137) (xy 66.761118 -17.592511)
			(xy 66.735004 -17.544681) (xy 66.715963 -17.493622) (xy 66.704383 -17.440373) (xy 66.700499 -17.386018)
			(xy 65.549681 -17.386018) (xy 65.545797 -17.440373) (xy 65.534217 -17.493622) (xy 65.515176 -17.544681)
			(xy 65.489062 -17.592511) (xy 65.456407 -17.636137) (xy 65.417876 -17.674671) (xy 65.374252 -17.707329)
			(xy 65.326425 -17.733446) (xy 65.275367 -17.752491) (xy 65.222119 -17.764075) (xy 65.167764 -17.767963)
			(xy 65.113409 -17.764075) (xy 65.060161 -17.752491) (xy 65.009103 -17.733446) (xy 64.961276 -17.707329)
			(xy 64.917652 -17.674671) (xy 64.879121 -17.636137) (xy 64.846466 -17.592511) (xy 64.820352 -17.544681)
			(xy 64.801311 -17.493622) (xy 64.789731 -17.440373) (xy 64.785847 -17.386018) (xy 36.474618 -17.386018)
			(xy 36.471468 -17.420013) (xy 36.4555 -17.505433) (xy 36.431719 -17.589015) (xy 36.400327 -17.670047)
			(xy 36.361593 -17.747836) (xy 36.315846 -17.82172) (xy 36.263477 -17.891067) (xy 36.204933 -17.955287)
			(xy 36.140713 -18.013831) (xy 36.071366 -18.0662) (xy 35.997482 -18.111947) (xy 35.919693 -18.150681)
			(xy 35.838661 -18.182073) (xy 35.755079 -18.205854) (xy 35.669659 -18.221822) (xy 35.58313 -18.22984)
			(xy 35.49623 -18.22984) (xy 35.409701 -18.221822) (xy 35.324281 -18.205854) (xy 35.240699 -18.182073)
			(xy 35.159667 -18.150681) (xy 35.081878 -18.111947) (xy 35.007994 -18.0662) (xy 34.938647 -18.013831)
			(xy 34.874427 -17.955287) (xy 34.815883 -17.891067) (xy 34.763514 -17.82172) (xy 34.717767 -17.747836)
			(xy 34.679033 -17.670047) (xy 34.647641 -17.589015) (xy 34.62386 -17.505433) (xy 34.607892 -17.420013)
			(xy 34.599874 -17.333484) (xy 31.398504 -17.333484) (xy 31.396714 -17.374425) (xy 31.384954 -17.460391)
			(xy 31.365325 -17.544908) (xy 31.337994 -17.627257) (xy 31.303192 -17.706738) (xy 31.28264 -17.744948)
			(xy 31.272421 -17.76442) (xy 31.258079 -17.805984) (xy 31.251105 -17.849396) (xy 31.251708 -17.893361)
			(xy 31.259871 -17.936566) (xy 31.275349 -17.977721) (xy 31.29768 -18.015597) (xy 31.326198 -18.049064)
			(xy 31.360052 -18.077121) (xy 31.39823 -18.098932) (xy 31.439593 -18.113846) (xy 31.482905 -18.121417)
			(xy 31.50489 -18.121884) (xy 32.670496 -18.121884) (xy 33.157837 -18.609225) (xy 47.374038 -18.609225)
			(xy 47.374038 -18.528115) (xy 47.381988 -18.447396) (xy 47.397811 -18.367845) (xy 47.421356 -18.290229)
			(xy 47.452395 -18.215293) (xy 47.49063 -18.143761) (xy 47.535692 -18.076321) (xy 47.587147 -18.013622)
			(xy 47.6445 -17.956269) (xy 47.707199 -17.904814) (xy 47.774639 -17.859752) (xy 47.846171 -17.821517)
			(xy 47.921107 -17.790478) (xy 47.998723 -17.766933) (xy 48.078274 -17.75111) (xy 48.158993 -17.74316)
			(xy 48.240103 -17.74316) (xy 48.320822 -17.75111) (xy 48.400373 -17.766933) (xy 48.477989 -17.790478)
			(xy 48.552925 -17.821517) (xy 48.624457 -17.859752) (xy 48.691897 -17.904814) (xy 48.754596 -17.956269)
			(xy 48.811949 -18.013622) (xy 48.863404 -18.076321) (xy 48.908466 -18.143761) (xy 48.946701 -18.215293)
			(xy 48.97774 -18.290229) (xy 49.001285 -18.367845) (xy 49.017108 -18.447396) (xy 49.025058 -18.528115)
			(xy 49.025556 -18.56867) (xy 49.025058 -18.609225) (xy 50.874158 -18.609225) (xy 50.874158 -18.528115)
			(xy 50.882108 -18.447396) (xy 50.897931 -18.367845) (xy 50.921476 -18.290229) (xy 50.952515 -18.215293)
			(xy 50.99075 -18.143761) (xy 51.035812 -18.076321) (xy 51.087267 -18.013622) (xy 51.14462 -17.956269)
			(xy 51.207319 -17.904814) (xy 51.274759 -17.859752) (xy 51.346291 -17.821517) (xy 51.421227 -17.790478)
			(xy 51.498843 -17.766933) (xy 51.578394 -17.75111) (xy 51.659113 -17.74316) (xy 51.740223 -17.74316)
			(xy 51.820942 -17.75111) (xy 51.900493 -17.766933) (xy 51.978109 -17.790478) (xy 52.053045 -17.821517)
			(xy 52.124577 -17.859752) (xy 52.192017 -17.904814) (xy 52.254716 -17.956269) (xy 52.312069 -18.013622)
			(xy 52.363524 -18.076321) (xy 52.408586 -18.143761) (xy 52.446821 -18.215293) (xy 52.47786 -18.290229)
			(xy 52.501405 -18.367845) (xy 52.517228 -18.447396) (xy 52.525178 -18.528115) (xy 52.525676 -18.56867)
			(xy 52.525178 -18.609225) (xy 52.517228 -18.689944) (xy 52.501405 -18.769495) (xy 52.47786 -18.847111)
			(xy 52.446821 -18.922047) (xy 52.408586 -18.993579) (xy 52.363524 -19.061019) (xy 52.312069 -19.123718)
			(xy 52.254716 -19.181071) (xy 52.192017 -19.232526) (xy 52.124577 -19.277588) (xy 52.053045 -19.315823)
			(xy 51.978109 -19.346862) (xy 51.900493 -19.370407) (xy 51.820942 -19.38623) (xy 51.740223 -19.39418)
			(xy 51.659113 -19.39418) (xy 51.578394 -19.38623) (xy 51.498843 -19.370407) (xy 51.421227 -19.346862)
			(xy 51.346291 -19.315823) (xy 51.274759 -19.277588) (xy 51.207319 -19.232526) (xy 51.14462 -19.181071)
			(xy 51.087267 -19.123718) (xy 51.035812 -19.061019) (xy 50.99075 -18.993579) (xy 50.952515 -18.922047)
			(xy 50.921476 -18.847111) (xy 50.897931 -18.769495) (xy 50.882108 -18.689944) (xy 50.874158 -18.609225)
			(xy 49.025058 -18.609225) (xy 49.017108 -18.689944) (xy 49.001285 -18.769495) (xy 48.97774 -18.847111)
			(xy 48.946701 -18.922047) (xy 48.908466 -18.993579) (xy 48.863404 -19.061019) (xy 48.811949 -19.123718)
			(xy 48.754596 -19.181071) (xy 48.691897 -19.232526) (xy 48.624457 -19.277588) (xy 48.552925 -19.315823)
			(xy 48.477989 -19.346862) (xy 48.400373 -19.370407) (xy 48.320822 -19.38623) (xy 48.240103 -19.39418)
			(xy 48.158993 -19.39418) (xy 48.078274 -19.38623) (xy 47.998723 -19.370407) (xy 47.921107 -19.346862)
			(xy 47.846171 -19.315823) (xy 47.774639 -19.277588) (xy 47.707199 -19.232526) (xy 47.6445 -19.181071)
			(xy 47.587147 -19.123718) (xy 47.535692 -19.061019) (xy 47.49063 -18.993579) (xy 47.452395 -18.922047)
			(xy 47.421356 -18.847111) (xy 47.397811 -18.769495) (xy 47.381988 -18.689944) (xy 47.374038 -18.609225)
			(xy 33.157837 -18.609225) (xy 34.215832 -19.66722) (xy 34.231662 -19.682317) (xy 34.267419 -19.707505)
			(xy 34.306962 -19.726195) (xy 34.349122 -19.737836) (xy 34.392653 -19.742083) (xy 34.436268 -19.738811)
			(xy 34.478678 -19.728117) (xy 34.518629 -19.710316) (xy 34.554941 -19.685936) (xy 34.58654 -19.655695)
			(xy 34.612493 -19.62049) (xy 34.632031 -19.581359) (xy 34.638742 -19.56054) (xy 34.651797 -19.518639)
			(xy 34.684675 -19.43726) (xy 34.724993 -19.359299) (xy 34.7724 -19.285434) (xy 34.826484 -19.216308)
			(xy 34.886773 -19.152521) (xy 34.952744 -19.094631) (xy 35.023821 -19.043139) (xy 35.099388 -18.998494)
			(xy 35.178786 -18.961084) (xy 35.261324 -18.931236) (xy 35.346284 -18.909208) (xy 35.432928 -18.895193)
			(xy 35.5205 -18.889312) (xy 35.608239 -18.891617) (xy 35.695382 -18.902087) (xy 35.78117 -18.920631)
			(xy 35.864857 -18.947089) (xy 35.945714 -18.981229) (xy 36.023038 -19.022755) (xy 36.096157 -19.071306)
			(xy 36.164434 -19.126458) (xy 36.227274 -19.187732) (xy 36.284132 -19.254596) (xy 36.334512 -19.326466)
			(xy 36.377976 -19.402718) (xy 36.414145 -19.482688) (xy 36.442706 -19.565681) (xy 36.463409 -19.650973)
			(xy 36.476075 -19.737824) (xy 36.480593 -19.825477) (xy 36.476923 -19.91317) (xy 36.465099 -20.000139)
			(xy 36.445222 -20.085628) (xy 36.417466 -20.168894) (xy 36.400232 -20.209256) (xy 36.391426 -20.230459)
			(xy 36.380742 -20.275106) (xy 36.378248 -20.320946) (xy 36.384027 -20.366488) (xy 36.397889 -20.410253)
			(xy 36.419384 -20.450817) (xy 36.447814 -20.486862) (xy 36.482255 -20.517215) (xy 36.521586 -20.540892)
			(xy 36.564529 -20.55712) (xy 36.609688 -20.565374) (xy 36.632642 -20.565872) (xy 39.155878 -20.565872)
			(xy 39.437564 -20.283932) (xy 50.988722 -20.283932) (xy 60.601352 -29.896816) (xy 64.081914 -29.896816)
			(xy 64.96812 -29.010356) (xy 64.990853 -28.988354) (xy 65.041045 -28.949841) (xy 65.095834 -28.918208)
			(xy 65.154284 -28.893997) (xy 65.215393 -28.877623) (xy 65.278117 -28.869365) (xy 65.341383 -28.869365)
			(xy 65.404107 -28.877623) (xy 65.465216 -28.893997) (xy 65.523666 -28.918208) (xy 65.578455 -28.949841)
			(xy 65.628647 -28.988354) (xy 65.673382 -29.033089) (xy 65.711895 -29.083281) (xy 65.743528 -29.13807)
			(xy 65.767739 -29.19652) (xy 65.784113 -29.257629) (xy 65.792371 -29.320353) (xy 65.792371 -29.383619)
			(xy 65.784113 -29.446343) (xy 65.767739 -29.507452) (xy 65.743528 -29.565902) (xy 65.711895 -29.620691)
			(xy 65.673382 -29.670883) (xy 65.65138 -29.693616) (xy 64.44488 -30.899862) (xy 64.433575 -30.912075)
			(xy 64.416983 -30.940902) (xy 64.408391 -30.973035) (xy 64.408382 -31.006296) (xy 64.416956 -31.038433)
			(xy 64.433533 -31.06727) (xy 64.44488 -31.07944) (xy 65.606168 -32.240474) (xy 65.62817 -32.263207)
			(xy 65.656138 -32.299656) (xy 72.868035 -32.299656) (xy 72.872042 -32.096906) (xy 72.884055 -31.894472)
			(xy 72.904056 -31.692671) (xy 72.932015 -31.491817) (xy 72.967886 -31.292225) (xy 73.011615 -31.094206)
			(xy 73.063133 -30.898069) (xy 73.122359 -30.704121) (xy 73.189201 -30.512663) (xy 73.263555 -30.323996)
			(xy 73.345304 -30.138414) (xy 73.434322 -29.956206) (xy 73.530468 -29.777657) (xy 73.633593 -29.603046)
			(xy 73.743536 -29.432646) (xy 73.860125 -29.266722) (xy 73.983178 -29.105533) (xy 74.112503 -28.949332)
			(xy 74.247898 -28.798362) (xy 74.389151 -28.652858) (xy 74.536043 -28.513049) (xy 74.688343 -28.379152)
			(xy 74.845814 -28.251377) (xy 75.008211 -28.129922) (xy 75.175278 -28.014978) (xy 75.346757 -27.906724)
			(xy 75.522378 -27.805329) (xy 75.701868 -27.710951) (xy 75.884946 -27.623739) (xy 76.071327 -27.543827)
			(xy 76.26072 -27.47134) (xy 76.452828 -27.406393) (xy 76.647352 -27.349085) (xy 76.843988 -27.299508)
			(xy 77.04243 -27.257737) (xy 77.242367 -27.223839) (xy 77.443486 -27.197867) (xy 77.645475 -27.17986)
			(xy 77.848018 -27.169847) (xy 78.050798 -27.167843) (xy 78.253499 -27.173853) (xy 78.455804 -27.187865)
			(xy 78.657398 -27.20986) (xy 78.857965 -27.239801) (xy 79.057193 -27.277642) (xy 79.254771 -27.323325)
			(xy 79.450389 -27.376778) (xy 79.643743 -27.437917) (xy 79.834531 -27.506648) (xy 80.022454 -27.582862)
			(xy 80.20722 -27.666441) (xy 80.388539 -27.757254) (xy 80.56613 -27.855159) (xy 80.739713 -27.960004)
			(xy 80.909019 -28.071625) (xy 81.073784 -28.189847) (xy 81.233749 -28.314487) (xy 81.388665 -28.445348)
			(xy 81.53829 -28.582228) (xy 81.68239 -28.724912) (xy 81.820742 -28.873178) (xy 81.953127 -29.026794)
			(xy 82.079341 -29.185519) (xy 82.199185 -29.349108) (xy 82.312473 -29.517303) (xy 82.419028 -29.689842)
			(xy 82.518683 -29.866457) (xy 82.611283 -30.04687) (xy 82.696683 -30.230801) (xy 82.77475 -30.417962)
			(xy 82.845362 -30.608062) (xy 82.908408 -30.800802) (xy 82.963791 -30.995883) (xy 83.011423 -31.193)
			(xy 83.051231 -31.391844) (xy 83.083153 -31.592106) (xy 83.107137 -31.793472) (xy 83.123148 -31.995629)
			(xy 83.131159 -32.198261) (xy 83.13166 -32.299656) (xy 83.131159 -32.401051) (xy 83.123148 -32.603683)
			(xy 83.107137 -32.80584) (xy 83.083153 -33.007206) (xy 83.051231 -33.207468) (xy 83.011423 -33.406312)
			(xy 82.963791 -33.603429) (xy 82.908408 -33.79851) (xy 82.845362 -33.99125) (xy 82.77475 -34.18135)
			(xy 82.696683 -34.368511) (xy 82.611283 -34.552442) (xy 82.518683 -34.732855) (xy 82.419028 -34.90947)
			(xy 82.312473 -35.082009) (xy 82.199185 -35.250204) (xy 82.079341 -35.413793) (xy 81.953127 -35.572518)
			(xy 81.820742 -35.726134) (xy 81.68239 -35.8744) (xy 81.53829 -36.017084) (xy 81.388665 -36.153964)
			(xy 81.233749 -36.284825) (xy 81.073784 -36.409465) (xy 80.909019 -36.527687) (xy 80.739713 -36.639308)
			(xy 80.56613 -36.744153) (xy 80.388539 -36.842058) (xy 80.20722 -36.932871) (xy 80.022454 -37.01645)
			(xy 79.834531 -37.092664) (xy 79.643743 -37.161395) (xy 79.450389 -37.222534) (xy 79.254771 -37.275987)
			(xy 79.057193 -37.32167) (xy 78.857965 -37.359511) (xy 78.657398 -37.389452) (xy 78.455804 -37.411447)
			(xy 78.253499 -37.425459) (xy 78.050798 -37.431469) (xy 77.848018 -37.429465) (xy 77.645475 -37.419452)
			(xy 77.443486 -37.401445) (xy 77.242367 -37.375473) (xy 77.04243 -37.341575) (xy 76.843988 -37.299804)
			(xy 76.647352 -37.250227) (xy 76.452828 -37.192919) (xy 76.26072 -37.127972) (xy 76.071327 -37.055485)
			(xy 75.884946 -36.975573) (xy 75.701868 -36.888361) (xy 75.522378 -36.793983) (xy 75.346757 -36.692588)
			(xy 75.175278 -36.584334) (xy 75.008211 -36.46939) (xy 74.845814 -36.347935) (xy 74.688343 -36.22016)
			(xy 74.536043 -36.086263) (xy 74.389151 -35.946454) (xy 74.247898 -35.80095) (xy 74.112503 -35.64998)
			(xy 73.983178 -35.493779) (xy 73.860125 -35.33259) (xy 73.743536 -35.166666) (xy 73.633593 -34.996266)
			(xy 73.530468 -34.821655) (xy 73.434322 -34.643106) (xy 73.345304 -34.460898) (xy 73.263555 -34.275316)
			(xy 73.189201 -34.086649) (xy 73.122359 -33.895191) (xy 73.063133 -33.701243) (xy 73.011615 -33.505106)
			(xy 72.967886 -33.307087) (xy 72.932015 -33.107495) (xy 72.904056 -32.906641) (xy 72.884055 -32.70484)
			(xy 72.872042 -32.502406) (xy 72.868035 -32.299656) (xy 65.656138 -32.299656) (xy 65.666683 -32.313399)
			(xy 65.698316 -32.368188) (xy 65.722527 -32.426638) (xy 65.738901 -32.487747) (xy 65.747159 -32.550471)
			(xy 65.747159 -32.613737) (xy 65.738901 -32.676461) (xy 65.722527 -32.73757) (xy 65.698316 -32.79602)
			(xy 65.666683 -32.850809) (xy 65.62817 -32.901001) (xy 65.583435 -32.945736) (xy 65.533243 -32.984249)
			(xy 65.478454 -33.015882) (xy 65.420004 -33.040093) (xy 65.358895 -33.056467) (xy 65.296171 -33.064725)
			(xy 65.232905 -33.064725) (xy 65.170181 -33.056467) (xy 65.109072 -33.040093) (xy 65.050622 -33.015882)
			(xy 64.995833 -32.984249) (xy 64.945641 -32.945736) (xy 64.922908 -32.923734) (xy 63.68923 -31.690056)
			(xy 59.858148 -31.690056) (xy 50.245518 -22.077172) (xy 41.613836 -22.077172) (xy 41.590582 -22.077692)
			(xy 41.544851 -22.086164) (xy 41.501425 -22.102815) (xy 41.461753 -22.127088) (xy 41.427159 -22.158174)
			(xy 41.398798 -22.195034) (xy 41.377615 -22.236439) (xy 41.364319 -22.281006) (xy 41.359352 -22.327249)
			(xy 41.360598 -22.350476) (xy 41.362221 -22.378223) (xy 41.358349 -22.433668) (xy 41.346476 -22.487965)
			(xy 41.326851 -22.539966) (xy 41.29989 -22.588569) (xy 41.266164 -22.632747) (xy 41.226386 -22.671566)
			(xy 41.181398 -22.704203) (xy 41.13215 -22.729969) (xy 41.079686 -22.748318) (xy 41.052496 -22.754082)
			(xy 41.029443 -22.759068) (xy 40.985596 -22.776435) (xy 40.945704 -22.80159) (xy 40.911134 -22.83367)
			(xy 40.883073 -22.871574) (xy 40.862481 -22.914002) (xy 40.850067 -22.9595) (xy 40.846255 -23.006507)
			(xy 40.851176 -23.05341) (xy 40.857424 -23.076154) (xy 40.864896 -23.102972) (xy 40.872914 -23.15806)
			(xy 40.872842 -23.213729) (xy 40.864681 -23.268797) (xy 40.848605 -23.322094) (xy 40.824956 -23.37249)
			(xy 40.794234 -23.418914) (xy 40.757093 -23.460382) (xy 40.71432 -23.496012) (xy 40.666824 -23.525049)
			(xy 40.615613 -23.546877) (xy 40.561774 -23.561031) (xy 40.506449 -23.567212) (xy 40.450813 -23.565289)
			(xy 40.396047 -23.555301) (xy 40.343314 -23.537461) (xy 40.293733 -23.512149) (xy 40.248356 -23.4799)
			(xy 40.208147 -23.4414) (xy 40.173959 -23.397466) (xy 40.146517 -23.349031) (xy 40.126405 -23.297122)
			(xy 40.114049 -23.242841) (xy 40.109712 -23.187342) (xy 40.113485 -23.131801) (xy 40.125288 -23.077398)
			(xy 40.144872 -23.025287) (xy 40.17182 -22.976575) (xy 40.20556 -22.932296) (xy 40.245376 -22.893389)
			(xy 40.290422 -22.860681) (xy 40.339744 -22.834866) (xy 40.392293 -22.816491) (xy 40.419528 -22.810724)
			(xy 40.442583 -22.805747) (xy 40.486428 -22.788376) (xy 40.526319 -22.763219) (xy 40.560887 -22.731138)
			(xy 40.588948 -22.693233) (xy 40.609539 -22.650804) (xy 40.621954 -22.605306) (xy 40.625767 -22.5583)
			(xy 40.620847 -22.511396) (xy 40.6146 -22.488652) (xy 40.606405 -22.459142) (xy 40.598486 -22.398414)
			(xy 40.600365 -22.3372) (xy 40.611995 -22.277073) (xy 40.621966 -22.248114) (xy 40.629586 -22.226778)
			(xy 40.629586 -22.204172) (xy 40.629081 -22.187521) (xy 40.620455 -22.155356) (xy 40.603799 -22.126519)
			(xy 40.580248 -22.102975) (xy 40.551405 -22.086328) (xy 40.519237 -22.077713) (xy 40.502586 -22.077172)
			(xy 40.360854 -22.077172) (xy 40.32912 -22.076662) (xy 40.266202 -22.068333) (xy 40.204915 -22.051838)
			(xy 40.146316 -22.027462) (xy 40.091413 -21.995623) (xy 40.04115 -21.95687) (xy 39.996394 -21.91187)
			(xy 39.957915 -21.861397) (xy 39.926376 -21.806321) (xy 39.902319 -21.74759) (xy 39.886158 -21.686214)
			(xy 39.878172 -21.623252) (xy 39.878498 -21.559785) (xy 39.882318 -21.528278) (xy 39.886636 -21.49856)
			(xy 39.867586 -21.442172) (xy 39.846504 -21.42109) (xy 39.834396 -21.409632) (xy 39.805561 -21.392922)
			(xy 39.773378 -21.384271) (xy 39.740052 -21.384271) (xy 39.707869 -21.392922) (xy 39.679034 -21.409632)
			(xy 39.666926 -21.42109) (xy 39.556182 -21.53158) (xy 36.581334 -21.53158) (xy 36.559274 -21.532048)
			(xy 36.515816 -21.539662) (xy 36.474325 -21.554667) (xy 36.43605 -21.576612) (xy 36.402139 -21.604837)
			(xy 36.373613 -21.638495) (xy 36.351328 -21.676573) (xy 36.335955 -21.717928) (xy 36.327954 -21.761317)
			(xy 36.327567 -21.805436) (xy 36.334805 -21.848958) (xy 36.349451 -21.890577) (xy 36.359846 -21.91004)
			(xy 36.380422 -21.94772) (xy 36.41542 -22.026122) (xy 36.443124 -22.107387) (xy 36.463304 -22.19084)
			(xy 36.475793 -22.275786) (xy 36.480485 -22.361516) (xy 36.477341 -22.447317) (xy 36.466389 -22.532474)
			(xy 36.447719 -22.616277) (xy 36.421486 -22.69803) (xy 36.38791 -22.777051) (xy 36.347269 -22.852681)
			(xy 36.299903 -22.924292) (xy 36.246205 -22.991286) (xy 36.186624 -23.053106) (xy 36.121654 -23.109236)
			(xy 36.051838 -23.15921) (xy 35.977757 -23.202611) (xy 35.900027 -23.239077) (xy 35.819297 -23.268305)
			(xy 35.736238 -23.290051) (xy 35.651543 -23.304135) (xy 35.565916 -23.310439) (xy 35.480071 -23.30891)
			(xy 35.394724 -23.299561) (xy 35.310583 -23.28247) (xy 35.228352 -23.25778) (xy 35.148713 -23.225695)
			(xy 35.072332 -23.186484) (xy 34.999843 -23.140473) (xy 34.931851 -23.088045) (xy 34.868921 -23.029637)
			(xy 34.811579 -22.965734) (xy 34.760301 -22.896871) (xy 34.715515 -22.823619) (xy 34.677593 -22.746589)
			(xy 34.646852 -22.666422) (xy 34.623547 -22.583787) (xy 34.607873 -22.499372) (xy 34.59996 -22.413879)
			(xy 34.599874 -22.328021) (xy 34.607616 -22.242512) (xy 34.623122 -22.158065) (xy 34.646261 -22.075384)
			(xy 34.676842 -21.995156) (xy 34.714609 -21.918051) (xy 34.759249 -21.844709) (xy 34.810389 -21.775743)
			(xy 34.83864 -21.743416) (xy 34.870898 -21.707094) (xy 34.870898 -21.65858) (xy 34.870374 -21.641931)
			(xy 34.861752 -21.609767) (xy 34.845099 -21.580932) (xy 34.821551 -21.557388) (xy 34.792712 -21.54074)
			(xy 34.760547 -21.532123) (xy 34.743898 -21.53158) (xy 34.71418 -21.53158) (xy 32.270192 -19.087592)
			(xy 31.549594 -19.087592) (xy 31.526571 -19.088072) (xy 31.481274 -19.09635) (xy 31.43821 -19.112653)
			(xy 31.398787 -19.136446) (xy 31.364296 -19.166953) (xy 31.335864 -19.203173) (xy 31.314423 -19.243923)
			(xy 31.300672 -19.287868) (xy 31.295064 -19.333572) (xy 31.29778 -19.379539) (xy 31.308733 -19.424264)
			(xy 31.317692 -19.445478) (xy 31.335063 -19.485438) (xy 31.363191 -19.567911) (xy 31.383569 -19.652633)
			(xy 31.39602 -19.738878) (xy 31.400437 -19.825904) (xy 31.396784 -19.912966) (xy 31.385091 -19.999316)
			(xy 31.365458 -20.084214) (xy 31.338054 -20.166931) (xy 31.303115 -20.246758) (xy 31.260939 -20.32301)
			(xy 31.211889 -20.395032) (xy 31.156386 -20.462207) (xy 31.094905 -20.523958) (xy 31.027975 -20.579756)
			(xy 30.956168 -20.629121) (xy 30.880103 -20.671631) (xy 30.80043 -20.706921) (xy 30.717834 -20.734687)
			(xy 30.633023 -20.754693) (xy 30.546725 -20.766765) (xy 30.45968 -20.7708) (xy 30.372635 -20.766765)
			(xy 30.286337 -20.754693) (xy 30.201526 -20.734687) (xy 30.11893 -20.706921) (xy 30.039257 -20.671631)
			(xy 29.963192 -20.629121) (xy 29.891385 -20.579756) (xy 29.824455 -20.523958) (xy 29.762974 -20.462207)
			(xy 29.707471 -20.395032) (xy 29.658421 -20.32301) (xy 29.616245 -20.246758) (xy 29.581306 -20.166931)
			(xy 29.553902 -20.084214) (xy 29.534269 -19.999316) (xy 29.522576 -19.912966) (xy 29.518923 -19.825904)
			(xy 29.52334 -19.738878) (xy 29.535791 -19.652633) (xy 29.556169 -19.567911) (xy 29.584297 -19.485438)
			(xy 29.601668 -19.445478) (xy 29.610599 -19.424258) (xy 29.621525 -19.379539) (xy 29.624223 -19.333585)
			(xy 29.618603 -19.287895) (xy 29.60485 -19.243963) (xy 29.583412 -19.203226) (xy 29.55499 -19.167013)
			(xy 29.520513 -19.136509) (xy 29.481108 -19.112711) (xy 29.438063 -19.096395) (xy 29.392783 -19.088096)
			(xy 29.369766 -19.087592) (xy 28.84424 -19.087592) (xy 28.589478 -18.833084) (xy 27.244802 -18.833084)
			(xy 27.213168 -18.832637) (xy 27.150442 -18.824379) (xy 27.08933 -18.808005) (xy 27.030878 -18.783793)
			(xy 26.976087 -18.75216) (xy 26.925893 -18.713645) (xy 26.881156 -18.668908) (xy 26.842641 -18.618715)
			(xy 26.811008 -18.563923) (xy 26.786796 -18.505472) (xy 26.770421 -18.44436) (xy 26.762163 -18.381634)
			(xy 14.640359 -18.381634) (xy 14.628522 -18.399349) (xy 14.577067 -18.462048) (xy 14.519714 -18.519401)
			(xy 14.457015 -18.570856) (xy 14.389575 -18.615918) (xy 14.318043 -18.654153) (xy 14.243107 -18.685192)
			(xy 14.165491 -18.708737) (xy 14.08594 -18.72456) (xy 14.005221 -18.73251) (xy 13.924111 -18.73251)
			(xy 13.843392 -18.72456) (xy 13.763841 -18.708737) (xy 13.686225 -18.685192) (xy 13.611289 -18.654153)
			(xy 13.539757 -18.615918) (xy 13.472317 -18.570856) (xy 13.409618 -18.519401) (xy 13.352265 -18.462048)
			(xy 13.30081 -18.399349) (xy 13.255748 -18.331909) (xy 13.217513 -18.260377) (xy 13.186474 -18.185441)
			(xy 13.162929 -18.107825) (xy 13.147106 -18.028274) (xy 13.139156 -17.947555) (xy 9.296321 -17.947555)
			(xy 9.345249 -18.015788) (xy 9.414094 -18.125624) (xy 9.475977 -18.239528) (xy 9.530658 -18.357058)
			(xy 9.577928 -18.477761) (xy 9.617601 -18.601169) (xy 9.649526 -18.726805) (xy 9.673578 -18.854182)
			(xy 9.689665 -18.982808) (xy 9.697724 -19.112186) (xy 9.698228 -19.177) (xy 9.697724 -19.241814)
			(xy 9.689665 -19.371192) (xy 9.673578 -19.499818) (xy 9.649526 -19.627195) (xy 9.617601 -19.752831)
			(xy 9.577928 -19.876239) (xy 9.530658 -19.996942) (xy 9.475977 -20.114472) (xy 9.414094 -20.228376)
			(xy 9.345249 -20.338212) (xy 9.26971 -20.443555) (xy 9.187767 -20.543998) (xy 9.099738 -20.639153)
			(xy 9.005964 -20.728651) (xy 8.906807 -20.812146) (xy 8.802651 -20.889315) (xy 8.693899 -20.959859)
			(xy 8.580971 -21.023506) (xy 8.464306 -21.080009) (xy 8.344353 -21.12915) (xy 8.221577 -21.170738)
			(xy 8.096453 -21.204613) (xy 7.969465 -21.230643) (xy 7.841104 -21.248728) (xy 7.711868 -21.258798)
			(xy 7.582255 -21.260814) (xy 7.452768 -21.254768) (xy 7.323907 -21.240684) (xy 7.196171 -21.218615)
			(xy 7.070054 -21.188648) (xy 6.946044 -21.150899) (xy 6.824621 -21.105512) (xy 6.706254 -21.052665)
			(xy 6.591402 -20.992561) (xy 6.480509 -20.925433) (xy 6.374003 -20.851541) (xy 6.272297 -20.77117)
			(xy 6.175785 -20.684632) (xy 6.08484 -20.59226) (xy 5.999813 -20.494414) (xy 5.921033 -20.391471)
			(xy 5.848806 -20.283829) (xy 5.783411 -20.171905) (xy 5.7251 -20.056132) (xy 5.6741 -19.936958) (xy 5.630608 -19.814844)
			(xy 5.594791 -19.690261) (xy 5.566789 -19.563694) (xy 5.54671 -19.43563) (xy 5.534631 -19.306566)
			(xy 5.5306 -19.177) (xy 1.525016 -19.177) (xy 1.525016 -21.8821) (xy 27.22067 -21.8821) (xy 27.224741 -21.826478)
			(xy 27.236867 -21.772041) (xy 27.25679 -21.71995) (xy 27.284086 -21.671315) (xy 27.318172 -21.627172)
			(xy 27.358321 -21.588463) (xy 27.403679 -21.556012) (xy 27.453279 -21.530511) (xy 27.506063 -21.512504)
			(xy 27.560906 -21.502374) (xy 27.61664 -21.500337) (xy 27.672077 -21.506437) (xy 27.726034 -21.520543)
			(xy 27.777363 -21.542355) (xy 27.824969 -21.571409) (xy 27.867837 -21.607084) (xy 27.905054 -21.648621)
			(xy 27.935827 -21.695134) (xy 27.959499 -21.745631) (xy 27.975567 -21.799038) (xy 27.983687 -21.854214)
			(xy 27.984196 -21.8821) (xy 27.983687 -21.909986) (xy 27.975567 -21.965162) (xy 27.959499 -22.018569)
			(xy 27.935827 -22.069066) (xy 27.905054 -22.115579) (xy 27.867837 -22.157116) (xy 27.824969 -22.192791)
			(xy 27.777363 -22.221845) (xy 27.726034 -22.243657) (xy 27.672077 -22.257763) (xy 27.61664 -22.263863)
			(xy 27.560906 -22.261826) (xy 27.506063 -22.251696) (xy 27.453279 -22.233689) (xy 27.403679 -22.208188)
			(xy 27.358321 -22.175737) (xy 27.318172 -22.137028) (xy 27.284086 -22.092885) (xy 27.25679 -22.04425)
			(xy 27.236867 -21.992159) (xy 27.224741 -21.937722) (xy 27.22067 -21.8821) (xy 1.525016 -21.8821)
			(xy 1.525016 -22.413484) (xy 29.519874 -22.413484) (xy 29.519874 -22.326584) (xy 29.527892 -22.240055)
			(xy 29.54386 -22.154635) (xy 29.567641 -22.071053) (xy 29.599033 -21.990021) (xy 29.637767 -21.912232)
			(xy 29.683514 -21.838348) (xy 29.735883 -21.769001) (xy 29.794427 -21.704781) (xy 29.858647 -21.646237)
			(xy 29.927994 -21.593868) (xy 30.001878 -21.548121) (xy 30.079667 -21.509387) (xy 30.160699 -21.477995)
			(xy 30.244281 -21.454214) (xy 30.329701 -21.438246) (xy 30.41623 -21.430228) (xy 30.50313 -21.430228)
			(xy 30.589659 -21.438246) (xy 30.675079 -21.454214) (xy 30.758661 -21.477995) (xy 30.839693 -21.509387)
			(xy 30.917482 -21.548121) (xy 30.991366 -21.593868) (xy 31.060713 -21.646237) (xy 31.124933 -21.704781)
			(xy 31.183477 -21.769001) (xy 31.235846 -21.838348) (xy 31.281593 -21.912232) (xy 31.320327 -21.990021)
			(xy 31.351719 -22.071053) (xy 31.3755 -22.154635) (xy 31.391468 -22.240055) (xy 31.399486 -22.326584)
			(xy 31.399988 -22.370034) (xy 31.399486 -22.413484) (xy 31.391468 -22.500013) (xy 31.3755 -22.585433)
			(xy 31.351719 -22.669015) (xy 31.320327 -22.750047) (xy 31.281593 -22.827836) (xy 31.235846 -22.90172)
			(xy 31.183477 -22.971067) (xy 31.124933 -23.035287) (xy 31.060713 -23.093831) (xy 30.991366 -23.1462)
			(xy 30.917482 -23.191947) (xy 30.839693 -23.230681) (xy 30.758661 -23.262073) (xy 30.675079 -23.285854)
			(xy 30.589659 -23.301822) (xy 30.50313 -23.30984) (xy 30.41623 -23.30984) (xy 30.329701 -23.301822)
			(xy 30.244281 -23.285854) (xy 30.160699 -23.262073) (xy 30.079667 -23.230681) (xy 30.001878 -23.191947)
			(xy 29.927994 -23.1462) (xy 29.858647 -23.093831) (xy 29.794427 -23.035287) (xy 29.735883 -22.971067)
			(xy 29.683514 -22.90172) (xy 29.637767 -22.827836) (xy 29.599033 -22.750047) (xy 29.567641 -22.669015)
			(xy 29.54386 -22.585433) (xy 29.527892 -22.500013) (xy 29.519874 -22.413484) (xy 1.525016 -22.413484)
			(xy 1.525016 -25.909778) (xy 6.672086 -25.909778) (xy 6.676039 -25.817963) (xy 6.687871 -25.726827)
			(xy 6.707494 -25.637046) (xy 6.734762 -25.549284) (xy 6.769473 -25.464192) (xy 6.811371 -25.382398)
			(xy 6.860146 -25.304509) (xy 6.915435 -25.2311) (xy 6.97683 -25.162717) (xy 7.043877 -25.099865)
			(xy 7.116079 -25.043008) (xy 7.1929 -24.99257) (xy 7.273774 -24.948921) (xy 7.3581 -24.912387) (xy 7.445255 -24.883237)
			(xy 7.534593 -24.861687) (xy 7.625453 -24.847897) (xy 7.717162 -24.841969) (xy 7.809041 -24.843946)
			(xy 7.90041 -24.853814) (xy 7.990592 -24.871501) (xy 8.07892 -24.896874) (xy 8.16474 -24.929747)
			(xy 8.247417 -24.969875) (xy 8.326337 -25.016962) (xy 8.400918 -25.07066) (xy 8.470607 -25.130569)
			(xy 8.534887 -25.196248) (xy 8.593284 -25.26721) (xy 8.645364 -25.342928) (xy 8.690742 -25.422844)
			(xy 8.729082 -25.506365) (xy 8.7601 -25.592872) (xy 8.783568 -25.681726) (xy 8.799309 -25.772268)
			(xy 8.80721 -25.863828) (xy 8.807704 -25.909778) (xy 8.80721 -25.955728) (xy 8.799309 -26.047288)
			(xy 8.783568 -26.13783) (xy 8.7601 -26.226684) (xy 8.729082 -26.313191) (xy 8.690742 -26.396712)
			(xy 8.645364 -26.476628) (xy 8.593284 -26.552346) (xy 8.534887 -26.623308) (xy 8.470607 -26.688987)
			(xy 8.400918 -26.748896) (xy 8.326337 -26.802594) (xy 8.247417 -26.849681) (xy 8.16474 -26.889809)
			(xy 8.07892 -26.922682) (xy 7.990592 -26.948055) (xy 7.90041 -26.965742) (xy 7.809041 -26.97561)
			(xy 7.717162 -26.977587) (xy 7.625453 -26.971659) (xy 7.534593 -26.957869) (xy 7.445255 -26.936319)
			(xy 7.3581 -26.907169) (xy 7.273774 -26.870635) (xy 7.1929 -26.826986) (xy 7.116079 -26.776548) (xy 7.043877 -26.719691)
			(xy 6.97683 -26.656839) (xy 6.915435 -26.588456) (xy 6.860146 -26.515047) (xy 6.811371 -26.437158)
			(xy 6.769473 -26.355364) (xy 6.734762 -26.270272) (xy 6.707494 -26.18251) (xy 6.687871 -26.092729)
			(xy 6.676039 -26.001593) (xy 6.672086 -25.909778) (xy 1.525016 -25.909778) (xy 1.525016 -29.19984)
			(xy 11.345418 -29.19984) (xy 11.345913 -29.096662) (xy 11.354005 -28.890463) (xy 11.370186 -28.684742)
			(xy 11.394432 -28.479814) (xy 11.426705 -28.275997) (xy 11.466954 -28.073603) (xy 11.515119 -27.872946)
			(xy 11.571125 -27.674335) (xy 11.634885 -27.478075) (xy 11.706302 -27.28447) (xy 11.785264 -27.093819)
			(xy 11.871651 -26.906414) (xy 11.965329 -26.722546) (xy 12.066153 -26.542497) (xy 12.173969 -26.366545)
			(xy 12.28861 -26.194963) (xy 12.409898 -26.028013) (xy 12.537648 -25.865954) (xy 12.671662 -25.709035)
			(xy 12.811733 -25.557499) (xy 12.957646 -25.411579) (xy 13.109175 -25.271501) (xy 13.266087 -25.137479)
			(xy 13.42814 -25.009722) (xy 13.595084 -24.888425) (xy 13.766662 -24.773776) (xy 13.942608 -24.665952)
			(xy 14.122652 -24.565119) (xy 14.306516 -24.471432) (xy 14.493916 -24.385036) (xy 14.684564 -24.306064)
			(xy 14.878165 -24.234638) (xy 15.074422 -24.170869) (xy 15.27303 -24.114853) (xy 15.473685 -24.066679)
			(xy 15.676077 -24.026419) (xy 15.879893 -23.994137) (xy 16.084819 -23.969881) (xy 16.29054 -23.95369)
			(xy 16.496738 -23.945588) (xy 16.599916 -23.945088) (xy 16.703094 -23.945596) (xy 16.909292 -23.953698)
			(xy 17.115013 -23.969888) (xy 17.319939 -23.994144) (xy 17.523755 -24.026426) (xy 17.726146 -24.066685)
			(xy 17.926801 -24.114859) (xy 18.12541 -24.170874) (xy 18.321666 -24.234644) (xy 18.515267 -24.30607)
			(xy 18.705915 -24.385041) (xy 18.893316 -24.471437) (xy 19.07718 -24.565123) (xy 19.257224 -24.665956)
			(xy 19.43317 -24.77378) (xy 19.604747 -24.888429) (xy 19.771691 -25.009725) (xy 19.933744 -25.137483)
			(xy 20.090656 -25.271504) (xy 20.242185 -25.411582) (xy 20.388098 -25.557502) (xy 20.52817 -25.709038)
			(xy 20.662183 -25.865956) (xy 20.789933 -26.028015) (xy 20.911222 -26.194965) (xy 21.025863 -26.366547)
			(xy 21.133678 -26.542499) (xy 21.234503 -26.722547) (xy 21.328181 -26.906416) (xy 21.414568 -27.09382)
			(xy 21.49353 -27.284472) (xy 21.564947 -27.478076) (xy 21.628707 -27.674336) (xy 21.684713 -27.872947)
			(xy 21.732878 -28.073604) (xy 21.773127 -28.275997) (xy 21.8054 -28.479815) (xy 21.829646 -28.684742)
			(xy 21.845827 -28.890464) (xy 21.853919 -29.096662) (xy 21.854414 -29.19984) (xy 21.853912 -29.303006)
			(xy 21.845812 -29.509178) (xy 21.829625 -29.714873) (xy 21.805375 -29.919775) (xy 21.773101 -30.123566)
			(xy 21.732851 -30.325934) (xy 21.684689 -30.526565) (xy 21.628687 -30.725151) (xy 21.564933 -30.921386)
			(xy 21.493524 -31.114966) (xy 21.414572 -31.305595) (xy 21.328196 -31.492976) (xy 21.234532 -31.676823)
			(xy 21.133722 -31.856851) (xy 21.025924 -32.032783) (xy 20.911301 -32.204347) (xy 20.790032 -32.37128)
			(xy 20.662304 -32.533323) (xy 20.528313 -32.690227) (xy 20.388265 -32.841751) (xy 20.242377 -32.98766)
			(xy 20.090874 -33.127729) (xy 19.933989 -33.261743) (xy 19.771964 -33.389495) (xy 19.605049 -33.510788)
			(xy 19.433501 -33.625435) (xy 19.257585 -33.733259) (xy 19.077572 -33.834095) (xy 18.893739 -33.927786)
			(xy 18.706369 -34.014188) (xy 18.515752 -34.093168) (xy 18.322182 -34.164604) (xy 18.125957 -34.228387)
			(xy 17.927379 -34.284417) (xy 17.726754 -34.332609) (xy 17.524393 -34.372888) (xy 17.320606 -34.405192)
			(xy 17.115708 -34.429471) (xy 16.910015 -34.445687) (xy 16.703844 -34.453817) (xy 16.600678 -34.454338)
			(xy 16.599154 -34.454338) (xy 16.495988 -34.453811) (xy 16.289818 -34.445681) (xy 16.084125 -34.429465)
			(xy 15.879227 -34.405186) (xy 15.67544 -34.372882) (xy 15.473079 -34.332603) (xy 15.272454 -34.284412)
			(xy 15.073877 -34.228382) (xy 14.877651 -34.164599) (xy 14.684081 -34.093163) (xy 14.493465 -34.014183)
			(xy 14.306095 -33.927781) (xy 14.122262 -33.83409) (xy 13.942249 -33.733255) (xy 13.766333 -33.62543)
			(xy 13.594785 -33.510784) (xy 13.42787 -33.389491) (xy 13.265846 -33.261739) (xy 13.108961 -33.127725)
			(xy 12.957458 -32.987656) (xy 12.81157 -32.841747) (xy 12.671523 -32.690224) (xy 12.537531 -32.53332)
			(xy 12.409803 -32.371277) (xy 12.288534 -32.204345) (xy 12.173912 -32.03278) (xy 12.066113 -31.856849)
			(xy 11.965304 -31.676821) (xy 11.871639 -31.492974) (xy 11.785264 -31.305593) (xy 11.706311 -31.114965)
			(xy 11.634903 -30.921384) (xy 11.571149 -30.72515) (xy 11.515147 -30.526564) (xy 11.466984 -30.325933)
			(xy 11.426735 -30.123565) (xy 11.394461 -29.919774) (xy 11.370211 -29.714873) (xy 11.354024 -29.509178)
			(xy 11.345924 -29.303006) (xy 11.345418 -29.19984) (xy 1.525016 -29.19984) (xy 1.525016 -31.952629)
			(xy 4.852911 -31.952629) (xy 4.852911 -31.866903) (xy 4.860821 -31.781543) (xy 4.876573 -31.697276)
			(xy 4.900033 -31.614823) (xy 4.931001 -31.534886) (xy 4.969212 -31.458147) (xy 5.014341 -31.385261)
			(xy 5.066002 -31.31685) (xy 5.123756 -31.253498) (xy 5.187108 -31.195744) (xy 5.255519 -31.144083)
			(xy 5.328405 -31.098954) (xy 5.405144 -31.060743) (xy 5.485081 -31.029775) (xy 5.567534 -31.006315)
			(xy 5.651801 -30.990563) (xy 5.737161 -30.982653) (xy 5.822887 -30.982653) (xy 5.908247 -30.990563)
			(xy 5.992514 -31.006315) (xy 6.074967 -31.029775) (xy 6.154904 -31.060743) (xy 6.231643 -31.098954)
			(xy 6.304529 -31.144083) (xy 6.37294 -31.195744) (xy 6.436292 -31.253498) (xy 6.494046 -31.31685)
			(xy 6.545707 -31.385261) (xy 6.590836 -31.458147) (xy 6.629047 -31.534886) (xy 6.660015 -31.614823)
			(xy 6.683475 -31.697276) (xy 6.699227 -31.781543) (xy 6.707137 -31.866903) (xy 6.707632 -31.909766)
			(xy 6.707137 -31.952629) (xy 6.699227 -32.037989) (xy 6.683475 -32.122256) (xy 6.660015 -32.204709)
			(xy 6.629047 -32.284646) (xy 6.590836 -32.361385) (xy 6.545707 -32.434271) (xy 6.494046 -32.502682)
			(xy 6.436292 -32.566034) (xy 6.37294 -32.623788) (xy 6.304529 -32.675449) (xy 6.231643 -32.720578)
			(xy 6.154904 -32.758789) (xy 6.074967 -32.789757) (xy 5.992514 -32.813217) (xy 5.908247 -32.828969)
			(xy 5.822887 -32.836879) (xy 5.737161 -32.836879) (xy 5.651801 -32.828969) (xy 5.567534 -32.813217)
			(xy 5.485081 -32.789757) (xy 5.405144 -32.758789) (xy 5.328405 -32.720578) (xy 5.255519 -32.675449)
			(xy 5.187108 -32.623788) (xy 5.123756 -32.566034) (xy 5.066002 -32.502682) (xy 5.014341 -32.434271)
			(xy 4.969212 -32.361385) (xy 4.931001 -32.284646) (xy 4.900033 -32.204709) (xy 4.876573 -32.122256)
			(xy 4.860821 -32.037989) (xy 4.852911 -31.952629) (xy 1.525016 -31.952629) (xy 1.525016 -34.90976)
			(xy 6.672086 -34.90976) (xy 6.676039 -34.817945) (xy 6.687871 -34.726809) (xy 6.707494 -34.637028)
			(xy 6.734762 -34.549266) (xy 6.769473 -34.464174) (xy 6.811371 -34.38238) (xy 6.860146 -34.304491)
			(xy 6.915435 -34.231082) (xy 6.97683 -34.162699) (xy 7.043877 -34.099847) (xy 7.116079 -34.04299)
			(xy 7.1929 -33.992552) (xy 7.273774 -33.948903) (xy 7.3581 -33.912369) (xy 7.445255 -33.883219) (xy 7.534593 -33.861669)
			(xy 7.625453 -33.847879) (xy 7.717162 -33.841951) (xy 7.809041 -33.843928) (xy 7.90041 -33.853796)
			(xy 7.990592 -33.871483) (xy 8.07892 -33.896856) (xy 8.16474 -33.929729) (xy 8.247417 -33.969857)
			(xy 8.326337 -34.016944) (xy 8.400918 -34.070642) (xy 8.470607 -34.130551) (xy 8.534887 -34.19623)
			(xy 8.593284 -34.267192) (xy 8.645364 -34.34291) (xy 8.690742 -34.422826) (xy 8.729082 -34.506347)
			(xy 8.7601 -34.592854) (xy 8.783568 -34.681708) (xy 8.799309 -34.77225) (xy 8.80721 -34.86381) (xy 8.807704 -34.90976)
			(xy 8.80721 -34.95571) (xy 8.799309 -35.04727) (xy 8.783568 -35.137812) (xy 8.7601 -35.226666) (xy 8.729082 -35.313173)
			(xy 8.690742 -35.396694) (xy 8.645364 -35.47661) (xy 8.593284 -35.552328) (xy 8.534887 -35.62329)
			(xy 8.470607 -35.688969) (xy 8.400918 -35.748878) (xy 8.326337 -35.802576) (xy 8.247417 -35.849663)
			(xy 8.16474 -35.889791) (xy 8.07892 -35.922664) (xy 7.990592 -35.948037) (xy 7.90041 -35.965724)
			(xy 7.809041 -35.975592) (xy 7.717162 -35.977569) (xy 7.625453 -35.971641) (xy 7.534593 -35.957851)
			(xy 7.445255 -35.936301) (xy 7.3581 -35.907151) (xy 7.273774 -35.870617) (xy 7.1929 -35.826968) (xy 7.116079 -35.77653)
			(xy 7.043877 -35.719673) (xy 6.97683 -35.656821) (xy 6.915435 -35.588438) (xy 6.860146 -35.515029)
			(xy 6.811371 -35.43714) (xy 6.769473 -35.355346) (xy 6.734762 -35.270254) (xy 6.707494 -35.182492)
			(xy 6.687871 -35.092711) (xy 6.676039 -35.001575) (xy 6.672086 -34.90976) (xy 1.525016 -34.90976)
			(xy 1.525016 -38.661255) (xy 47.507896 -38.661255) (xy 47.507896 -38.580145) (xy 47.515846 -38.499426)
			(xy 47.531669 -38.419875) (xy 47.555214 -38.342259) (xy 47.586253 -38.267323) (xy 47.624488 -38.195791)
			(xy 47.66955 -38.128351) (xy 47.721005 -38.065652) (xy 47.778358 -38.008299) (xy 47.841057 -37.956844)
			(xy 47.908497 -37.911782) (xy 47.980029 -37.873547) (xy 48.054965 -37.842508) (xy 48.132581 -37.818963)
			(xy 48.212132 -37.80314) (xy 48.292851 -37.79519) (xy 48.373961 -37.79519) (xy 48.45468 -37.80314)
			(xy 48.534231 -37.818963) (xy 48.611847 -37.842508) (xy 48.686783 -37.873547) (xy 48.758315 -37.911782)
			(xy 48.825755 -37.956844) (xy 48.888454 -38.008299) (xy 48.945807 -38.065652) (xy 48.997262 -38.128351)
			(xy 49.042324 -38.195791) (xy 49.080559 -38.267323) (xy 49.111598 -38.342259) (xy 49.135143 -38.419875)
			(xy 49.150966 -38.499426) (xy 49.158916 -38.580145) (xy 49.159414 -38.6207) (xy 49.158916 -38.661255)
			(xy 51.008016 -38.661255) (xy 51.008016 -38.580145) (xy 51.015966 -38.499426) (xy 51.031789 -38.419875)
			(xy 51.055334 -38.342259) (xy 51.086373 -38.267323) (xy 51.124608 -38.195791) (xy 51.16967 -38.128351)
			(xy 51.221125 -38.065652) (xy 51.278478 -38.008299) (xy 51.341177 -37.956844) (xy 51.408617 -37.911782)
			(xy 51.480149 -37.873547) (xy 51.555085 -37.842508) (xy 51.632701 -37.818963) (xy 51.712252 -37.80314)
			(xy 51.792971 -37.79519) (xy 51.874081 -37.79519) (xy 51.9548 -37.80314) (xy 52.034351 -37.818963)
			(xy 52.111967 -37.842508) (xy 52.186903 -37.873547) (xy 52.258435 -37.911782) (xy 52.325875 -37.956844)
			(xy 52.388574 -38.008299) (xy 52.445927 -38.065652) (xy 52.497382 -38.128351) (xy 52.542444 -38.195791)
			(xy 52.580679 -38.267323) (xy 52.611718 -38.342259) (xy 52.635263 -38.419875) (xy 52.651086 -38.499426)
			(xy 52.659036 -38.580145) (xy 52.659534 -38.6207) (xy 52.659036 -38.661255) (xy 52.651086 -38.741974)
			(xy 52.635263 -38.821525) (xy 52.611718 -38.899141) (xy 52.580679 -38.974077) (xy 52.542444 -39.045609)
			(xy 52.497382 -39.113049) (xy 52.445927 -39.175748) (xy 52.388574 -39.233101) (xy 52.325875 -39.284556)
			(xy 52.258435 -39.329618) (xy 52.186903 -39.367853) (xy 52.111967 -39.398892) (xy 52.034351 -39.422437)
			(xy 51.9548 -39.43826) (xy 51.874081 -39.44621) (xy 51.792971 -39.44621) (xy 51.712252 -39.43826)
			(xy 51.632701 -39.422437) (xy 51.555085 -39.398892) (xy 51.480149 -39.367853) (xy 51.408617 -39.329618)
			(xy 51.341177 -39.284556) (xy 51.278478 -39.233101) (xy 51.221125 -39.175748) (xy 51.16967 -39.113049)
			(xy 51.124608 -39.045609) (xy 51.086373 -38.974077) (xy 51.055334 -38.899141) (xy 51.031789 -38.821525)
			(xy 51.015966 -38.741974) (xy 51.008016 -38.661255) (xy 49.158916 -38.661255) (xy 49.150966 -38.741974)
			(xy 49.135143 -38.821525) (xy 49.111598 -38.899141) (xy 49.080559 -38.974077) (xy 49.042324 -39.045609)
			(xy 48.997262 -39.113049) (xy 48.945807 -39.175748) (xy 48.888454 -39.233101) (xy 48.825755 -39.284556)
			(xy 48.758315 -39.329618) (xy 48.686783 -39.367853) (xy 48.611847 -39.398892) (xy 48.534231 -39.422437)
			(xy 48.45468 -39.43826) (xy 48.373961 -39.44621) (xy 48.292851 -39.44621) (xy 48.212132 -39.43826)
			(xy 48.132581 -39.422437) (xy 48.054965 -39.398892) (xy 47.980029 -39.367853) (xy 47.908497 -39.329618)
			(xy 47.841057 -39.284556) (xy 47.778358 -39.233101) (xy 47.721005 -39.175748) (xy 47.66955 -39.113049)
			(xy 47.624488 -39.045609) (xy 47.586253 -38.974077) (xy 47.555214 -38.899141) (xy 47.531669 -38.821525)
			(xy 47.515846 -38.741974) (xy 47.507896 -38.661255) (xy 1.525016 -38.661255) (xy 1.525016 -39.868828)
			(xy 54.922011 -39.868828) (xy 54.925903 -39.814473) (xy 54.937491 -39.761226) (xy 54.956539 -39.71017)
			(xy 54.98266 -39.662344) (xy 54.99862 -39.640256) (xy 55.012256 -39.621271) (xy 55.032983 -39.57938)
			(xy 55.045703 -39.534406) (xy 55.049986 -39.487865) (xy 55.04569 -39.441324) (xy 55.032957 -39.396354)
			(xy 55.012219 -39.354469) (xy 54.99862 -39.335456) (xy 54.98266 -39.313368) (xy 54.956539 -39.265542)
			(xy 54.937491 -39.214486) (xy 54.925903 -39.161239) (xy 54.922011 -39.106884) (xy 54.925895 -39.052529)
			(xy 54.937475 -38.99928) (xy 54.956516 -38.948221) (xy 54.98263 -38.900391) (xy 55.015285 -38.856765)
			(xy 55.053816 -38.818231) (xy 55.09744 -38.785573) (xy 55.145267 -38.759456) (xy 55.196325 -38.740411)
			(xy 55.249573 -38.728827) (xy 55.303928 -38.724939) (xy 55.358283 -38.728827) (xy 55.411531 -38.740411)
			(xy 55.462589 -38.759456) (xy 55.510416 -38.785573) (xy 55.55404 -38.818231) (xy 55.592571 -38.856765)
			(xy 55.625226 -38.900391) (xy 55.65134 -38.948221) (xy 55.670381 -38.99928) (xy 55.681961 -39.052529)
			(xy 55.685845 -39.106884) (xy 55.681953 -39.161239) (xy 55.670365 -39.214486) (xy 55.651317 -39.265542)
			(xy 55.625196 -39.313368) (xy 55.609236 -39.335456) (xy 55.59568 -39.354495) (xy 55.574941 -39.396371)
			(xy 55.562208 -39.441333) (xy 55.557911 -39.487865) (xy 55.562195 -39.534398) (xy 55.574915 -39.579363)
			(xy 55.595643 -39.621245) (xy 55.609236 -39.640256) (xy 55.625196 -39.662344) (xy 55.651317 -39.71017)
			(xy 55.670365 -39.761226) (xy 55.681953 -39.814473) (xy 55.685845 -39.868828) (xy 57.453883 -39.868828)
			(xy 57.457775 -39.814473) (xy 57.469363 -39.761226) (xy 57.488411 -39.71017) (xy 57.514532 -39.662344)
			(xy 57.530492 -39.640256) (xy 57.544129 -39.621272) (xy 57.564858 -39.579381) (xy 57.57758 -39.534407)
			(xy 57.581864 -39.487865) (xy 57.577567 -39.441324) (xy 57.564833 -39.396353) (xy 57.544092 -39.354468)
			(xy 57.530492 -39.335456) (xy 57.514532 -39.313368) (xy 57.488411 -39.265542) (xy 57.469363 -39.214486)
			(xy 57.457775 -39.161239) (xy 57.453883 -39.106884) (xy 57.457767 -39.052529) (xy 57.469347 -38.99928)
			(xy 57.488388 -38.948221) (xy 57.514502 -38.900391) (xy 57.547157 -38.856765) (xy 57.585688 -38.818231)
			(xy 57.629312 -38.785573) (xy 57.677139 -38.759456) (xy 57.728197 -38.740411) (xy 57.781445 -38.728827)
			(xy 57.8358 -38.724939) (xy 57.890155 -38.728827) (xy 57.943403 -38.740411) (xy 57.994461 -38.759456)
			(xy 58.042288 -38.785573) (xy 58.085912 -38.818231) (xy 58.124443 -38.856765) (xy 58.157098 -38.900391)
			(xy 58.183212 -38.948221) (xy 58.202253 -38.99928) (xy 58.213833 -39.052529) (xy 58.217717 -39.106884)
			(xy 58.213825 -39.161239) (xy 58.202237 -39.214486) (xy 58.183189 -39.265542) (xy 58.157068 -39.313368)
			(xy 58.141108 -39.335456) (xy 58.127553 -39.354496) (xy 58.106816 -39.396372) (xy 58.094085 -39.441333)
			(xy 58.089789 -39.487865) (xy 58.094072 -39.534397) (xy 58.106791 -39.579362) (xy 58.127516 -39.621244)
			(xy 58.141108 -39.640256) (xy 58.157068 -39.662344) (xy 58.183189 -39.71017) (xy 58.202237 -39.761226)
			(xy 58.213825 -39.814473) (xy 58.217717 -39.868828) (xy 60.258297 -39.868828) (xy 60.262189 -39.814473)
			(xy 60.273777 -39.761226) (xy 60.292825 -39.71017) (xy 60.318946 -39.662344) (xy 60.334906 -39.640256)
			(xy 60.348542 -39.621272) (xy 60.369271 -39.579381) (xy 60.381991 -39.534407) (xy 60.386275 -39.487865)
			(xy 60.381978 -39.441324) (xy 60.369245 -39.396353) (xy 60.348505 -39.354468) (xy 60.334906 -39.335456)
			(xy 60.318946 -39.313368) (xy 60.292825 -39.265542) (xy 60.273777 -39.214486) (xy 60.262189 -39.161239)
			(xy 60.258297 -39.106884) (xy 60.262181 -39.052529) (xy 60.273761 -38.99928) (xy 60.292802 -38.948221)
			(xy 60.318916 -38.900391) (xy 60.351571 -38.856765) (xy 60.390102 -38.818231) (xy 60.433726 -38.785573)
			(xy 60.481553 -38.759456) (xy 60.532611 -38.740411) (xy 60.585859 -38.728827) (xy 60.640214 -38.724939)
			(xy 60.694569 -38.728827) (xy 60.747817 -38.740411) (xy 60.798875 -38.759456) (xy 60.846702 -38.785573)
			(xy 60.890326 -38.818231) (xy 60.928857 -38.856765) (xy 60.961512 -38.900391) (xy 60.987626 -38.948221)
			(xy 61.006667 -38.99928) (xy 61.018247 -39.052529) (xy 61.022131 -39.106884) (xy 61.018239 -39.161239)
			(xy 61.006651 -39.214486) (xy 60.987603 -39.265542) (xy 60.961482 -39.313368) (xy 60.945522 -39.335456)
			(xy 60.931966 -39.354495) (xy 60.911228 -39.396371) (xy 60.898497 -39.441333) (xy 60.8942 -39.487865)
			(xy 60.898484 -39.534398) (xy 60.911203 -39.579363) (xy 60.931929 -39.621245) (xy 60.945522 -39.640256)
			(xy 60.961482 -39.662344) (xy 60.987603 -39.71017) (xy 61.006651 -39.761226) (xy 61.018239 -39.814473)
			(xy 61.022131 -39.868828) (xy 62.631165 -39.868828) (xy 62.635057 -39.814473) (xy 62.646645 -39.761226)
			(xy 62.665693 -39.71017) (xy 62.691814 -39.662344) (xy 62.707774 -39.640256) (xy 62.721412 -39.621272)
			(xy 62.742143 -39.579382) (xy 62.754865 -39.534407) (xy 62.75915 -39.487865) (xy 62.754852 -39.441323)
			(xy 62.742117 -39.396352) (xy 62.721375 -39.354468) (xy 62.707774 -39.335456) (xy 62.691814 -39.313368)
			(xy 62.665693 -39.265542) (xy 62.646645 -39.214486) (xy 62.635057 -39.161239) (xy 62.631165 -39.106884)
			(xy 62.635049 -39.052529) (xy 62.646629 -38.99928) (xy 62.66567 -38.948221) (xy 62.691784 -38.900391)
			(xy 62.724439 -38.856765) (xy 62.76297 -38.818231) (xy 62.806594 -38.785573) (xy 62.854421 -38.759456)
			(xy 62.905479 -38.740411) (xy 62.958727 -38.728827) (xy 63.013082 -38.724939) (xy 63.067437 -38.728827)
			(xy 63.120685 -38.740411) (xy 63.171743 -38.759456) (xy 63.21957 -38.785573) (xy 63.263194 -38.818231)
			(xy 63.301725 -38.856765) (xy 63.33438 -38.900391) (xy 63.360494 -38.948221) (xy 63.379535 -38.99928)
			(xy 63.391115 -39.052529) (xy 63.394999 -39.106884) (xy 63.391107 -39.161239) (xy 63.379519 -39.214486)
			(xy 63.360471 -39.265542) (xy 63.33435 -39.313368) (xy 63.31839 -39.335456) (xy 63.304836 -39.354496)
			(xy 63.284101 -39.396372) (xy 63.27137 -39.441334) (xy 63.267074 -39.487865) (xy 63.271357 -39.534397)
			(xy 63.284075 -39.579362) (xy 63.304799 -39.621244) (xy 63.31839 -39.640256) (xy 63.33435 -39.662344)
			(xy 63.360471 -39.71017) (xy 63.379519 -39.761226) (xy 63.391107 -39.814473) (xy 63.394999 -39.868828)
			(xy 64.860777 -39.868828) (xy 64.864669 -39.814473) (xy 64.876257 -39.761226) (xy 64.895305 -39.71017)
			(xy 64.921426 -39.662344) (xy 64.937386 -39.640256) (xy 64.951023 -39.621272) (xy 64.971753 -39.579382)
			(xy 64.984475 -39.534407) (xy 64.988759 -39.487865) (xy 64.984462 -39.441324) (xy 64.971728 -39.396353)
			(xy 64.950986 -39.354468) (xy 64.937386 -39.335456) (xy 64.921426 -39.313368) (xy 64.895305 -39.265542)
			(xy 64.876257 -39.214486) (xy 64.864669 -39.161239) (xy 64.860777 -39.106884) (xy 64.864661 -39.052529)
			(xy 64.876241 -38.99928) (xy 64.895282 -38.948221) (xy 64.921396 -38.900391) (xy 64.954051 -38.856765)
			(xy 64.992582 -38.818231) (xy 65.036206 -38.785573) (xy 65.084033 -38.759456) (xy 65.135091 -38.740411)
			(xy 65.188339 -38.728827) (xy 65.242694 -38.724939) (xy 65.297049 -38.728827) (xy 65.350297 -38.740411)
			(xy 65.401355 -38.759456) (xy 65.449182 -38.785573) (xy 65.492806 -38.818231) (xy 65.531337 -38.856765)
			(xy 65.563992 -38.900391) (xy 65.590106 -38.948221) (xy 65.609147 -38.99928) (xy 65.620727 -39.052529)
			(xy 65.624611 -39.106884) (xy 65.620719 -39.161239) (xy 65.609131 -39.214486) (xy 65.590083 -39.265542)
			(xy 65.563962 -39.313368) (xy 65.548002 -39.335456) (xy 65.534447 -39.354496) (xy 65.513711 -39.396372)
			(xy 65.50098 -39.441334) (xy 65.496684 -39.487865) (xy 65.500967 -39.534397) (xy 65.513686 -39.579362)
			(xy 65.53441 -39.621244) (xy 65.548002 -39.640256) (xy 65.563962 -39.662344) (xy 65.590083 -39.71017)
			(xy 65.609131 -39.761226) (xy 65.620719 -39.814473) (xy 65.624611 -39.868828) (xy 65.620727 -39.923183)
			(xy 65.609147 -39.976432) (xy 65.590106 -40.027491) (xy 65.563992 -40.075321) (xy 65.531337 -40.118947)
			(xy 65.492806 -40.157481) (xy 65.449182 -40.190139) (xy 65.401355 -40.216256) (xy 65.350297 -40.235301)
			(xy 65.297049 -40.246885) (xy 65.242694 -40.250773) (xy 65.188339 -40.246885) (xy 65.135091 -40.235301)
			(xy 65.084033 -40.216256) (xy 65.036206 -40.190139) (xy 64.992582 -40.157481) (xy 64.954051 -40.118947)
			(xy 64.921396 -40.075321) (xy 64.895282 -40.027491) (xy 64.876241 -39.976432) (xy 64.864661 -39.923183)
			(xy 64.860777 -39.868828) (xy 63.394999 -39.868828) (xy 63.391115 -39.923183) (xy 63.379535 -39.976432)
			(xy 63.360494 -40.027491) (xy 63.33438 -40.075321) (xy 63.301725 -40.118947) (xy 63.263194 -40.157481)
			(xy 63.21957 -40.190139) (xy 63.171743 -40.216256) (xy 63.120685 -40.235301) (xy 63.067437 -40.246885)
			(xy 63.013082 -40.250773) (xy 62.958727 -40.246885) (xy 62.905479 -40.235301) (xy 62.854421 -40.216256)
			(xy 62.806594 -40.190139) (xy 62.76297 -40.157481) (xy 62.724439 -40.118947) (xy 62.691784 -40.075321)
			(xy 62.66567 -40.027491) (xy 62.646629 -39.976432) (xy 62.635049 -39.923183) (xy 62.631165 -39.868828)
			(xy 61.022131 -39.868828) (xy 61.018247 -39.923183) (xy 61.006667 -39.976432) (xy 60.987626 -40.027491)
			(xy 60.961512 -40.075321) (xy 60.928857 -40.118947) (xy 60.890326 -40.157481) (xy 60.846702 -40.190139)
			(xy 60.798875 -40.216256) (xy 60.747817 -40.235301) (xy 60.694569 -40.246885) (xy 60.640214 -40.250773)
			(xy 60.585859 -40.246885) (xy 60.532611 -40.235301) (xy 60.481553 -40.216256) (xy 60.433726 -40.190139)
			(xy 60.390102 -40.157481) (xy 60.351571 -40.118947) (xy 60.318916 -40.075321) (xy 60.292802 -40.027491)
			(xy 60.273761 -39.976432) (xy 60.262181 -39.923183) (xy 60.258297 -39.868828) (xy 58.217717 -39.868828)
			(xy 58.213833 -39.923183) (xy 58.202253 -39.976432) (xy 58.183212 -40.027491) (xy 58.157098 -40.075321)
			(xy 58.124443 -40.118947) (xy 58.085912 -40.157481) (xy 58.042288 -40.190139) (xy 57.994461 -40.216256)
			(xy 57.943403 -40.235301) (xy 57.890155 -40.246885) (xy 57.8358 -40.250773) (xy 57.781445 -40.246885)
			(xy 57.728197 -40.235301) (xy 57.677139 -40.216256) (xy 57.629312 -40.190139) (xy 57.585688 -40.157481)
			(xy 57.547157 -40.118947) (xy 57.514502 -40.075321) (xy 57.488388 -40.027491) (xy 57.469347 -39.976432)
			(xy 57.457767 -39.923183) (xy 57.453883 -39.868828) (xy 55.685845 -39.868828) (xy 55.681961 -39.923183)
			(xy 55.670381 -39.976432) (xy 55.65134 -40.027491) (xy 55.625226 -40.075321) (xy 55.592571 -40.118947)
			(xy 55.55404 -40.157481) (xy 55.510416 -40.190139) (xy 55.462589 -40.216256) (xy 55.411531 -40.235301)
			(xy 55.358283 -40.246885) (xy 55.303928 -40.250773) (xy 55.249573 -40.246885) (xy 55.196325 -40.235301)
			(xy 55.145267 -40.216256) (xy 55.09744 -40.190139) (xy 55.053816 -40.157481) (xy 55.015285 -40.118947)
			(xy 54.98263 -40.075321) (xy 54.956516 -40.027491) (xy 54.937475 -39.976432) (xy 54.925895 -39.923183)
			(xy 54.922011 -39.868828) (xy 1.525016 -39.868828) (xy 1.525016 -42.291) (xy 5.5306 -42.291) (xy 5.534631 -42.161434)
			(xy 5.54671 -42.03237) (xy 5.566789 -41.904306) (xy 5.594791 -41.777739) (xy 5.630608 -41.653156)
			(xy 5.6741 -41.531042) (xy 5.7251 -41.411868) (xy 5.783411 -41.296095) (xy 5.848806 -41.184171) (xy 5.921033 -41.076529)
			(xy 5.999813 -40.973586) (xy 6.08484 -40.87574) (xy 6.175785 -40.783368) (xy 6.272297 -40.69683)
			(xy 6.374003 -40.616459) (xy 6.480509 -40.542567) (xy 6.591402 -40.475439) (xy 6.706254 -40.415335)
			(xy 6.824621 -40.362488) (xy 6.946044 -40.317101) (xy 7.070054 -40.279352) (xy 7.196171 -40.249385)
			(xy 7.323907 -40.227316) (xy 7.452768 -40.213232) (xy 7.582255 -40.207186) (xy 7.711868 -40.209202)
			(xy 7.841104 -40.219272) (xy 7.969465 -40.237357) (xy 8.096453 -40.263387) (xy 8.221577 -40.297262)
			(xy 8.344353 -40.33885) (xy 8.464306 -40.387991) (xy 8.580971 -40.444494) (xy 8.693899 -40.508141)
			(xy 8.802651 -40.578685) (xy 8.906807 -40.655854) (xy 9.005964 -40.739349) (xy 9.099738 -40.828847)
			(xy 9.187767 -40.924002) (xy 9.26971 -41.024445) (xy 9.345249 -41.129788) (xy 9.414094 -41.239624)
			(xy 9.475977 -41.353528) (xy 9.530658 -41.471058) (xy 9.577928 -41.591761) (xy 9.617601 -41.715169)
			(xy 9.647223 -41.83174) (xy 54.922011 -41.83174) (xy 54.925903 -41.777385) (xy 54.937491 -41.724138)
			(xy 54.956539 -41.673082) (xy 54.98266 -41.625256) (xy 54.99862 -41.603168) (xy 55.012244 -41.584176)
			(xy 55.032973 -41.542287) (xy 55.045694 -41.497314) (xy 55.049979 -41.450774) (xy 55.045684 -41.404235)
			(xy 55.032954 -41.359265) (xy 55.012217 -41.317381) (xy 54.99862 -41.298368) (xy 54.98266 -41.27628)
			(xy 54.956539 -41.228454) (xy 54.937491 -41.177398) (xy 54.925903 -41.124151) (xy 54.922011 -41.069796)
			(xy 54.925895 -41.015441) (xy 54.937475 -40.962192) (xy 54.956516 -40.911133) (xy 54.98263 -40.863303)
			(xy 55.015285 -40.819677) (xy 55.053816 -40.781143) (xy 55.09744 -40.748485) (xy 55.145267 -40.722368)
			(xy 55.196325 -40.703323) (xy 55.249573 -40.691739) (xy 55.303928 -40.687851) (xy 55.358283 -40.691739)
			(xy 55.411531 -40.703323) (xy 55.462589 -40.722368) (xy 55.510416 -40.748485) (xy 55.55404 -40.781143)
			(xy 55.592571 -40.819677) (xy 55.625226 -40.863303) (xy 55.65134 -40.911133) (xy 55.670381 -40.962192)
			(xy 55.681961 -41.015441) (xy 55.685845 -41.069796) (xy 55.681953 -41.124151) (xy 55.670365 -41.177398)
			(xy 55.651317 -41.228454) (xy 55.625196 -41.27628) (xy 55.609236 -41.298368) (xy 55.595669 -41.3174)
			(xy 55.57493 -41.359277) (xy 55.562199 -41.404241) (xy 55.557904 -41.450774) (xy 55.56219 -41.497309)
			(xy 55.574912 -41.542275) (xy 55.595642 -41.584157) (xy 55.609236 -41.603168) (xy 55.625196 -41.625256)
			(xy 55.651317 -41.673082) (xy 55.670365 -41.724138) (xy 55.681953 -41.777385) (xy 55.685845 -41.83174)
			(xy 57.453883 -41.83174) (xy 57.457775 -41.777385) (xy 57.469363 -41.724138) (xy 57.488411 -41.673082)
			(xy 57.514532 -41.625256) (xy 57.530492 -41.603168) (xy 57.544118 -41.584176) (xy 57.564848 -41.542288)
			(xy 57.577571 -41.497315) (xy 57.581857 -41.450774) (xy 57.577562 -41.404234) (xy 57.56483 -41.359264)
			(xy 57.544091 -41.31738) (xy 57.530492 -41.298368) (xy 57.514532 -41.27628) (xy 57.488411 -41.228454)
			(xy 57.469363 -41.177398) (xy 57.457775 -41.124151) (xy 57.453883 -41.069796) (xy 57.457767 -41.015441)
			(xy 57.469347 -40.962192) (xy 57.488388 -40.911133) (xy 57.514502 -40.863303) (xy 57.547157 -40.819677)
			(xy 57.585688 -40.781143) (xy 57.629312 -40.748485) (xy 57.677139 -40.722368) (xy 57.728197 -40.703323)
			(xy 57.781445 -40.691739) (xy 57.8358 -40.687851) (xy 57.890155 -40.691739) (xy 57.943403 -40.703323)
			(xy 57.994461 -40.722368) (xy 58.042288 -40.748485) (xy 58.085912 -40.781143) (xy 58.124443 -40.819677)
			(xy 58.157098 -40.863303) (xy 58.183212 -40.911133) (xy 58.202253 -40.962192) (xy 58.213833 -41.015441)
			(xy 58.217717 -41.069796) (xy 58.213825 -41.124151) (xy 58.202237 -41.177398) (xy 58.183189 -41.228454)
			(xy 58.157068 -41.27628) (xy 58.141108 -41.298368) (xy 58.127542 -41.3174) (xy 58.106806 -41.359278)
			(xy 58.094076 -41.404242) (xy 58.089782 -41.450774) (xy 58.094067 -41.497308) (xy 58.106788 -41.542274)
			(xy 58.127515 -41.584156) (xy 58.141108 -41.603168) (xy 58.157068 -41.625256) (xy 58.183189 -41.673082)
			(xy 58.202237 -41.724138) (xy 58.213825 -41.777385) (xy 58.217717 -41.83174) (xy 60.258297 -41.83174)
			(xy 60.262189 -41.777385) (xy 60.273777 -41.724138) (xy 60.292825 -41.673082) (xy 60.318946 -41.625256)
			(xy 60.334906 -41.603168) (xy 60.348531 -41.584176) (xy 60.36926 -41.542287) (xy 60.381982 -41.497315)
			(xy 60.386268 -41.450774) (xy 60.381973 -41.404235) (xy 60.369242 -41.359265) (xy 60.348504 -41.31738)
			(xy 60.334906 -41.298368) (xy 60.318946 -41.27628) (xy 60.292825 -41.228454) (xy 60.273777 -41.177398)
			(xy 60.262189 -41.124151) (xy 60.258297 -41.069796) (xy 60.262181 -41.015441) (xy 60.273761 -40.962192)
			(xy 60.292802 -40.911133) (xy 60.318916 -40.863303) (xy 60.351571 -40.819677) (xy 60.390102 -40.781143)
			(xy 60.433726 -40.748485) (xy 60.481553 -40.722368) (xy 60.532611 -40.703323) (xy 60.585859 -40.691739)
			(xy 60.640214 -40.687851) (xy 60.694569 -40.691739) (xy 60.747817 -40.703323) (xy 60.798875 -40.722368)
			(xy 60.846702 -40.748485) (xy 60.890326 -40.781143) (xy 60.928857 -40.819677) (xy 60.961512 -40.863303)
			(xy 60.987626 -40.911133) (xy 61.006667 -40.962192) (xy 61.018247 -41.015441) (xy 61.022131 -41.069796)
			(xy 61.018239 -41.124151) (xy 61.006651 -41.177398) (xy 60.987603 -41.228454) (xy 60.961482 -41.27628)
			(xy 60.945522 -41.298368) (xy 60.931955 -41.3174) (xy 60.911218 -41.359278) (xy 60.898488 -41.404241)
			(xy 60.894193 -41.450774) (xy 60.898478 -41.497308) (xy 60.9112 -41.542274) (xy 60.931928 -41.584156)
			(xy 60.945522 -41.603168) (xy 60.961482 -41.625256) (xy 60.987603 -41.673082) (xy 61.006651 -41.724138)
			(xy 61.018239 -41.777385) (xy 61.022131 -41.83174) (xy 62.631165 -41.83174) (xy 62.635057 -41.777385)
			(xy 62.646645 -41.724138) (xy 62.665693 -41.673082) (xy 62.691814 -41.625256) (xy 62.707774 -41.603168)
			(xy 62.721401 -41.584177) (xy 62.742133 -41.542288) (xy 62.754856 -41.497315) (xy 62.759142 -41.450774)
			(xy 62.754847 -41.404234) (xy 62.742114 -41.359264) (xy 62.721374 -41.31738) (xy 62.707774 -41.298368)
			(xy 62.691814 -41.27628) (xy 62.665693 -41.228454) (xy 62.646645 -41.177398) (xy 62.635057 -41.124151)
			(xy 62.631165 -41.069796) (xy 62.635049 -41.015441) (xy 62.646629 -40.962192) (xy 62.66567 -40.911133)
			(xy 62.691784 -40.863303) (xy 62.724439 -40.819677) (xy 62.76297 -40.781143) (xy 62.806594 -40.748485)
			(xy 62.854421 -40.722368) (xy 62.905479 -40.703323) (xy 62.958727 -40.691739) (xy 63.013082 -40.687851)
			(xy 63.067437 -40.691739) (xy 63.120685 -40.703323) (xy 63.171743 -40.722368) (xy 63.21957 -40.748485)
			(xy 63.263194 -40.781143) (xy 63.301725 -40.819677) (xy 63.33438 -40.863303) (xy 63.360494 -40.911133)
			(xy 63.379535 -40.962192) (xy 63.391115 -41.015441) (xy 63.394999 -41.069796) (xy 63.391107 -41.124151)
			(xy 63.379519 -41.177398) (xy 63.360471 -41.228454) (xy 63.33435 -41.27628) (xy 63.31839 -41.298368)
			(xy 63.304825 -41.3174) (xy 63.28409 -41.359279) (xy 63.271362 -41.404242) (xy 63.267067 -41.450774)
			(xy 63.271352 -41.497308) (xy 63.284072 -41.542273) (xy 63.304798 -41.584156) (xy 63.31839 -41.603168)
			(xy 63.33435 -41.625256) (xy 63.360471 -41.673082) (xy 63.379519 -41.724138) (xy 63.391107 -41.777385)
			(xy 63.394999 -41.83174) (xy 64.860777 -41.83174) (xy 64.864669 -41.777385) (xy 64.876257 -41.724138)
			(xy 64.895305 -41.673082) (xy 64.921426 -41.625256) (xy 64.937386 -41.603168) (xy 64.951012 -41.584176)
			(xy 64.971743 -41.542288) (xy 64.984466 -41.497315) (xy 64.988752 -41.450774) (xy 64.984457 -41.404234)
			(xy 64.971725 -41.359264) (xy 64.950985 -41.31738) (xy 64.937386 -41.298368) (xy 64.921426 -41.27628)
			(xy 64.895305 -41.228454) (xy 64.876257 -41.177398) (xy 64.864669 -41.124151) (xy 64.860777 -41.069796)
			(xy 64.864661 -41.015441) (xy 64.876241 -40.962192) (xy 64.895282 -40.911133) (xy 64.921396 -40.863303)
			(xy 64.954051 -40.819677) (xy 64.992582 -40.781143) (xy 65.036206 -40.748485) (xy 65.084033 -40.722368)
			(xy 65.135091 -40.703323) (xy 65.188339 -40.691739) (xy 65.242694 -40.687851) (xy 65.297049 -40.691739)
			(xy 65.350297 -40.703323) (xy 65.401355 -40.722368) (xy 65.449182 -40.748485) (xy 65.492806 -40.781143)
			(xy 65.531337 -40.819677) (xy 65.563992 -40.863303) (xy 65.590106 -40.911133) (xy 65.609147 -40.962192)
			(xy 65.620727 -41.015441) (xy 65.624611 -41.069796) (xy 65.620719 -41.124151) (xy 65.609131 -41.177398)
			(xy 65.590083 -41.228454) (xy 65.563962 -41.27628) (xy 65.548002 -41.298368) (xy 65.534436 -41.3174)
			(xy 65.513701 -41.359278) (xy 65.500971 -41.404242) (xy 65.496677 -41.450774) (xy 65.500962 -41.497308)
			(xy 65.513682 -41.542274) (xy 65.534409 -41.584156) (xy 65.548002 -41.603168) (xy 65.563962 -41.625256)
			(xy 65.590083 -41.673082) (xy 65.609131 -41.724138) (xy 65.620719 -41.777385) (xy 65.624611 -41.83174)
			(xy 65.620727 -41.886095) (xy 65.609147 -41.939344) (xy 65.590106 -41.990403) (xy 65.563992 -42.038233)
			(xy 65.531337 -42.081859) (xy 65.492806 -42.120393) (xy 65.449182 -42.153051) (xy 65.401355 -42.179168)
			(xy 65.350297 -42.198213) (xy 65.297049 -42.209797) (xy 65.242694 -42.213685) (xy 65.188339 -42.209797)
			(xy 65.135091 -42.198213) (xy 65.084033 -42.179168) (xy 65.036206 -42.153051) (xy 64.992582 -42.120393)
			(xy 64.954051 -42.081859) (xy 64.921396 -42.038233) (xy 64.895282 -41.990403) (xy 64.876241 -41.939344)
			(xy 64.864661 -41.886095) (xy 64.860777 -41.83174) (xy 63.394999 -41.83174) (xy 63.391115 -41.886095)
			(xy 63.379535 -41.939344) (xy 63.360494 -41.990403) (xy 63.33438 -42.038233) (xy 63.301725 -42.081859)
			(xy 63.263194 -42.120393) (xy 63.21957 -42.153051) (xy 63.171743 -42.179168) (xy 63.120685 -42.198213)
			(xy 63.067437 -42.209797) (xy 63.013082 -42.213685) (xy 62.958727 -42.209797) (xy 62.905479 -42.198213)
			(xy 62.854421 -42.179168) (xy 62.806594 -42.153051) (xy 62.76297 -42.120393) (xy 62.724439 -42.081859)
			(xy 62.691784 -42.038233) (xy 62.66567 -41.990403) (xy 62.646629 -41.939344) (xy 62.635049 -41.886095)
			(xy 62.631165 -41.83174) (xy 61.022131 -41.83174) (xy 61.018247 -41.886095) (xy 61.006667 -41.939344)
			(xy 60.987626 -41.990403) (xy 60.961512 -42.038233) (xy 60.928857 -42.081859) (xy 60.890326 -42.120393)
			(xy 60.846702 -42.153051) (xy 60.798875 -42.179168) (xy 60.747817 -42.198213) (xy 60.694569 -42.209797)
			(xy 60.640214 -42.213685) (xy 60.585859 -42.209797) (xy 60.532611 -42.198213) (xy 60.481553 -42.179168)
			(xy 60.433726 -42.153051) (xy 60.390102 -42.120393) (xy 60.351571 -42.081859) (xy 60.318916 -42.038233)
			(xy 60.292802 -41.990403) (xy 60.273761 -41.939344) (xy 60.262181 -41.886095) (xy 60.258297 -41.83174)
			(xy 58.217717 -41.83174) (xy 58.213833 -41.886095) (xy 58.202253 -41.939344) (xy 58.183212 -41.990403)
			(xy 58.157098 -42.038233) (xy 58.124443 -42.081859) (xy 58.085912 -42.120393) (xy 58.042288 -42.153051)
			(xy 57.994461 -42.179168) (xy 57.943403 -42.198213) (xy 57.890155 -42.209797) (xy 57.8358 -42.213685)
			(xy 57.781445 -42.209797) (xy 57.728197 -42.198213) (xy 57.677139 -42.179168) (xy 57.629312 -42.153051)
			(xy 57.585688 -42.120393) (xy 57.547157 -42.081859) (xy 57.514502 -42.038233) (xy 57.488388 -41.990403)
			(xy 57.469347 -41.939344) (xy 57.457767 -41.886095) (xy 57.453883 -41.83174) (xy 55.685845 -41.83174)
			(xy 55.681961 -41.886095) (xy 55.670381 -41.939344) (xy 55.65134 -41.990403) (xy 55.625226 -42.038233)
			(xy 55.592571 -42.081859) (xy 55.55404 -42.120393) (xy 55.510416 -42.153051) (xy 55.462589 -42.179168)
			(xy 55.411531 -42.198213) (xy 55.358283 -42.209797) (xy 55.303928 -42.213685) (xy 55.249573 -42.209797)
			(xy 55.196325 -42.198213) (xy 55.145267 -42.179168) (xy 55.09744 -42.153051) (xy 55.053816 -42.120393)
			(xy 55.015285 -42.081859) (xy 54.98263 -42.038233) (xy 54.956516 -41.990403) (xy 54.937475 -41.939344)
			(xy 54.925895 -41.886095) (xy 54.922011 -41.83174) (xy 9.647223 -41.83174) (xy 9.649526 -41.840805)
			(xy 9.673578 -41.968182) (xy 9.689665 -42.096808) (xy 9.697724 -42.226186) (xy 9.698228 -42.291)
			(xy 9.697724 -42.355814) (xy 9.689665 -42.485192) (xy 9.673578 -42.613818) (xy 9.649526 -42.741195)
			(xy 9.617601 -42.866831) (xy 9.577928 -42.990239) (xy 9.530658 -43.110942) (xy 9.475977 -43.228472)
			(xy 9.414094 -43.342376) (xy 9.345249 -43.452212) (xy 9.26971 -43.557555) (xy 9.187767 -43.657998)
			(xy 9.099738 -43.753153) (xy 9.005964 -43.842651) (xy 8.906807 -43.926146) (xy 8.802651 -44.003315)
			(xy 8.693899 -44.073859) (xy 8.580971 -44.137506) (xy 8.464306 -44.194009) (xy 8.344353 -44.24315)
			(xy 8.221577 -44.284738) (xy 8.096453 -44.318613) (xy 7.969465 -44.344643) (xy 7.841104 -44.362728)
			(xy 7.711868 -44.372798) (xy 7.582255 -44.374814) (xy 7.452768 -44.368768) (xy 7.323907 -44.354684)
			(xy 7.196171 -44.332615) (xy 7.070054 -44.302648) (xy 6.946044 -44.264899) (xy 6.824621 -44.219512)
			(xy 6.706254 -44.166665) (xy 6.591402 -44.106561) (xy 6.480509 -44.039433) (xy 6.374003 -43.965541)
			(xy 6.272297 -43.88517) (xy 6.175785 -43.798632) (xy 6.08484 -43.70626) (xy 5.999813 -43.608414)
			(xy 5.921033 -43.505471) (xy 5.848806 -43.397829) (xy 5.783411 -43.285905) (xy 5.7251 -43.170132)
			(xy 5.6741 -43.050958) (xy 5.630608 -42.928844) (xy 5.594791 -42.804261) (xy 5.566789 -42.677694)
			(xy 5.54671 -42.54963) (xy 5.534631 -42.420566) (xy 5.5306 -42.291) (xy 1.525016 -42.291) (xy 1.525016 -53.721)
			(xy 5.5306 -53.721) (xy 5.534631 -53.591434) (xy 5.54671 -53.46237) (xy 5.566789 -53.334306) (xy 5.594791 -53.207739)
			(xy 5.630608 -53.083156) (xy 5.6741 -52.961042) (xy 5.7251 -52.841868) (xy 5.783411 -52.726095) (xy 5.848806 -52.614171)
			(xy 5.921033 -52.506529) (xy 5.999813 -52.403586) (xy 6.08484 -52.30574) (xy 6.175785 -52.213368)
			(xy 6.272297 -52.12683) (xy 6.374003 -52.046459) (xy 6.480509 -51.972567) (xy 6.591402 -51.905439)
			(xy 6.706254 -51.845335) (xy 6.824621 -51.792488) (xy 6.946044 -51.747101) (xy 7.070054 -51.709352)
			(xy 7.196171 -51.679385) (xy 7.323907 -51.657316) (xy 7.452768 -51.643232) (xy 7.582255 -51.637186)
			(xy 7.711868 -51.639202) (xy 7.841104 -51.649272) (xy 7.969465 -51.667357) (xy 8.096453 -51.693387)
			(xy 8.221577 -51.727262) (xy 8.344353 -51.76885) (xy 8.464306 -51.817991) (xy 8.580971 -51.874494)
			(xy 8.693899 -51.938141) (xy 8.802651 -52.008685) (xy 8.906807 -52.085854) (xy 9.005964 -52.169349)
			(xy 9.099738 -52.258847) (xy 9.187767 -52.354002) (xy 9.26971 -52.454445) (xy 9.345249 -52.559788)
			(xy 9.414094 -52.669624) (xy 9.475977 -52.783528) (xy 9.530658 -52.901058) (xy 9.577928 -53.021761)
			(xy 9.617601 -53.145169) (xy 9.649526 -53.270805) (xy 9.673578 -53.398182) (xy 9.689665 -53.526808)
			(xy 9.697724 -53.656186) (xy 9.698228 -53.721) (xy 9.697724 -53.785814) (xy 9.689665 -53.915192)
			(xy 9.673578 -54.043818) (xy 9.649526 -54.171195) (xy 9.617601 -54.296831) (xy 9.577928 -54.420239)
			(xy 9.530658 -54.540942) (xy 9.475977 -54.658472) (xy 9.414094 -54.772376) (xy 9.345249 -54.882212)
			(xy 9.26971 -54.987555) (xy 9.187767 -55.087998) (xy 9.099738 -55.183153) (xy 9.005964 -55.272651)
			(xy 8.906807 -55.356146) (xy 8.802651 -55.433315) (xy 8.693899 -55.503859) (xy 8.580971 -55.567506)
			(xy 8.464306 -55.624009) (xy 8.344353 -55.67315) (xy 8.221577 -55.714738) (xy 8.096453 -55.748613)
			(xy 7.969465 -55.774643) (xy 7.841104 -55.792728) (xy 7.711868 -55.802798) (xy 7.582255 -55.804814)
			(xy 7.452768 -55.798768) (xy 7.323907 -55.784684) (xy 7.196171 -55.762615) (xy 7.070054 -55.732648)
			(xy 6.946044 -55.694899) (xy 6.824621 -55.649512) (xy 6.706254 -55.596665) (xy 6.591402 -55.536561)
			(xy 6.480509 -55.469433) (xy 6.374003 -55.395541) (xy 6.272297 -55.31517) (xy 6.175785 -55.228632)
			(xy 6.08484 -55.13626) (xy 5.999813 -55.038414) (xy 5.921033 -54.935471) (xy 5.848806 -54.827829)
			(xy 5.783411 -54.715905) (xy 5.7251 -54.600132) (xy 5.6741 -54.480958) (xy 5.630608 -54.358844) (xy 5.594791 -54.234261)
			(xy 5.566789 -54.107694) (xy 5.54671 -53.97963) (xy 5.534631 -53.850566) (xy 5.5306 -53.721) (xy 1.525016 -53.721)
			(xy 1.525016 -60.833) (xy 5.5306 -60.833) (xy 5.534631 -60.703434) (xy 5.54671 -60.57437) (xy 5.566789 -60.446306)
			(xy 5.594791 -60.319739) (xy 5.630608 -60.195156) (xy 5.6741 -60.073042) (xy 5.7251 -59.953868) (xy 5.783411 -59.838095)
			(xy 5.848806 -59.726171) (xy 5.921033 -59.618529) (xy 5.999813 -59.515586) (xy 6.08484 -59.41774)
			(xy 6.175785 -59.325368) (xy 6.272297 -59.23883) (xy 6.374003 -59.158459) (xy 6.480509 -59.084567)
			(xy 6.591402 -59.017439) (xy 6.706254 -58.957335) (xy 6.824621 -58.904488) (xy 6.946044 -58.859101)
			(xy 7.070054 -58.821352) (xy 7.196171 -58.791385) (xy 7.323907 -58.769316) (xy 7.452768 -58.755232)
			(xy 7.582255 -58.749186) (xy 7.711868 -58.751202) (xy 7.841104 -58.761272) (xy 7.969465 -58.779357)
			(xy 8.096453 -58.805387) (xy 8.221577 -58.839262) (xy 8.344353 -58.88085) (xy 8.464306 -58.929991)
			(xy 8.580971 -58.986494) (xy 8.693899 -59.050141) (xy 8.802651 -59.120685) (xy 8.906807 -59.197854)
			(xy 9.005964 -59.281349) (xy 9.099738 -59.370847) (xy 9.187767 -59.466002) (xy 9.26971 -59.566445)
			(xy 9.345249 -59.671788) (xy 9.414094 -59.781624) (xy 9.475977 -59.895528) (xy 9.530658 -60.013058)
			(xy 9.577928 -60.133761) (xy 9.617601 -60.257169) (xy 9.649526 -60.382805) (xy 9.673578 -60.510182)
			(xy 9.689665 -60.638808) (xy 9.697724 -60.768186) (xy 9.698228 -60.833) (xy 9.697724 -60.897814)
			(xy 9.689665 -61.027192) (xy 9.673578 -61.155818) (xy 9.649526 -61.283195) (xy 9.617601 -61.408831)
			(xy 9.577928 -61.532239) (xy 9.530658 -61.652942) (xy 9.475977 -61.770472) (xy 9.414094 -61.884376)
			(xy 9.345249 -61.994212) (xy 9.26971 -62.099555) (xy 9.187767 -62.199998) (xy 9.099738 -62.295153)
			(xy 9.005964 -62.384651) (xy 8.906807 -62.468146) (xy 8.802651 -62.545315) (xy 8.693899 -62.615859)
			(xy 8.580971 -62.679506) (xy 8.464306 -62.736009) (xy 8.344353 -62.78515) (xy 8.221577 -62.826738)
			(xy 8.096453 -62.860613) (xy 7.969465 -62.886643) (xy 7.841104 -62.904728) (xy 7.711868 -62.914798)
			(xy 7.582255 -62.916814) (xy 7.452768 -62.910768) (xy 7.323907 -62.896684) (xy 7.196171 -62.874615)
			(xy 7.070054 -62.844648) (xy 6.946044 -62.806899) (xy 6.824621 -62.761512) (xy 6.706254 -62.708665)
			(xy 6.591402 -62.648561) (xy 6.480509 -62.581433) (xy 6.374003 -62.507541) (xy 6.272297 -62.42717)
			(xy 6.175785 -62.340632) (xy 6.08484 -62.24826) (xy 5.999813 -62.150414) (xy 5.921033 -62.047471)
			(xy 5.848806 -61.939829) (xy 5.783411 -61.827905) (xy 5.7251 -61.712132) (xy 5.6741 -61.592958) (xy 5.630608 -61.470844)
			(xy 5.594791 -61.346261) (xy 5.566789 -61.219694) (xy 5.54671 -61.09163) (xy 5.534631 -60.962566)
			(xy 5.5306 -60.833) (xy 1.525016 -60.833) (xy 1.525016 -83.519709) (xy 4.782807 -83.519709) (xy 4.782807 -83.433983)
			(xy 4.790717 -83.348623) (xy 4.806469 -83.264356) (xy 4.829929 -83.181903) (xy 4.860897 -83.101966)
			(xy 4.899108 -83.025227) (xy 4.944237 -82.952341) (xy 4.995898 -82.88393) (xy 5.053652 -82.820578)
			(xy 5.117004 -82.762824) (xy 5.185415 -82.711163) (xy 5.258301 -82.666034) (xy 5.33504 -82.627823)
			(xy 5.414977 -82.596855) (xy 5.49743 -82.573395) (xy 5.581697 -82.557643) (xy 5.667057 -82.549733)
			(xy 5.752783 -82.549733) (xy 5.838143 -82.557643) (xy 5.92241 -82.573395) (xy 6.004863 -82.596855)
			(xy 6.0848 -82.627823) (xy 6.161539 -82.666034) (xy 6.234425 -82.711163) (xy 6.302836 -82.762824)
			(xy 6.366188 -82.820578) (xy 6.423942 -82.88393) (xy 6.475603 -82.952341) (xy 6.520732 -83.025227)
			(xy 6.558943 -83.101966) (xy 6.589911 -83.181903) (xy 6.613371 -83.264356) (xy 6.629123 -83.348623)
			(xy 6.637033 -83.433983) (xy 6.637528 -83.476846) (xy 6.637033 -83.519709) (xy 6.629123 -83.605069)
			(xy 6.613371 -83.689336) (xy 6.589911 -83.771789) (xy 6.558943 -83.851726) (xy 6.520732 -83.928465)
			(xy 6.475603 -84.001351) (xy 6.423942 -84.069762) (xy 6.366188 -84.133114) (xy 6.302836 -84.190868)
			(xy 6.234425 -84.242529) (xy 6.161539 -84.287658) (xy 6.0848 -84.325869) (xy 6.004863 -84.356837)
			(xy 5.92241 -84.380297) (xy 5.838143 -84.396049) (xy 5.752783 -84.403959) (xy 5.667057 -84.403959)
			(xy 5.581697 -84.396049) (xy 5.49743 -84.380297) (xy 5.414977 -84.356837) (xy 5.33504 -84.325869)
			(xy 5.258301 -84.287658) (xy 5.185415 -84.242529) (xy 5.117004 -84.190868) (xy 5.053652 -84.133114)
			(xy 4.995898 -84.069762) (xy 4.944237 -84.001351) (xy 4.899108 -83.928465) (xy 4.860897 -83.851726)
			(xy 4.829929 -83.771789) (xy 4.806469 -83.689336) (xy 4.790717 -83.605069) (xy 4.782807 -83.519709)
			(xy 1.525016 -83.519709) (xy 1.525016 -130.137971) (xy 2.787139 -130.137971) (xy 2.787139 -130.058105)
			(xy 2.795219 -129.97865) (xy 2.811296 -129.90042) (xy 2.835205 -129.824218) (xy 2.8667 -129.750825)
			(xy 2.905459 -129.680995) (xy 2.951083 -129.615445) (xy 3.003105 -129.554846) (xy 3.06099 -129.499822)
			(xy 3.124146 -129.450936) (xy 3.191923 -129.40869) (xy 3.263626 -129.373518) (xy 3.33852 -129.345781)
			(xy 3.415835 -129.325762) (xy 3.494779 -129.313669) (xy 3.574542 -129.309624) (xy 3.654305 -129.313669)
			(xy 3.733249 -129.325762) (xy 3.810564 -129.345781) (xy 3.885458 -129.373518) (xy 3.957161 -129.40869)
			(xy 4.024938 -129.450936) (xy 4.088094 -129.499822) (xy 4.145979 -129.554846) (xy 4.198001 -129.615445)
			(xy 4.243625 -129.680995) (xy 4.282384 -129.750825) (xy 4.313879 -129.824218) (xy 4.337788 -129.90042)
			(xy 4.353865 -129.97865) (xy 4.361945 -130.058105) (xy 4.36245 -130.098038) (xy 4.361945 -130.137971)
			(xy 4.353865 -130.217426) (xy 4.337788 -130.295656) (xy 4.313879 -130.371858) (xy 4.282384 -130.445251)
			(xy 4.243625 -130.515081) (xy 4.198001 -130.580631) (xy 4.145979 -130.64123) (xy 4.088094 -130.696254)
			(xy 4.024938 -130.74514) (xy 4.023449 -130.746068) (xy 5.677649 -130.746068) (xy 5.677649 -130.619932)
			(xy 5.685569 -130.494044) (xy 5.701379 -130.368902) (xy 5.725014 -130.244999) (xy 5.756383 -130.122826)
			(xy 5.795361 -130.002863) (xy 5.841795 -129.885584) (xy 5.895502 -129.771452) (xy 5.956269 -129.660917)
			(xy 6.023856 -129.554417) (xy 6.097997 -129.45237) (xy 6.1784 -129.35518) (xy 6.264746 -129.26323)
			(xy 6.356696 -129.176884) (xy 6.453886 -129.096481) (xy 6.555933 -129.02234) (xy 6.662433 -128.954753)
			(xy 6.772968 -128.893986) (xy 6.8871 -128.840279) (xy 7.004379 -128.793845) (xy 7.124342 -128.754867)
			(xy 7.246515 -128.723498) (xy 7.370418 -128.699863) (xy 7.49556 -128.684053) (xy 7.621448 -128.676133)
			(xy 7.747584 -128.676133) (xy 7.873472 -128.684053) (xy 7.998614 -128.699863) (xy 8.122517 -128.723498)
			(xy 8.24469 -128.754867) (xy 8.364653 -128.793845) (xy 8.481932 -128.840279) (xy 8.596064 -128.893986)
			(xy 8.706599 -128.954753) (xy 8.813099 -129.02234) (xy 8.915146 -129.096481) (xy 9.012336 -129.176884)
			(xy 9.104286 -129.26323) (xy 9.190632 -129.35518) (xy 9.271035 -129.45237) (xy 9.345176 -129.554417)
			(xy 9.412763 -129.660917) (xy 9.47353 -129.771452) (xy 9.527237 -129.885584) (xy 9.573671 -130.002863)
			(xy 9.612649 -130.122826) (xy 9.644018 -130.244999) (xy 9.667653 -130.368902) (xy 9.683463 -130.494044)
			(xy 9.691383 -130.619932) (xy 9.691878 -130.683) (xy 9.691383 -130.746068) (xy 9.683463 -130.871956)
			(xy 9.667653 -130.997098) (xy 9.644018 -131.121001) (xy 9.612649 -131.243174) (xy 9.573671 -131.363137)
			(xy 9.527237 -131.480416) (xy 9.47353 -131.594548) (xy 9.412763 -131.705083) (xy 9.345176 -131.811583)
			(xy 9.271035 -131.91363) (xy 9.190632 -132.01082) (xy 9.104286 -132.10277) (xy 9.012336 -132.189116)
			(xy 8.915146 -132.269519) (xy 8.813099 -132.34366) (xy 8.706599 -132.411247) (xy 8.596064 -132.472014)
			(xy 8.481932 -132.525721) (xy 8.364653 -132.572155) (xy 8.24469 -132.611133) (xy 8.122517 -132.642502)
			(xy 7.998614 -132.666137) (xy 7.873472 -132.681947) (xy 7.747584 -132.689867) (xy 7.621448 -132.689867)
			(xy 7.49556 -132.681947) (xy 7.370418 -132.666137) (xy 7.246515 -132.642502) (xy 7.124342 -132.611133)
			(xy 7.004379 -132.572155) (xy 6.8871 -132.525721) (xy 6.772968 -132.472014) (xy 6.662433 -132.411247)
			(xy 6.555933 -132.34366) (xy 6.453886 -132.269519) (xy 6.356696 -132.189116) (xy 6.264746 -132.10277)
			(xy 6.1784 -132.01082) (xy 6.097997 -131.91363) (xy 6.023856 -131.811583) (xy 5.956269 -131.705083)
			(xy 5.895502 -131.594548) (xy 5.841795 -131.480416) (xy 5.795361 -131.363137) (xy 5.756383 -131.243174)
			(xy 5.725014 -131.121001) (xy 5.701379 -130.997098) (xy 5.685569 -130.871956) (xy 5.677649 -130.746068)
			(xy 4.023449 -130.746068) (xy 3.957161 -130.787386) (xy 3.885458 -130.822558) (xy 3.810564 -130.850295)
			(xy 3.733249 -130.870314) (xy 3.654305 -130.882407) (xy 3.574542 -130.886453) (xy 3.494779 -130.882407)
			(xy 3.415835 -130.870314) (xy 3.33852 -130.850295) (xy 3.263626 -130.822558) (xy 3.191923 -130.787386)
			(xy 3.124146 -130.74514) (xy 3.06099 -130.696254) (xy 3.003105 -130.64123) (xy 2.951083 -130.580631)
			(xy 2.905459 -130.515081) (xy 2.8667 -130.445251) (xy 2.835205 -130.371858) (xy 2.811296 -130.295656)
			(xy 2.795219 -130.217426) (xy 2.787139 -130.137971) (xy 1.525016 -130.137971) (xy 1.525016 -132.627933)
			(xy 2.787139 -132.627933) (xy 2.787139 -132.548067) (xy 2.795219 -132.468612) (xy 2.811296 -132.390382)
			(xy 2.835205 -132.31418) (xy 2.8667 -132.240787) (xy 2.905459 -132.170957) (xy 2.951083 -132.105407)
			(xy 3.003105 -132.044808) (xy 3.06099 -131.989784) (xy 3.124146 -131.940898) (xy 3.191923 -131.898652)
			(xy 3.263626 -131.86348) (xy 3.33852 -131.835743) (xy 3.415835 -131.815724) (xy 3.494779 -131.803631)
			(xy 3.574542 -131.799586) (xy 3.654305 -131.803631) (xy 3.733249 -131.815724) (xy 3.810564 -131.835743)
			(xy 3.885458 -131.86348) (xy 3.957161 -131.898652) (xy 4.024938 -131.940898) (xy 4.088094 -131.989784)
			(xy 4.145979 -132.044808) (xy 4.198001 -132.105407) (xy 4.243625 -132.170957) (xy 4.282384 -132.240787)
			(xy 4.313879 -132.31418) (xy 4.337788 -132.390382) (xy 4.353865 -132.468612) (xy 4.361945 -132.548067)
			(xy 4.36245 -132.588) (xy 4.361945 -132.627933) (xy 4.353865 -132.707388) (xy 4.337788 -132.785618)
			(xy 4.313879 -132.86182) (xy 4.282384 -132.935213) (xy 4.243625 -133.005043) (xy 4.198001 -133.070593)
			(xy 4.145979 -133.131192) (xy 4.088094 -133.186216) (xy 4.024938 -133.235102) (xy 3.980288 -133.262933)
			(xy 13.247113 -133.262933) (xy 13.247113 -133.183067) (xy 13.255193 -133.103612) (xy 13.27127 -133.025382)
			(xy 13.295179 -132.94918) (xy 13.326674 -132.875787) (xy 13.365433 -132.805957) (xy 13.411057 -132.740407)
			(xy 13.463079 -132.679808) (xy 13.520964 -132.624784) (xy 13.58412 -132.575898) (xy 13.651897 -132.533652)
			(xy 13.7236 -132.49848) (xy 13.798494 -132.470743) (xy 13.875809 -132.450724) (xy 13.954753 -132.438631)
			(xy 14.034516 -132.434586) (xy 14.114279 -132.438631) (xy 14.193223 -132.450724) (xy 14.270538 -132.470743)
			(xy 14.345432 -132.49848) (xy 14.417135 -132.533652) (xy 14.484912 -132.575898) (xy 14.548068 -132.624784)
			(xy 14.605953 -132.679808) (xy 14.657975 -132.740407) (xy 14.703599 -132.805957) (xy 14.742358 -132.875787)
			(xy 14.773853 -132.94918) (xy 14.797762 -133.025382) (xy 14.813839 -133.103612) (xy 14.821919 -133.183067)
			(xy 14.822424 -133.223) (xy 14.821919 -133.262933) (xy 14.813839 -133.342388) (xy 14.797762 -133.420618)
			(xy 14.773853 -133.49682) (xy 14.742358 -133.570213) (xy 14.703599 -133.640043) (xy 14.657975 -133.705593)
			(xy 14.605953 -133.766192) (xy 14.548068 -133.821216) (xy 14.484912 -133.870102) (xy 14.417135 -133.912348)
			(xy 14.345432 -133.94752) (xy 14.270538 -133.975257) (xy 14.193223 -133.995276) (xy 14.114279 -134.007369)
			(xy 14.034516 -134.011415) (xy 13.954753 -134.007369) (xy 13.875809 -133.995276) (xy 13.798494 -133.975257)
			(xy 13.7236 -133.94752) (xy 13.651897 -133.912348) (xy 13.58412 -133.870102) (xy 13.520964 -133.821216)
			(xy 13.463079 -133.766192) (xy 13.411057 -133.705593) (xy 13.365433 -133.640043) (xy 13.326674 -133.570213)
			(xy 13.295179 -133.49682) (xy 13.27127 -133.420618) (xy 13.255193 -133.342388) (xy 13.247113 -133.262933)
			(xy 3.980288 -133.262933) (xy 3.957161 -133.277348) (xy 3.885458 -133.31252) (xy 3.810564 -133.340257)
			(xy 3.733249 -133.360276) (xy 3.654305 -133.372369) (xy 3.574542 -133.376415) (xy 3.494779 -133.372369)
			(xy 3.415835 -133.360276) (xy 3.33852 -133.340257) (xy 3.263626 -133.31252) (xy 3.191923 -133.277348)
			(xy 3.124146 -133.235102) (xy 3.06099 -133.186216) (xy 3.003105 -133.131192) (xy 2.951083 -133.070593)
			(xy 2.905459 -133.005043) (xy 2.8667 -132.935213) (xy 2.835205 -132.86182) (xy 2.811296 -132.785618)
			(xy 2.795219 -132.707388) (xy 2.787139 -132.627933) (xy 1.525016 -132.627933) (xy 1.525016 -134.532933)
			(xy 15.787113 -134.532933) (xy 15.787113 -134.453067) (xy 15.795193 -134.373612) (xy 15.81127 -134.295382)
			(xy 15.835179 -134.21918) (xy 15.866674 -134.145787) (xy 15.905433 -134.075957) (xy 15.951057 -134.010407)
			(xy 16.003079 -133.949808) (xy 16.060964 -133.894784) (xy 16.12412 -133.845898) (xy 16.191897 -133.803652)
			(xy 16.2636 -133.76848) (xy 16.338494 -133.740743) (xy 16.415809 -133.720724) (xy 16.494753 -133.708631)
			(xy 16.574516 -133.704586) (xy 16.654279 -133.708631) (xy 16.733223 -133.720724) (xy 16.810538 -133.740743)
			(xy 16.885432 -133.76848) (xy 16.957135 -133.803652) (xy 17.024912 -133.845898) (xy 17.088068 -133.894784)
			(xy 17.145953 -133.949808) (xy 17.197975 -134.010407) (xy 17.243599 -134.075957) (xy 17.282358 -134.145787)
			(xy 17.313853 -134.21918) (xy 17.337762 -134.295382) (xy 17.353839 -134.373612) (xy 17.361919 -134.453067)
			(xy 17.362424 -134.493) (xy 17.361919 -134.532933) (xy 17.353839 -134.612388) (xy 17.337762 -134.690618)
			(xy 17.313853 -134.76682) (xy 17.282358 -134.840213) (xy 17.243599 -134.910043) (xy 17.197975 -134.975593)
			(xy 17.145953 -135.036192) (xy 17.088068 -135.091216) (xy 17.024912 -135.140102) (xy 16.957135 -135.182348)
			(xy 16.885432 -135.21752) (xy 16.810538 -135.245257) (xy 16.733223 -135.265276) (xy 16.654279 -135.277369)
			(xy 16.574516 -135.281415) (xy 16.494753 -135.277369) (xy 16.415809 -135.265276) (xy 16.338494 -135.245257)
			(xy 16.2636 -135.21752) (xy 16.191897 -135.182348) (xy 16.12412 -135.140102) (xy 16.060964 -135.091216)
			(xy 16.003079 -135.036192) (xy 15.951057 -134.975593) (xy 15.905433 -134.910043) (xy 15.866674 -134.840213)
			(xy 15.835179 -134.76682) (xy 15.81127 -134.690618) (xy 15.795193 -134.612388) (xy 15.787113 -134.532933)
			(xy 1.525016 -134.532933) (xy 1.525016 -135.802933) (xy 13.247113 -135.802933) (xy 13.247113 -135.723067)
			(xy 13.255193 -135.643612) (xy 13.27127 -135.565382) (xy 13.295179 -135.48918) (xy 13.326674 -135.415787)
			(xy 13.365433 -135.345957) (xy 13.411057 -135.280407) (xy 13.463079 -135.219808) (xy 13.520964 -135.164784)
			(xy 13.58412 -135.115898) (xy 13.651897 -135.073652) (xy 13.7236 -135.03848) (xy 13.798494 -135.010743)
			(xy 13.875809 -134.990724) (xy 13.954753 -134.978631) (xy 14.034516 -134.974586) (xy 14.114279 -134.978631)
			(xy 14.193223 -134.990724) (xy 14.270538 -135.010743) (xy 14.345432 -135.03848) (xy 14.417135 -135.073652)
			(xy 14.484912 -135.115898) (xy 14.548068 -135.164784) (xy 14.605953 -135.219808) (xy 14.657975 -135.280407)
			(xy 14.703599 -135.345957) (xy 14.742358 -135.415787) (xy 14.773853 -135.48918) (xy 14.797762 -135.565382)
			(xy 14.813839 -135.643612) (xy 14.821919 -135.723067) (xy 14.822424 -135.763) (xy 14.821919 -135.802933)
			(xy 14.813839 -135.882388) (xy 14.797762 -135.960618) (xy 14.773853 -136.03682) (xy 14.742358 -136.110213)
			(xy 14.703599 -136.180043) (xy 14.657975 -136.245593) (xy 14.605953 -136.306192) (xy 14.548068 -136.361216)
			(xy 14.484912 -136.410102) (xy 14.417135 -136.452348) (xy 14.345432 -136.48752) (xy 14.270538 -136.515257)
			(xy 14.193223 -136.535276) (xy 14.114279 -136.547369) (xy 14.034516 -136.551415) (xy 13.954753 -136.547369)
			(xy 13.875809 -136.535276) (xy 13.798494 -136.515257) (xy 13.7236 -136.48752) (xy 13.651897 -136.452348)
			(xy 13.58412 -136.410102) (xy 13.520964 -136.361216) (xy 13.463079 -136.306192) (xy 13.411057 -136.245593)
			(xy 13.365433 -136.180043) (xy 13.326674 -136.110213) (xy 13.295179 -136.03682) (xy 13.27127 -135.960618)
			(xy 13.255193 -135.882388) (xy 13.247113 -135.802933) (xy 1.525016 -135.802933) (xy 1.525016 -137.072933)
			(xy 15.787113 -137.072933) (xy 15.787113 -136.993067) (xy 15.795193 -136.913612) (xy 15.81127 -136.835382)
			(xy 15.835179 -136.75918) (xy 15.866674 -136.685787) (xy 15.905433 -136.615957) (xy 15.951057 -136.550407)
			(xy 16.003079 -136.489808) (xy 16.060964 -136.434784) (xy 16.12412 -136.385898) (xy 16.191897 -136.343652)
			(xy 16.2636 -136.30848) (xy 16.338494 -136.280743) (xy 16.415809 -136.260724) (xy 16.494753 -136.248631)
			(xy 16.574516 -136.244586) (xy 16.654279 -136.248631) (xy 16.733223 -136.260724) (xy 16.810538 -136.280743)
			(xy 16.885432 -136.30848) (xy 16.957135 -136.343652) (xy 17.024912 -136.385898) (xy 17.088068 -136.434784)
			(xy 17.145953 -136.489808) (xy 17.197975 -136.550407) (xy 17.243599 -136.615957) (xy 17.282358 -136.685787)
			(xy 17.313853 -136.75918) (xy 17.337762 -136.835382) (xy 17.353839 -136.913612) (xy 17.361919 -136.993067)
			(xy 17.362424 -137.033) (xy 17.361919 -137.072933) (xy 17.353839 -137.152388) (xy 17.337762 -137.230618)
			(xy 17.313853 -137.30682) (xy 17.282358 -137.380213) (xy 17.243599 -137.450043) (xy 17.197975 -137.515593)
			(xy 17.145953 -137.576192) (xy 17.088068 -137.631216) (xy 17.024912 -137.680102) (xy 16.957135 -137.722348)
			(xy 16.885432 -137.75752) (xy 16.810538 -137.785257) (xy 16.733223 -137.805276) (xy 16.654279 -137.817369)
			(xy 16.574516 -137.821415) (xy 16.494753 -137.817369) (xy 16.415809 -137.805276) (xy 16.338494 -137.785257)
			(xy 16.2636 -137.75752) (xy 16.191897 -137.722348) (xy 16.12412 -137.680102) (xy 16.060964 -137.631216)
			(xy 16.003079 -137.576192) (xy 15.951057 -137.515593) (xy 15.905433 -137.450043) (xy 15.866674 -137.380213)
			(xy 15.835179 -137.30682) (xy 15.81127 -137.230618) (xy 15.795193 -137.152388) (xy 15.787113 -137.072933)
			(xy 1.525016 -137.072933) (xy 1.525016 -138.342933) (xy 13.247113 -138.342933) (xy 13.247113 -138.263067)
			(xy 13.255193 -138.183612) (xy 13.27127 -138.105382) (xy 13.295179 -138.02918) (xy 13.326674 -137.955787)
			(xy 13.365433 -137.885957) (xy 13.411057 -137.820407) (xy 13.463079 -137.759808) (xy 13.520964 -137.704784)
			(xy 13.58412 -137.655898) (xy 13.651897 -137.613652) (xy 13.7236 -137.57848) (xy 13.798494 -137.550743)
			(xy 13.875809 -137.530724) (xy 13.954753 -137.518631) (xy 14.034516 -137.514586) (xy 14.114279 -137.518631)
			(xy 14.193223 -137.530724) (xy 14.270538 -137.550743) (xy 14.345432 -137.57848) (xy 14.417135 -137.613652)
			(xy 14.484912 -137.655898) (xy 14.548068 -137.704784) (xy 14.605953 -137.759808) (xy 14.657975 -137.820407)
			(xy 14.703599 -137.885957) (xy 14.742358 -137.955787) (xy 14.773853 -138.02918) (xy 14.797762 -138.105382)
			(xy 14.813839 -138.183612) (xy 14.821919 -138.263067) (xy 14.822424 -138.303) (xy 14.821919 -138.342933)
			(xy 14.813839 -138.422388) (xy 14.797762 -138.500618) (xy 14.773853 -138.57682) (xy 14.742358 -138.650213)
			(xy 14.703599 -138.720043) (xy 14.657975 -138.785593) (xy 14.605953 -138.846192) (xy 14.548068 -138.901216)
			(xy 14.484912 -138.950102) (xy 14.417135 -138.992348) (xy 14.345432 -139.02752) (xy 14.270538 -139.055257)
			(xy 14.193223 -139.075276) (xy 14.114279 -139.087369) (xy 14.034516 -139.091415) (xy 13.954753 -139.087369)
			(xy 13.875809 -139.075276) (xy 13.798494 -139.055257) (xy 13.7236 -139.02752) (xy 13.651897 -138.992348)
			(xy 13.58412 -138.950102) (xy 13.520964 -138.901216) (xy 13.463079 -138.846192) (xy 13.411057 -138.785593)
			(xy 13.365433 -138.720043) (xy 13.326674 -138.650213) (xy 13.295179 -138.57682) (xy 13.27127 -138.500618)
			(xy 13.255193 -138.422388) (xy 13.247113 -138.342933) (xy 1.525016 -138.342933) (xy 1.525016 -140.247933)
			(xy 2.787139 -140.247933) (xy 2.787139 -140.168067) (xy 2.795219 -140.088612) (xy 2.811296 -140.010382)
			(xy 2.835205 -139.93418) (xy 2.8667 -139.860787) (xy 2.905459 -139.790957) (xy 2.951083 -139.725407)
			(xy 3.003105 -139.664808) (xy 3.06099 -139.609784) (xy 3.124146 -139.560898) (xy 3.191923 -139.518652)
			(xy 3.263626 -139.48348) (xy 3.33852 -139.455743) (xy 3.415835 -139.435724) (xy 3.494779 -139.423631)
			(xy 3.574542 -139.419586) (xy 3.654305 -139.423631) (xy 3.733249 -139.435724) (xy 3.810564 -139.455743)
			(xy 3.885458 -139.48348) (xy 3.957161 -139.518652) (xy 4.024938 -139.560898) (xy 4.088094 -139.609784)
			(xy 4.091407 -139.612933) (xy 15.787113 -139.612933) (xy 15.787113 -139.533067) (xy 15.795193 -139.453612)
			(xy 15.81127 -139.375382) (xy 15.835179 -139.29918) (xy 15.866674 -139.225787) (xy 15.905433 -139.155957)
			(xy 15.951057 -139.090407) (xy 16.003079 -139.029808) (xy 16.060964 -138.974784) (xy 16.12412 -138.925898)
			(xy 16.191897 -138.883652) (xy 16.2636 -138.84848) (xy 16.338494 -138.820743) (xy 16.415809 -138.800724)
			(xy 16.494753 -138.788631) (xy 16.574516 -138.784586) (xy 16.654279 -138.788631) (xy 16.733223 -138.800724)
			(xy 16.810538 -138.820743) (xy 16.885432 -138.84848) (xy 16.957135 -138.883652) (xy 17.024912 -138.925898)
			(xy 17.088068 -138.974784) (xy 17.145953 -139.029808) (xy 17.197975 -139.090407) (xy 17.243599 -139.155957)
			(xy 17.282358 -139.225787) (xy 17.313853 -139.29918) (xy 17.337762 -139.375382) (xy 17.353839 -139.453612)
			(xy 17.361919 -139.533067) (xy 17.362424 -139.573) (xy 17.361919 -139.612933) (xy 17.353839 -139.692388)
			(xy 17.337762 -139.770618) (xy 17.313853 -139.84682) (xy 17.282358 -139.920213) (xy 17.243599 -139.990043)
			(xy 17.197975 -140.055593) (xy 17.145953 -140.116192) (xy 17.088068 -140.171216) (xy 17.024912 -140.220102)
			(xy 16.957135 -140.262348) (xy 16.885432 -140.29752) (xy 16.810538 -140.325257) (xy 16.733223 -140.345276)
			(xy 16.654279 -140.357369) (xy 16.574516 -140.361415) (xy 16.494753 -140.357369) (xy 16.415809 -140.345276)
			(xy 16.338494 -140.325257) (xy 16.2636 -140.29752) (xy 16.191897 -140.262348) (xy 16.12412 -140.220102)
			(xy 16.060964 -140.171216) (xy 16.003079 -140.116192) (xy 15.951057 -140.055593) (xy 15.905433 -139.990043)
			(xy 15.866674 -139.920213) (xy 15.835179 -139.84682) (xy 15.81127 -139.770618) (xy 15.795193 -139.692388)
			(xy 15.787113 -139.612933) (xy 4.091407 -139.612933) (xy 4.145979 -139.664808) (xy 4.198001 -139.725407)
			(xy 4.243625 -139.790957) (xy 4.282384 -139.860787) (xy 4.313879 -139.93418) (xy 4.337788 -140.010382)
			(xy 4.353865 -140.088612) (xy 4.361945 -140.168067) (xy 4.36245 -140.208) (xy 4.361945 -140.247933)
			(xy 4.353865 -140.327388) (xy 4.337788 -140.405618) (xy 4.313879 -140.48182) (xy 4.282384 -140.555213)
			(xy 4.243625 -140.625043) (xy 4.198001 -140.690593) (xy 4.145979 -140.751192) (xy 4.088094 -140.806216)
			(xy 4.024938 -140.855102) (xy 3.957161 -140.897348) (xy 3.885458 -140.93252) (xy 3.810564 -140.960257)
			(xy 3.733249 -140.980276) (xy 3.654305 -140.992369) (xy 3.574542 -140.996415) (xy 3.494779 -140.992369)
			(xy 3.415835 -140.980276) (xy 3.33852 -140.960257) (xy 3.263626 -140.93252) (xy 3.191923 -140.897348)
			(xy 3.124146 -140.855102) (xy 3.06099 -140.806216) (xy 3.003105 -140.751192) (xy 2.951083 -140.690593)
			(xy 2.905459 -140.625043) (xy 2.8667 -140.555213) (xy 2.835205 -140.48182) (xy 2.811296 -140.405618)
			(xy 2.795219 -140.327388) (xy 2.787139 -140.247933) (xy 1.525016 -140.247933) (xy 1.525016 -142.737895)
			(xy 2.787139 -142.737895) (xy 2.787139 -142.658029) (xy 2.795219 -142.578574) (xy 2.811296 -142.500344)
			(xy 2.835205 -142.424142) (xy 2.8667 -142.350749) (xy 2.905459 -142.280919) (xy 2.951083 -142.215369)
			(xy 3.003105 -142.15477) (xy 3.06099 -142.099746) (xy 3.124146 -142.05086) (xy 3.191923 -142.008614)
			(xy 3.263626 -141.973442) (xy 3.33852 -141.945705) (xy 3.415835 -141.925686) (xy 3.494779 -141.913593)
			(xy 3.574542 -141.909548) (xy 3.654305 -141.913593) (xy 3.733249 -141.925686) (xy 3.810564 -141.945705)
			(xy 3.885458 -141.973442) (xy 3.957161 -142.008614) (xy 4.024938 -142.05086) (xy 4.088094 -142.099746)
			(xy 4.145979 -142.15477) (xy 4.164263 -142.176068) (xy 5.677649 -142.176068) (xy 5.677649 -142.049932)
			(xy 5.685569 -141.924044) (xy 5.701379 -141.798902) (xy 5.725014 -141.674999) (xy 5.756383 -141.552826)
			(xy 5.795361 -141.432863) (xy 5.841795 -141.315584) (xy 5.895502 -141.201452) (xy 5.956269 -141.090917)
			(xy 6.023856 -140.984417) (xy 6.097997 -140.88237) (xy 6.1784 -140.78518) (xy 6.264746 -140.69323)
			(xy 6.356696 -140.606884) (xy 6.453886 -140.526481) (xy 6.555933 -140.45234) (xy 6.662433 -140.384753)
			(xy 6.772968 -140.323986) (xy 6.8871 -140.270279) (xy 7.004379 -140.223845) (xy 7.124342 -140.184867)
			(xy 7.246515 -140.153498) (xy 7.370418 -140.129863) (xy 7.49556 -140.114053) (xy 7.621448 -140.106133)
			(xy 7.747584 -140.106133) (xy 7.873472 -140.114053) (xy 7.998614 -140.129863) (xy 8.122517 -140.153498)
			(xy 8.24469 -140.184867) (xy 8.364653 -140.223845) (xy 8.481932 -140.270279) (xy 8.596064 -140.323986)
			(xy 8.706599 -140.384753) (xy 8.813099 -140.45234) (xy 8.915146 -140.526481) (xy 9.012336 -140.606884)
			(xy 9.104286 -140.69323) (xy 9.190632 -140.78518) (xy 9.271035 -140.88237) (xy 9.271444 -140.882933)
			(xy 13.247113 -140.882933) (xy 13.247113 -140.803067) (xy 13.255193 -140.723612) (xy 13.27127 -140.645382)
			(xy 13.295179 -140.56918) (xy 13.326674 -140.495787) (xy 13.365433 -140.425957) (xy 13.411057 -140.360407)
			(xy 13.463079 -140.299808) (xy 13.520964 -140.244784) (xy 13.58412 -140.195898) (xy 13.651897 -140.153652)
			(xy 13.7236 -140.11848) (xy 13.798494 -140.090743) (xy 13.875809 -140.070724) (xy 13.954753 -140.058631)
			(xy 14.034516 -140.054586) (xy 14.114279 -140.058631) (xy 14.193223 -140.070724) (xy 14.270538 -140.090743)
			(xy 14.345432 -140.11848) (xy 14.417135 -140.153652) (xy 14.484912 -140.195898) (xy 14.548068 -140.244784)
			(xy 14.605953 -140.299808) (xy 14.657975 -140.360407) (xy 14.703599 -140.425957) (xy 14.742358 -140.495787)
			(xy 14.773853 -140.56918) (xy 14.797762 -140.645382) (xy 14.813839 -140.723612) (xy 14.821919 -140.803067)
			(xy 14.822424 -140.843) (xy 14.821919 -140.882933) (xy 14.813839 -140.962388) (xy 14.797762 -141.040618)
			(xy 14.773853 -141.11682) (xy 14.742358 -141.190213) (xy 14.703599 -141.260043) (xy 14.657975 -141.325593)
			(xy 14.605953 -141.386192) (xy 14.548068 -141.441216) (xy 14.484912 -141.490102) (xy 14.417135 -141.532348)
			(xy 14.345432 -141.56752) (xy 14.270538 -141.595257) (xy 14.193223 -141.615276) (xy 14.114279 -141.627369)
			(xy 14.034516 -141.631415) (xy 13.954753 -141.627369) (xy 13.875809 -141.615276) (xy 13.798494 -141.595257)
			(xy 13.7236 -141.56752) (xy 13.651897 -141.532348) (xy 13.58412 -141.490102) (xy 13.520964 -141.441216)
			(xy 13.463079 -141.386192) (xy 13.411057 -141.325593) (xy 13.365433 -141.260043) (xy 13.326674 -141.190213)
			(xy 13.295179 -141.11682) (xy 13.27127 -141.040618) (xy 13.255193 -140.962388) (xy 13.247113 -140.882933)
			(xy 9.271444 -140.882933) (xy 9.345176 -140.984417) (xy 9.412763 -141.090917) (xy 9.47353 -141.201452)
			(xy 9.527237 -141.315584) (xy 9.573671 -141.432863) (xy 9.612649 -141.552826) (xy 9.644018 -141.674999)
			(xy 9.667653 -141.798902) (xy 9.683463 -141.924044) (xy 9.691383 -142.049932) (xy 9.691878 -142.113)
			(xy 9.691383 -142.176068) (xy 9.683463 -142.301956) (xy 9.667653 -142.427098) (xy 9.644018 -142.551001)
			(xy 9.612649 -142.673174) (xy 9.573671 -142.793137) (xy 9.527237 -142.910416) (xy 9.47353 -143.024548)
			(xy 9.412763 -143.135083) (xy 9.345176 -143.241583) (xy 9.271035 -143.34363) (xy 9.190632 -143.44082)
			(xy 9.104286 -143.53277) (xy 9.012336 -143.619116) (xy 8.915146 -143.699519) (xy 8.813099 -143.77366)
			(xy 8.706599 -143.841247) (xy 8.596064 -143.902014) (xy 8.481932 -143.955721) (xy 8.364653 -144.002155)
			(xy 8.24469 -144.041133) (xy 8.122517 -144.072502) (xy 7.998614 -144.096137) (xy 7.873472 -144.111947)
			(xy 7.747584 -144.119867) (xy 7.621448 -144.119867) (xy 7.49556 -144.111947) (xy 7.370418 -144.096137)
			(xy 7.246515 -144.072502) (xy 7.124342 -144.041133) (xy 7.004379 -144.002155) (xy 6.8871 -143.955721)
			(xy 6.772968 -143.902014) (xy 6.662433 -143.841247) (xy 6.555933 -143.77366) (xy 6.453886 -143.699519)
			(xy 6.356696 -143.619116) (xy 6.264746 -143.53277) (xy 6.1784 -143.44082) (xy 6.097997 -143.34363)
			(xy 6.023856 -143.241583) (xy 5.956269 -143.135083) (xy 5.895502 -143.024548) (xy 5.841795 -142.910416)
			(xy 5.795361 -142.793137) (xy 5.756383 -142.673174) (xy 5.725014 -142.551001) (xy 5.701379 -142.427098)
			(xy 5.685569 -142.301956) (xy 5.677649 -142.176068) (xy 4.164263 -142.176068) (xy 4.198001 -142.215369)
			(xy 4.243625 -142.280919) (xy 4.282384 -142.350749) (xy 4.313879 -142.424142) (xy 4.337788 -142.500344)
			(xy 4.353865 -142.578574) (xy 4.361945 -142.658029) (xy 4.36245 -142.697962) (xy 4.361945 -142.737895)
			(xy 4.353865 -142.81735) (xy 4.337788 -142.89558) (xy 4.313879 -142.971782) (xy 4.282384 -143.045175)
			(xy 4.243625 -143.115005) (xy 4.198001 -143.180555) (xy 4.145979 -143.241154) (xy 4.088094 -143.296178)
			(xy 4.024938 -143.345064) (xy 3.957161 -143.38731) (xy 3.885458 -143.422482) (xy 3.810564 -143.450219)
			(xy 3.733249 -143.470238) (xy 3.654305 -143.482331) (xy 3.574542 -143.486377) (xy 3.494779 -143.482331)
			(xy 3.415835 -143.470238) (xy 3.33852 -143.450219) (xy 3.263626 -143.422482) (xy 3.191923 -143.38731)
			(xy 3.124146 -143.345064) (xy 3.06099 -143.296178) (xy 3.003105 -143.241154) (xy 2.951083 -143.180555)
			(xy 2.905459 -143.115005) (xy 2.8667 -143.045175) (xy 2.835205 -142.971782) (xy 2.811296 -142.89558)
			(xy 2.795219 -142.81735) (xy 2.787139 -142.737895) (xy 1.525016 -142.737895) (xy 1.525016 -176.870614)
			(xy 3.864362 -176.870614) (xy 3.868375 -176.7672) (xy 3.88039 -176.664407) (xy 3.900334 -176.562855)
			(xy 3.928088 -176.463153) (xy 3.963484 -176.365903) (xy 4.00631 -176.271687) (xy 4.056309 -176.181074)
			(xy 4.113179 -176.094607) (xy 4.176578 -176.012808) (xy 4.246126 -175.936167) (xy 4.321403 -175.865146)
			(xy 4.401958 -175.800173) (xy 4.487305 -175.741637) (xy 4.576932 -175.689891) (xy 4.6703 -175.645245)
			(xy 4.766846 -175.60797) (xy 4.86599 -175.578288) (xy 4.967137 -175.556378) (xy 5.069677 -175.542372)
			(xy 5.172994 -175.536355) (xy 5.276467 -175.538362) (xy 5.379473 -175.548381) (xy 5.481393 -175.566352)
			(xy 5.581614 -175.592167) (xy 5.679533 -175.625671) (xy 5.774561 -175.666663) (xy 5.866127 -175.714894)
			(xy 5.95368 -175.770077) (xy 6.036694 -175.831878) (xy 6.114668 -175.899927) (xy 6.187135 -175.973813)
			(xy 6.253659 -176.053092) (xy 6.313839 -176.137289) (xy 6.367313 -176.225895) (xy 6.41376 -176.318379)
			(xy 6.452901 -176.414185) (xy 6.4845 -176.512735) (xy 6.508367 -176.613438) (xy 6.524359 -176.715687)
			(xy 6.532378 -176.818868) (xy 6.53288 -176.870614) (xy 6.532378 -176.92236) (xy 6.524359 -177.025541)
			(xy 6.508367 -177.12779) (xy 6.4845 -177.228493) (xy 6.452901 -177.327043) (xy 6.41376 -177.422849)
			(xy 6.367313 -177.515333) (xy 6.313839 -177.603939) (xy 6.253659 -177.688136) (xy 6.187135 -177.767415)
			(xy 6.114668 -177.841301) (xy 6.036694 -177.90935) (xy 5.95368 -177.971151) (xy 5.866127 -178.026334)
			(xy 5.774561 -178.074565) (xy 5.679533 -178.115557) (xy 5.581614 -178.149061) (xy 5.481393 -178.174876)
			(xy 5.379473 -178.192847) (xy 5.276467 -178.202866) (xy 5.172994 -178.204873) (xy 5.069677 -178.198856)
			(xy 4.967137 -178.18485) (xy 4.86599 -178.16294) (xy 4.766846 -178.133258) (xy 4.6703 -178.095983)
			(xy 4.576932 -178.051337) (xy 4.487305 -177.999591) (xy 4.401958 -177.941055) (xy 4.321403 -177.876082)
			(xy 4.246126 -177.805061) (xy 4.176578 -177.72842) (xy 4.113179 -177.646621) (xy 4.056309 -177.560154)
			(xy 4.00631 -177.469541) (xy 3.963484 -177.375325) (xy 3.928088 -177.278075) (xy 3.900334 -177.178373)
			(xy 3.88039 -177.076821) (xy 3.868375 -176.974028) (xy 3.864362 -176.870614) (xy 1.525016 -176.870614)
			(xy 1.525016 -177.797206) (xy 1.525496 -177.819613) (xy 1.533363 -177.86373) (xy 1.548842 -177.905786)
			(xy 1.571453 -177.944477) (xy 1.600496 -177.978605) (xy 1.635072 -178.007114) (xy 1.67411 -178.02912)
			(xy 1.716401 -178.043943) (xy 1.760635 -178.051123) (xy 1.805443 -178.050438) (xy 1.82753 -178.046634)
			(xy 1.863115 -178.040227) (xy 1.9352 -178.034559) (xy 2.007462 -178.037108) (xy 2.078968 -178.047843)
			(xy 2.148793 -178.066624) (xy 2.216036 -178.093209) (xy 2.279827 -178.127254) (xy 2.339341 -178.168319)
			(xy 2.393811 -178.215873) (xy 2.442531 -178.269302) (xy 2.484872 -178.327916) (xy 2.520287 -178.390957)
			(xy 2.548318 -178.457609) (xy 2.568603 -178.527013) (xy 2.58088 -178.59827) (xy 2.58499 -178.67046)
			(xy 2.58296 -178.706119) (xy 7.813794 -178.706119) (xy 7.813794 -178.634797) (xy 7.82178 -178.563923)
			(xy 7.83765 -178.494388) (xy 7.861207 -178.427068) (xy 7.892152 -178.362809) (xy 7.930098 -178.302418)
			(xy 7.974567 -178.246656) (xy 8.025 -178.196223) (xy 8.080762 -178.151754) (xy 8.141153 -178.113808)
			(xy 8.205412 -178.082863) (xy 8.272732 -178.059306) (xy 8.342267 -178.043436) (xy 8.413141 -178.03545)
			(xy 8.484463 -178.03545) (xy 8.555337 -178.043436) (xy 8.624872 -178.059306) (xy 8.692192 -178.082863)
			(xy 8.756451 -178.113808) (xy 8.816842 -178.151754) (xy 8.872604 -178.196223) (xy 8.923037 -178.246656)
			(xy 8.967506 -178.302418) (xy 9.005452 -178.362809) (xy 9.036397 -178.427068) (xy 9.059954 -178.494388)
			(xy 9.075824 -178.563923) (xy 9.08381 -178.634797) (xy 9.08431 -178.670458) (xy 9.08381 -178.706119)
			(xy 9.075824 -178.776993) (xy 9.059954 -178.846528) (xy 9.036397 -178.913848) (xy 9.005452 -178.978107)
			(xy 8.967506 -179.038498) (xy 8.923037 -179.09426) (xy 8.872604 -179.144693) (xy 8.816842 -179.189162)
			(xy 8.756451 -179.227108) (xy 8.692192 -179.258053) (xy 8.624872 -179.28161) (xy 8.555337 -179.29748)
			(xy 8.484463 -179.305466) (xy 8.413141 -179.305466) (xy 8.342267 -179.29748) (xy 8.272732 -179.28161)
			(xy 8.205412 -179.258053) (xy 8.141153 -179.227108) (xy 8.080762 -179.189162) (xy 8.025 -179.144693)
			(xy 7.974567 -179.09426) (xy 7.930098 -179.038498) (xy 7.892152 -178.978107) (xy 7.861207 -178.913848)
			(xy 7.83765 -178.846528) (xy 7.82178 -178.776993) (xy 7.813794 -178.706119) (xy 2.58296 -178.706119)
			(xy 2.58088 -178.742651) (xy 2.568603 -178.813908) (xy 2.548318 -178.883311) (xy 2.520286 -178.949964)
			(xy 2.484871 -179.013005) (xy 2.44253 -179.071618) (xy 2.39381 -179.125047) (xy 2.339341 -179.172602)
			(xy 2.279826 -179.213667) (xy 2.216035 -179.247712) (xy 2.148793 -179.274296) (xy 2.078967 -179.293077)
			(xy 2.007461 -179.303812) (xy 1.935199 -179.306361) (xy 1.863114 -179.300693) (xy 1.82753 -179.294282)
			(xy 1.80544 -179.290464) (xy 1.760621 -179.289748) (xy 1.716372 -179.296907) (xy 1.674065 -179.311718)
			(xy 1.635013 -179.333724) (xy 1.600429 -179.362239) (xy 1.571384 -179.396381) (xy 1.54878 -179.43509)
			(xy 1.533319 -179.477163) (xy 1.52548 -179.521297) (xy 1.525016 -179.54371) (xy 1.525016 -179.706117)
			(xy 3.31393 -179.706117) (xy 3.31393 -179.634795) (xy 3.321916 -179.563921) (xy 3.337786 -179.494386)
			(xy 3.361343 -179.427066) (xy 3.392288 -179.362807) (xy 3.430234 -179.302416) (xy 3.474703 -179.246654)
			(xy 3.525136 -179.196221) (xy 3.580898 -179.151752) (xy 3.641289 -179.113806) (xy 3.705548 -179.082861)
			(xy 3.772868 -179.059304) (xy 3.842403 -179.043434) (xy 3.913277 -179.035448) (xy 3.984599 -179.035448)
			(xy 4.055473 -179.043434) (xy 4.125008 -179.059304) (xy 4.192328 -179.082861) (xy 4.256587 -179.113806)
			(xy 4.316978 -179.151752) (xy 4.37274 -179.196221) (xy 4.423173 -179.246654) (xy 4.467642 -179.302416)
			(xy 4.505588 -179.362807) (xy 4.536533 -179.427066) (xy 4.56009 -179.494386) (xy 4.57596 -179.563921)
			(xy 4.583946 -179.634795) (xy 4.584446 -179.670456) (xy 4.583946 -179.706117) (xy 5.813798 -179.706117)
			(xy 5.813798 -179.634795) (xy 5.821784 -179.563921) (xy 5.837654 -179.494386) (xy 5.861211 -179.427066)
			(xy 5.892156 -179.362807) (xy 5.930102 -179.302416) (xy 5.974571 -179.246654) (xy 6.025004 -179.196221)
			(xy 6.080766 -179.151752) (xy 6.141157 -179.113806) (xy 6.205416 -179.082861) (xy 6.272736 -179.059304)
			(xy 6.342271 -179.043434) (xy 6.413145 -179.035448) (xy 6.484467 -179.035448) (xy 6.555341 -179.043434)
			(xy 6.624876 -179.059304) (xy 6.692196 -179.082861) (xy 6.756455 -179.113806) (xy 6.816846 -179.151752)
			(xy 6.872608 -179.196221) (xy 6.923041 -179.246654) (xy 6.96751 -179.302416) (xy 7.005456 -179.362807)
			(xy 7.036401 -179.427066) (xy 7.059958 -179.494386) (xy 7.075828 -179.563921) (xy 7.083814 -179.634795)
			(xy 7.084314 -179.670456) (xy 7.083814 -179.706117) (xy 7.075828 -179.776991) (xy 7.059958 -179.846526)
			(xy 7.036401 -179.913846) (xy 7.005456 -179.978105) (xy 6.96751 -180.038496) (xy 6.923041 -180.094258)
			(xy 6.872608 -180.144691) (xy 6.816846 -180.18916) (xy 6.756455 -180.227106) (xy 6.692196 -180.258051)
			(xy 6.624876 -180.281608) (xy 6.555341 -180.297478) (xy 6.484467 -180.305464) (xy 6.413145 -180.305464)
			(xy 6.342271 -180.297478) (xy 6.272736 -180.281608) (xy 6.205416 -180.258051) (xy 6.141157 -180.227106)
			(xy 6.080766 -180.18916) (xy 6.025004 -180.144691) (xy 5.974571 -180.094258) (xy 5.930102 -180.038496)
			(xy 5.892156 -179.978105) (xy 5.861211 -179.913846) (xy 5.837654 -179.846526) (xy 5.821784 -179.776991)
			(xy 5.813798 -179.706117) (xy 4.583946 -179.706117) (xy 4.57596 -179.776991) (xy 4.56009 -179.846526)
			(xy 4.536533 -179.913846) (xy 4.505588 -179.978105) (xy 4.467642 -180.038496) (xy 4.423173 -180.094258)
			(xy 4.37274 -180.144691) (xy 4.316978 -180.18916) (xy 4.256587 -180.227106) (xy 4.192328 -180.258051)
			(xy 4.125008 -180.281608) (xy 4.055473 -180.297478) (xy 3.984599 -180.305464) (xy 3.913277 -180.305464)
			(xy 3.842403 -180.297478) (xy 3.772868 -180.281608) (xy 3.705548 -180.258051) (xy 3.641289 -180.227106)
			(xy 3.580898 -180.18916) (xy 3.525136 -180.144691) (xy 3.474703 -180.094258) (xy 3.430234 -180.038496)
			(xy 3.392288 -179.978105) (xy 3.361343 -179.913846) (xy 3.337786 -179.846526) (xy 3.321916 -179.776991)
			(xy 3.31393 -179.706117) (xy 1.525016 -179.706117) (xy 1.525016 -179.797202) (xy 1.525496 -179.819609)
			(xy 1.533362 -179.863727) (xy 1.54884 -179.905783) (xy 1.571451 -179.944475) (xy 1.600494 -179.978604)
			(xy 1.63507 -180.007113) (xy 1.674109 -180.02912) (xy 1.7164 -180.043943) (xy 1.760635 -180.051123)
			(xy 1.805444 -180.050437) (xy 1.82753 -180.04663) (xy 1.863115 -180.040223) (xy 1.9352 -180.034554)
			(xy 2.007462 -180.037104) (xy 2.078968 -180.047838) (xy 2.148793 -180.066619) (xy 2.216036 -180.093204)
			(xy 2.279827 -180.127248) (xy 2.339341 -180.168313) (xy 2.393811 -180.215867) (xy 2.442531 -180.269297)
			(xy 2.484872 -180.32791) (xy 2.520287 -180.39095) (xy 2.548318 -180.457603) (xy 2.568603 -180.527007)
			(xy 2.58088 -180.598264) (xy 2.58499 -180.670454) (xy 2.58296 -180.706115) (xy 7.813794 -180.706115)
			(xy 7.813794 -180.634793) (xy 7.82178 -180.563919) (xy 7.83765 -180.494384) (xy 7.861207 -180.427064)
			(xy 7.892152 -180.362805) (xy 7.930098 -180.302414) (xy 7.974567 -180.246652) (xy 8.025 -180.196219)
			(xy 8.080762 -180.15175) (xy 8.141153 -180.113804) (xy 8.205412 -180.082859) (xy 8.272732 -180.059302)
			(xy 8.342267 -180.043432) (xy 8.413141 -180.035446) (xy 8.484463 -180.035446) (xy 8.555337 -180.043432)
			(xy 8.624872 -180.059302) (xy 8.692192 -180.082859) (xy 8.756451 -180.113804) (xy 8.816842 -180.15175)
			(xy 8.872604 -180.196219) (xy 8.923037 -180.246652) (xy 8.967506 -180.302414) (xy 9.005452 -180.362805)
			(xy 9.036397 -180.427064) (xy 9.059954 -180.494384) (xy 9.075824 -180.563919) (xy 9.08381 -180.634793)
			(xy 9.08431 -180.670454) (xy 9.08381 -180.706115) (xy 9.075824 -180.776989) (xy 9.059954 -180.846524)
			(xy 9.036397 -180.913844) (xy 9.005452 -180.978103) (xy 8.967506 -181.038494) (xy 8.923037 -181.094256)
			(xy 8.872604 -181.144689) (xy 8.816842 -181.189158) (xy 8.756451 -181.227104) (xy 8.692192 -181.258049)
			(xy 8.624872 -181.281606) (xy 8.555337 -181.297476) (xy 8.484463 -181.305462) (xy 8.413141 -181.305462)
			(xy 8.342267 -181.297476) (xy 8.272732 -181.281606) (xy 8.205412 -181.258049) (xy 8.141153 -181.227104)
			(xy 8.080762 -181.189158) (xy 8.025 -181.144689) (xy 7.974567 -181.094256) (xy 7.930098 -181.038494)
			(xy 7.892152 -180.978103) (xy 7.861207 -180.913844) (xy 7.83765 -180.846524) (xy 7.82178 -180.776989)
			(xy 7.813794 -180.706115) (xy 2.58296 -180.706115) (xy 2.58088 -180.742644) (xy 2.568603 -180.813901)
			(xy 2.548318 -180.883305) (xy 2.520287 -180.949958) (xy 2.484872 -181.012998) (xy 2.442531 -181.071611)
			(xy 2.393811 -181.125041) (xy 2.339341 -181.172595) (xy 2.279827 -181.21366) (xy 2.216036 -181.247704)
			(xy 2.148793 -181.274289) (xy 2.078968 -181.29307) (xy 2.007462 -181.303804) (xy 1.9352 -181.306354)
			(xy 1.863115 -181.300685) (xy 1.82753 -181.294278) (xy 1.80544 -181.29046) (xy 1.760621 -181.289744)
			(xy 1.716371 -181.296903) (xy 1.674064 -181.311714) (xy 1.635012 -181.33372) (xy 1.600427 -181.362235)
			(xy 1.571382 -181.396377) (xy 1.548778 -181.435085) (xy 1.533316 -181.477159) (xy 1.525477 -181.521293)
			(xy 1.525016 -181.543706) (xy 1.525016 -181.706113) (xy 3.31393 -181.706113) (xy 3.31393 -181.634791)
			(xy 3.321916 -181.563917) (xy 3.337786 -181.494382) (xy 3.361343 -181.427062) (xy 3.392288 -181.362803)
			(xy 3.430234 -181.302412) (xy 3.474703 -181.24665) (xy 3.525136 -181.196217) (xy 3.580898 -181.151748)
			(xy 3.641289 -181.113802) (xy 3.705548 -181.082857) (xy 3.772868 -181.0593) (xy 3.842403 -181.04343)
			(xy 3.913277 -181.035444) (xy 3.984599 -181.035444) (xy 4.055473 -181.04343) (xy 4.125008 -181.0593)
			(xy 4.192328 -181.082857) (xy 4.256587 -181.113802) (xy 4.316978 -181.151748) (xy 4.37274 -181.196217)
			(xy 4.423173 -181.24665) (xy 4.467642 -181.302412) (xy 4.505588 -181.362803) (xy 4.536533 -181.427062)
			(xy 4.56009 -181.494382) (xy 4.57596 -181.563917) (xy 4.583946 -181.634791) (xy 4.584446 -181.670452)
			(xy 4.583946 -181.706113) (xy 5.813798 -181.706113) (xy 5.813798 -181.634791) (xy 5.821784 -181.563917)
			(xy 5.837654 -181.494382) (xy 5.861211 -181.427062) (xy 5.892156 -181.362803) (xy 5.930102 -181.302412)
			(xy 5.974571 -181.24665) (xy 6.025004 -181.196217) (xy 6.080766 -181.151748) (xy 6.141157 -181.113802)
			(xy 6.205416 -181.082857) (xy 6.272736 -181.0593) (xy 6.342271 -181.04343) (xy 6.413145 -181.035444)
			(xy 6.484467 -181.035444) (xy 6.555341 -181.04343) (xy 6.624876 -181.0593) (xy 6.692196 -181.082857)
			(xy 6.756455 -181.113802) (xy 6.816846 -181.151748) (xy 6.872608 -181.196217) (xy 6.923041 -181.24665)
			(xy 6.96751 -181.302412) (xy 7.005456 -181.362803) (xy 7.036401 -181.427062) (xy 7.059958 -181.494382)
			(xy 7.075828 -181.563917) (xy 7.083814 -181.634791) (xy 7.084314 -181.670452) (xy 7.083814 -181.706113)
			(xy 7.075828 -181.776987) (xy 7.059958 -181.846522) (xy 7.036401 -181.913842) (xy 7.005456 -181.978101)
			(xy 6.96751 -182.038492) (xy 6.923041 -182.094254) (xy 6.872608 -182.144687) (xy 6.816846 -182.189156)
			(xy 6.756455 -182.227102) (xy 6.692196 -182.258047) (xy 6.624876 -182.281604) (xy 6.555341 -182.297474)
			(xy 6.484467 -182.30546) (xy 6.413145 -182.30546) (xy 6.342271 -182.297474) (xy 6.272736 -182.281604)
			(xy 6.205416 -182.258047) (xy 6.141157 -182.227102) (xy 6.080766 -182.189156) (xy 6.025004 -182.144687)
			(xy 5.974571 -182.094254) (xy 5.930102 -182.038492) (xy 5.892156 -181.978101) (xy 5.861211 -181.913842)
			(xy 5.837654 -181.846522) (xy 5.821784 -181.776987) (xy 5.813798 -181.706113) (xy 4.583946 -181.706113)
			(xy 4.57596 -181.776987) (xy 4.56009 -181.846522) (xy 4.536533 -181.913842) (xy 4.505588 -181.978101)
			(xy 4.467642 -182.038492) (xy 4.423173 -182.094254) (xy 4.37274 -182.144687) (xy 4.316978 -182.189156)
			(xy 4.256587 -182.227102) (xy 4.192328 -182.258047) (xy 4.125008 -182.281604) (xy 4.055473 -182.297474)
			(xy 3.984599 -182.30546) (xy 3.913277 -182.30546) (xy 3.842403 -182.297474) (xy 3.772868 -182.281604)
			(xy 3.705548 -182.258047) (xy 3.641289 -182.227102) (xy 3.580898 -182.189156) (xy 3.525136 -182.144687)
			(xy 3.474703 -182.094254) (xy 3.430234 -182.038492) (xy 3.392288 -181.978101) (xy 3.361343 -181.913842)
			(xy 3.337786 -181.846522) (xy 3.321916 -181.776987) (xy 3.31393 -181.706113) (xy 1.525016 -181.706113)
			(xy 1.525016 -181.797198) (xy 1.525496 -181.819604) (xy 1.533363 -181.863722) (xy 1.548842 -181.905777)
			(xy 1.571453 -181.944468) (xy 1.600496 -181.978596) (xy 1.635072 -182.007104) (xy 1.67411 -182.02911)
			(xy 1.716401 -182.043933) (xy 1.760635 -182.051113) (xy 1.805443 -182.050428) (xy 1.82753 -182.046626)
			(xy 1.863115 -182.040219) (xy 1.935199 -182.034551) (xy 2.007461 -182.0371) (xy 2.078967 -182.047835)
			(xy 2.148792 -182.066616) (xy 2.216035 -182.0932) (xy 2.279825 -182.127245) (xy 2.33934 -182.16831)
			(xy 2.393809 -182.215864) (xy 2.442529 -182.269293) (xy 2.48487 -182.327907) (xy 2.520285 -182.390947)
			(xy 2.548316 -182.4576) (xy 2.568601 -182.527003) (xy 2.580878 -182.59826) (xy 2.584988 -182.67045)
			(xy 2.582958 -182.706111) (xy 7.813794 -182.706111) (xy 7.813794 -182.634789) (xy 7.82178 -182.563915)
			(xy 7.83765 -182.49438) (xy 7.861207 -182.42706) (xy 7.892152 -182.362801) (xy 7.930098 -182.30241)
			(xy 7.974567 -182.246648) (xy 8.025 -182.196215) (xy 8.080762 -182.151746) (xy 8.141153 -182.1138)
			(xy 8.205412 -182.082855) (xy 8.272732 -182.059298) (xy 8.342267 -182.043428) (xy 8.413141 -182.035442)
			(xy 8.484463 -182.035442) (xy 8.555337 -182.043428) (xy 8.624872 -182.059298) (xy 8.692192 -182.082855)
			(xy 8.756451 -182.1138) (xy 8.816842 -182.151746) (xy 8.872604 -182.196215) (xy 8.923037 -182.246648)
			(xy 8.967506 -182.30241) (xy 9.005452 -182.362801) (xy 9.036397 -182.42706) (xy 9.059954 -182.49438)
			(xy 9.075824 -182.563915) (xy 9.08381 -182.634789) (xy 9.08431 -182.67045) (xy 9.08381 -182.706111)
			(xy 9.075824 -182.776985) (xy 9.059954 -182.84652) (xy 9.036397 -182.91384) (xy 9.005452 -182.978099)
			(xy 8.967506 -183.03849) (xy 8.923037 -183.094252) (xy 8.872604 -183.144685) (xy 8.816842 -183.189154)
			(xy 8.756451 -183.2271) (xy 8.692192 -183.258045) (xy 8.624872 -183.281602) (xy 8.555337 -183.297472)
			(xy 8.484463 -183.305458) (xy 8.413141 -183.305458) (xy 8.342267 -183.297472) (xy 8.272732 -183.281602)
			(xy 8.205412 -183.258045) (xy 8.141153 -183.2271) (xy 8.080762 -183.189154) (xy 8.025 -183.144685)
			(xy 7.974567 -183.094252) (xy 7.930098 -183.03849) (xy 7.892152 -182.978099) (xy 7.861207 -182.91384)
			(xy 7.83765 -182.84652) (xy 7.82178 -182.776985) (xy 7.813794 -182.706111) (xy 2.582958 -182.706111)
			(xy 2.580878 -182.74264) (xy 2.568601 -182.813897) (xy 2.548316 -182.8833) (xy 2.520285 -182.949953)
			(xy 2.48487 -183.012993) (xy 2.442529 -183.071607) (xy 2.393809 -183.125036) (xy 2.33934 -183.17259)
			(xy 2.279825 -183.213655) (xy 2.216035 -183.2477) (xy 2.148792 -183.274284) (xy 2.078967 -183.293065)
			(xy 2.007461 -183.3038) (xy 1.935199 -183.306349) (xy 1.863115 -183.300681) (xy 1.82753 -183.294274)
			(xy 1.80544 -183.290457) (xy 1.760621 -183.28974) (xy 1.716372 -183.296899) (xy 1.674066 -183.311711)
			(xy 1.635014 -183.333716) (xy 1.60043 -183.362232) (xy 1.571385 -183.396374) (xy 1.548782 -183.435082)
			(xy 1.533321 -183.477156) (xy 1.525483 -183.521289) (xy 1.525016 -183.543702) (xy 1.525016 -183.797194)
			(xy 1.525496 -183.819601) (xy 1.533363 -183.863719) (xy 1.548841 -183.905774) (xy 1.571452 -183.944466)
			(xy 1.600495 -183.978594) (xy 1.635071 -184.007103) (xy 1.674109 -184.02911) (xy 1.7164 -184.043933)
			(xy 1.760635 -184.051113) (xy 1.805444 -184.050427) (xy 1.82753 -184.046622) (xy 1.863115 -184.040215)
			(xy 1.9352 -184.034546) (xy 2.007462 -184.037096) (xy 2.078968 -184.04783) (xy 2.148793 -184.066611)
			(xy 2.216036 -184.093196) (xy 2.279827 -184.12724) (xy 2.339341 -184.168305) (xy 2.393811 -184.215859)
			(xy 2.442531 -184.269289) (xy 2.484872 -184.327902) (xy 2.520287 -184.390942) (xy 2.548318 -184.457595)
			(xy 2.568603 -184.526999) (xy 2.58088 -184.598256) (xy 2.58499 -184.670446) (xy 2.58296 -184.706107)
			(xy 7.813794 -184.706107) (xy 7.813794 -184.634785) (xy 7.82178 -184.563911) (xy 7.83765 -184.494376)
			(xy 7.861207 -184.427056) (xy 7.892152 -184.362797) (xy 7.930098 -184.302406) (xy 7.974567 -184.246644)
			(xy 8.025 -184.196211) (xy 8.080762 -184.151742) (xy 8.141153 -184.113796) (xy 8.205412 -184.082851)
			(xy 8.272732 -184.059294) (xy 8.342267 -184.043424) (xy 8.413141 -184.035438) (xy 8.484463 -184.035438)
			(xy 8.555337 -184.043424) (xy 8.624872 -184.059294) (xy 8.692192 -184.082851) (xy 8.756451 -184.113796)
			(xy 8.816842 -184.151742) (xy 8.872604 -184.196211) (xy 8.923037 -184.246644) (xy 8.967506 -184.302406)
			(xy 9.005452 -184.362797) (xy 9.036397 -184.427056) (xy 9.059954 -184.494376) (xy 9.075824 -184.563911)
			(xy 9.08381 -184.634785) (xy 9.08431 -184.670446) (xy 9.08381 -184.706107) (xy 9.075824 -184.776981)
			(xy 9.059954 -184.846516) (xy 9.036397 -184.913836) (xy 9.005452 -184.978095) (xy 8.967506 -185.038486)
			(xy 8.923037 -185.094248) (xy 8.872604 -185.144681) (xy 8.816842 -185.18915) (xy 8.756451 -185.227096)
			(xy 8.692192 -185.258041) (xy 8.624872 -185.281598) (xy 8.555337 -185.297468) (xy 8.484463 -185.305454)
			(xy 8.413141 -185.305454) (xy 8.342267 -185.297468) (xy 8.272732 -185.281598) (xy 8.205412 -185.258041)
			(xy 8.141153 -185.227096) (xy 8.080762 -185.18915) (xy 8.025 -185.144681) (xy 7.974567 -185.094248)
			(xy 7.930098 -185.038486) (xy 7.892152 -184.978095) (xy 7.861207 -184.913836) (xy 7.83765 -184.846516)
			(xy 7.82178 -184.776981) (xy 7.813794 -184.706107) (xy 2.58296 -184.706107) (xy 2.58088 -184.742636)
			(xy 2.568603 -184.813893) (xy 2.548318 -184.883297) (xy 2.520287 -184.94995) (xy 2.484872 -185.01299)
			(xy 2.442531 -185.071603) (xy 2.393811 -185.125033) (xy 2.339341 -185.172587) (xy 2.279827 -185.213652)
			(xy 2.216036 -185.247696) (xy 2.148793 -185.274281) (xy 2.078968 -185.293062) (xy 2.007462 -185.303796)
			(xy 1.9352 -185.306346) (xy 1.863115 -185.300677) (xy 1.82753 -185.29427) (xy 1.80544 -185.290452)
			(xy 1.760621 -185.289736) (xy 1.716371 -185.296895) (xy 1.674065 -185.311706) (xy 1.635013 -185.333712)
			(xy 1.600428 -185.362227) (xy 1.571383 -185.396369) (xy 1.548779 -185.435077) (xy 1.533318 -185.477151)
			(xy 1.525479 -185.521285) (xy 1.525016 -185.543698) (xy 1.525016 -185.706105) (xy 3.31393 -185.706105)
			(xy 3.31393 -185.634783) (xy 3.321916 -185.563909) (xy 3.337786 -185.494374) (xy 3.361343 -185.427054)
			(xy 3.392288 -185.362795) (xy 3.430234 -185.302404) (xy 3.474703 -185.246642) (xy 3.525136 -185.196209)
			(xy 3.580898 -185.15174) (xy 3.641289 -185.113794) (xy 3.705548 -185.082849) (xy 3.772868 -185.059292)
			(xy 3.842403 -185.043422) (xy 3.913277 -185.035436) (xy 3.984599 -185.035436) (xy 4.055473 -185.043422)
			(xy 4.125008 -185.059292) (xy 4.192328 -185.082849) (xy 4.256587 -185.113794) (xy 4.316978 -185.15174)
			(xy 4.37274 -185.196209) (xy 4.423173 -185.246642) (xy 4.467642 -185.302404) (xy 4.505588 -185.362795)
			(xy 4.536533 -185.427054) (xy 4.56009 -185.494374) (xy 4.57596 -185.563909) (xy 4.583946 -185.634783)
			(xy 4.584446 -185.670444) (xy 4.583946 -185.706105) (xy 5.813798 -185.706105) (xy 5.813798 -185.634783)
			(xy 5.821784 -185.563909) (xy 5.837654 -185.494374) (xy 5.861211 -185.427054) (xy 5.892156 -185.362795)
			(xy 5.930102 -185.302404) (xy 5.974571 -185.246642) (xy 6.025004 -185.196209) (xy 6.080766 -185.15174)
			(xy 6.141157 -185.113794) (xy 6.205416 -185.082849) (xy 6.272736 -185.059292) (xy 6.342271 -185.043422)
			(xy 6.413145 -185.035436) (xy 6.484467 -185.035436) (xy 6.555341 -185.043422) (xy 6.624876 -185.059292)
			(xy 6.692196 -185.082849) (xy 6.756455 -185.113794) (xy 6.816846 -185.15174) (xy 6.872608 -185.196209)
			(xy 6.923041 -185.246642) (xy 6.96751 -185.302404) (xy 7.005456 -185.362795) (xy 7.036401 -185.427054)
			(xy 7.059958 -185.494374) (xy 7.075828 -185.563909) (xy 7.083814 -185.634783) (xy 7.084314 -185.670444)
			(xy 7.083814 -185.706105) (xy 7.075828 -185.776979) (xy 7.059958 -185.846514) (xy 7.036401 -185.913834)
			(xy 7.005456 -185.978093) (xy 6.96751 -186.038484) (xy 6.923041 -186.094246) (xy 6.872608 -186.144679)
			(xy 6.816846 -186.189148) (xy 6.756455 -186.227094) (xy 6.692196 -186.258039) (xy 6.624876 -186.281596)
			(xy 6.555341 -186.297466) (xy 6.484467 -186.305452) (xy 6.413145 -186.305452) (xy 6.342271 -186.297466)
			(xy 6.272736 -186.281596) (xy 6.205416 -186.258039) (xy 6.141157 -186.227094) (xy 6.080766 -186.189148)
			(xy 6.025004 -186.144679) (xy 5.974571 -186.094246) (xy 5.930102 -186.038484) (xy 5.892156 -185.978093)
			(xy 5.861211 -185.913834) (xy 5.837654 -185.846514) (xy 5.821784 -185.776979) (xy 5.813798 -185.706105)
			(xy 4.583946 -185.706105) (xy 4.57596 -185.776979) (xy 4.56009 -185.846514) (xy 4.536533 -185.913834)
			(xy 4.505588 -185.978093) (xy 4.467642 -186.038484) (xy 4.423173 -186.094246) (xy 4.37274 -186.144679)
			(xy 4.316978 -186.189148) (xy 4.256587 -186.227094) (xy 4.192328 -186.258039) (xy 4.125008 -186.281596)
			(xy 4.055473 -186.297466) (xy 3.984599 -186.305452) (xy 3.913277 -186.305452) (xy 3.842403 -186.297466)
			(xy 3.772868 -186.281596) (xy 3.705548 -186.258039) (xy 3.641289 -186.227094) (xy 3.580898 -186.189148)
			(xy 3.525136 -186.144679) (xy 3.474703 -186.094246) (xy 3.430234 -186.038484) (xy 3.392288 -185.978093)
			(xy 3.361343 -185.913834) (xy 3.337786 -185.846514) (xy 3.321916 -185.776979) (xy 3.31393 -185.706105)
			(xy 1.525016 -185.706105) (xy 1.525016 -187.706101) (xy 3.31393 -187.706101) (xy 3.31393 -187.634779)
			(xy 3.321916 -187.563905) (xy 3.337786 -187.49437) (xy 3.361343 -187.42705) (xy 3.392288 -187.362791)
			(xy 3.430234 -187.3024) (xy 3.474703 -187.246638) (xy 3.525136 -187.196205) (xy 3.580898 -187.151736)
			(xy 3.641289 -187.11379) (xy 3.705548 -187.082845) (xy 3.772868 -187.059288) (xy 3.842403 -187.043418)
			(xy 3.913277 -187.035432) (xy 3.984599 -187.035432) (xy 4.055473 -187.043418) (xy 4.125008 -187.059288)
			(xy 4.192328 -187.082845) (xy 4.256587 -187.11379) (xy 4.316978 -187.151736) (xy 4.37274 -187.196205)
			(xy 4.423173 -187.246638) (xy 4.467642 -187.3024) (xy 4.505588 -187.362791) (xy 4.536533 -187.42705)
			(xy 4.56009 -187.49437) (xy 4.57596 -187.563905) (xy 4.583946 -187.634779) (xy 4.584446 -187.67044)
			(xy 4.583946 -187.706101) (xy 4.57596 -187.776975) (xy 4.56009 -187.84651) (xy 4.536533 -187.91383)
			(xy 4.505588 -187.978089) (xy 4.467642 -188.03848) (xy 4.423173 -188.094242) (xy 4.37274 -188.144675)
			(xy 4.316978 -188.189144) (xy 4.256587 -188.22709) (xy 4.192328 -188.258035) (xy 4.125008 -188.281592)
			(xy 4.055473 -188.297462) (xy 3.984599 -188.305448) (xy 3.913277 -188.305448) (xy 3.842403 -188.297462)
			(xy 3.772868 -188.281592) (xy 3.705548 -188.258035) (xy 3.641289 -188.22709) (xy 3.580898 -188.189144)
			(xy 3.525136 -188.144675) (xy 3.474703 -188.094242) (xy 3.430234 -188.03848) (xy 3.392288 -187.978089)
			(xy 3.361343 -187.91383) (xy 3.337786 -187.84651) (xy 3.321916 -187.776975) (xy 3.31393 -187.706101)
			(xy 1.525016 -187.706101) (xy 1.525016 -187.797186) (xy 1.525496 -187.819593) (xy 1.533363 -187.86371)
			(xy 1.548842 -187.905766) (xy 1.571453 -187.944457) (xy 1.600496 -187.978585) (xy 1.635072 -188.007094)
			(xy 1.67411 -188.0291) (xy 1.716401 -188.043923) (xy 1.760635 -188.051103) (xy 1.805443 -188.050418)
			(xy 1.82753 -188.046614) (xy 1.863115 -188.040207) (xy 1.9352 -188.034539) (xy 2.007462 -188.037088)
			(xy 2.078968 -188.047823) (xy 2.148793 -188.066604) (xy 2.216036 -188.093189) (xy 2.279827 -188.127234)
			(xy 2.339341 -188.168299) (xy 2.393811 -188.215853) (xy 2.442531 -188.269282) (xy 2.484872 -188.327896)
			(xy 2.520287 -188.390937) (xy 2.548318 -188.457589) (xy 2.568603 -188.526993) (xy 2.58088 -188.59825)
			(xy 2.58499 -188.67044) (xy 2.58088 -188.742631) (xy 2.568603 -188.813888) (xy 2.548318 -188.883291)
			(xy 2.520286 -188.949944) (xy 2.484871 -189.012985) (xy 2.44253 -189.071598) (xy 2.39381 -189.125027)
			(xy 2.339341 -189.172582) (xy 2.279826 -189.213647) (xy 2.216035 -189.247692) (xy 2.148793 -189.274276)
			(xy 2.078967 -189.293057) (xy 2.007461 -189.303792) (xy 1.935199 -189.306341) (xy 1.863114 -189.300673)
			(xy 1.82753 -189.294262) (xy 1.80544 -189.290444) (xy 1.760621 -189.289728) (xy 1.716372 -189.296887)
			(xy 1.674065 -189.311698) (xy 1.635013 -189.333704) (xy 1.600429 -189.362219) (xy 1.571384 -189.396361)
			(xy 1.54878 -189.43507) (xy 1.533319 -189.477143) (xy 1.52548 -189.521277) (xy 1.525016 -189.54369)
			(xy 1.525016 -189.797182) (xy 1.525496 -189.819589) (xy 1.533362 -189.863707) (xy 1.54884 -189.905763)
			(xy 1.571451 -189.944455) (xy 1.600494 -189.978584) (xy 1.63507 -190.007093) (xy 1.674109 -190.0291)
			(xy 1.7164 -190.043923) (xy 1.760635 -190.051103) (xy 1.805444 -190.050417) (xy 1.82753 -190.04661)
			(xy 1.8415 -190.04407) (xy 1.875662 -190.038672) (xy 1.9447 -190.034447) (xy 2.013787 -190.037745)
			(xy 2.082108 -190.048527) (xy 2.148854 -190.066665) (xy 2.213235 -190.091946) (xy 2.274489 -190.12407)
			(xy 2.331891 -190.162657) (xy 2.384763 -190.20725) (xy 2.432479 -190.257322) (xy 2.474474 -190.31228)
			(xy 2.510252 -190.371474) (xy 2.539389 -190.434204) (xy 2.56154 -190.499728) (xy 2.576443 -190.567269)
		)
		(stroke
			(width 0)
			(type solid)
		)
		(fill yes)
		(layer "In5.Cu")
		(net "GND")
	)
	(gr_poly
		(pts
			(xy 48.223424 -260.186424) (xy 63.859156 -260.186424) (xy 80.55864 -243.48821) (xy 80.569986 -243.47606)
			(xy 80.58657 -243.447264) (xy 80.595159 -243.415163) (xy 80.595724 -243.398548) (xy 80.595724 -239.272572)
			(xy 80.579722 -239.24387) (xy 80.566809 -239.219529) (xy 80.547348 -239.16798) (xy 80.535507 -239.114167)
			(xy 80.531531 -239.059211) (xy 80.535504 -239.004254) (xy 80.547342 -238.95044) (xy 80.5668 -238.89889)
			(xy 80.579722 -238.874554) (xy 80.595724 -238.845852) (xy 80.595724 -235.877354) (xy 82.647028 -233.82605)
			(xy 82.647028 -231.426004) (xy 82.645138 -231.403734) (xy 82.634541 -231.360317) (xy 82.616519 -231.31942)
			(xy 82.591629 -231.282302) (xy 82.560635 -231.250104) (xy 82.524491 -231.223818) (xy 82.484311 -231.204253)
			(xy 82.441329 -231.19201) (xy 82.396869 -231.187467) (xy 82.3523 -231.190763) (xy 82.330544 -231.19588)
			(xy 82.294313 -231.205458) (xy 82.220399 -231.217843) (xy 82.145592 -231.222394) (xy 82.070721 -231.21906)
			(xy 81.996615 -231.207878) (xy 81.924094 -231.188972) (xy 81.853961 -231.162551) (xy 81.786992 -231.128908)
			(xy 81.723928 -231.088414) (xy 81.665468 -231.041519) (xy 81.612259 -230.988741) (xy 81.56489 -230.930665)
			(xy 81.523884 -230.867933) (xy 81.489697 -230.80124) (xy 81.462706 -230.731324) (xy 81.44321 -230.658959)
			(xy 81.431425 -230.584946) (xy 81.427482 -230.510105) (xy 81.431424 -230.435264) (xy 81.443208 -230.361251)
			(xy 81.462702 -230.288886) (xy 81.489692 -230.21897) (xy 81.523879 -230.152277) (xy 81.564883 -230.089544)
			(xy 81.612252 -230.031467) (xy 81.66546 -229.978688) (xy 81.72392 -229.931792) (xy 81.786983 -229.891297)
			(xy 81.853951 -229.857653) (xy 81.924084 -229.831231) (xy 81.996605 -229.812324) (xy 82.070711 -229.801141)
			(xy 82.145581 -229.797806) (xy 82.220388 -229.802356) (xy 82.294303 -229.81474) (xy 82.330544 -229.82428)
			(xy 82.35231 -229.829342) (xy 82.396873 -229.832636) (xy 82.441326 -229.828093) (xy 82.484301 -229.815854)
			(xy 82.524477 -229.796294) (xy 82.560617 -229.770015) (xy 82.59161 -229.737826) (xy 82.616502 -229.700717)
			(xy 82.634527 -229.65983) (xy 82.645131 -229.616422) (xy 82.647028 -229.594156) (xy 82.647028 -229.106984)
			(xy 86.238842 -225.514916) (xy 91.94546 -225.514916) (xy 93.189552 -226.759008) (xy 93.189552 -227.899722)
			(xy 93.065346 -228.023928) (xy 92.626688 -228.462332) (xy 91.556332 -228.462332) (xy 91.540506 -228.462818)
			(xy 91.509828 -228.470616) (xy 91.482008 -228.485715) (xy 91.458753 -228.50719) (xy 91.441492 -228.533723)
			(xy 91.431282 -228.563684) (xy 91.429586 -228.579426) (xy 91.429586 -228.57968) (xy 91.426208 -228.617156)
			(xy 91.412544 -228.691155) (xy 91.39115 -228.7633) (xy 91.362264 -228.832785) (xy 91.326209 -228.898834)
			(xy 91.283388 -228.960712) (xy 91.234277 -229.017727) (xy 91.179426 -229.069242) (xy 91.119445 -229.114684)
			(xy 91.055006 -229.153544) (xy 90.986827 -229.185389) (xy 90.915668 -229.209864) (xy 90.842325 -229.226695)
			(xy 90.767615 -229.235694) (xy 90.692373 -229.236762) (xy 90.617438 -229.229886) (xy 90.543646 -229.215143)
			(xy 90.471822 -229.192698) (xy 90.402766 -229.162801) (xy 90.33725 -229.125785) (xy 90.276005 -229.082064)
			(xy 90.219713 -229.032126) (xy 90.169004 -228.976528) (xy 90.124444 -228.91589) (xy 90.086529 -228.85089)
			(xy 90.055683 -228.782253) (xy 90.03225 -228.710745) (xy 90.016492 -228.637164) (xy 90.008585 -228.56233)
			(xy 90.008616 -228.487081) (xy 90.016585 -228.412254) (xy 90.032404 -228.338686) (xy 90.055896 -228.267197)
			(xy 90.086799 -228.198585) (xy 90.124768 -228.133617) (xy 90.169379 -228.073016) (xy 90.220134 -228.01746)
			(xy 90.276466 -227.967569) (xy 90.337748 -227.923898) (xy 90.403295 -227.886937) (xy 90.472375 -227.857097)
			(xy 90.544218 -227.834711) (xy 90.618022 -227.820029) (xy 90.692962 -227.813215) (xy 90.768204 -227.814345)
			(xy 90.842906 -227.823407) (xy 90.879676 -227.831396) (xy 90.919808 -227.840794) (xy 90.970862 -227.826824)
			(xy 91.093798 -227.826824) (xy 91.117173 -227.824812) (xy 91.162656 -227.813326) (xy 91.205261 -227.793696)
			(xy 91.243546 -227.766587) (xy 91.276211 -227.732918) (xy 91.30215 -227.693832) (xy 91.320482 -227.650652)
			(xy 91.330587 -227.604842) (xy 91.332122 -227.557957) (xy 91.325034 -227.511585) (xy 91.317826 -227.489258)
			(xy 91.305166 -227.451321) (xy 91.287456 -227.373328) (xy 91.278604 -227.29384) (xy 91.278722 -227.213861)
			(xy 91.287809 -227.1344) (xy 91.296236 -227.095304) (xy 91.299374 -227.079511) (xy 91.29849 -227.047332)
			(xy 91.289587 -227.016397) (xy 91.273231 -226.988672) (xy 91.2622 -226.97694) (xy 90.837512 -226.552252)
			(xy 90.304874 -226.552252) (xy 90.283127 -226.552692) (xy 90.240267 -226.56009) (xy 90.199294 -226.574683)
			(xy 90.161407 -226.596044) (xy 90.127713 -226.623547) (xy 90.099198 -226.65639) (xy 90.076696 -226.69361)
			(xy 90.060865 -226.734121) (xy 90.052168 -226.776736) (xy 90.050859 -226.82021) (xy 90.056976 -226.863272)
			(xy 90.070341 -226.904661) (xy 90.080084 -226.924108) (xy 90.097095 -226.957536) (xy 90.124795 -227.027243)
			(xy 90.145011 -227.099476) (xy 90.157519 -227.173435) (xy 90.16218 -227.248299) (xy 90.158943 -227.323238)
			(xy 90.147843 -227.397421) (xy 90.129004 -227.470025) (xy 90.102634 -227.540246) (xy 90.069026 -227.607304)
			(xy 90.028553 -227.670457) (xy 89.981663 -227.729003) (xy 89.928877 -227.782294) (xy 89.870779 -227.829738)
			(xy 89.808014 -227.87081) (xy 89.741278 -227.905054) (xy 89.671311 -227.93209) (xy 89.598889 -227.951618)
			(xy 89.524815 -227.963423) (xy 89.44991 -227.967372) (xy 89.375005 -227.963423) (xy 89.300931 -227.951618)
			(xy 89.228509 -227.93209) (xy 89.158542 -227.905054) (xy 89.091806 -227.87081) (xy 89.029041 -227.829738)
			(xy 88.970943 -227.782294) (xy 88.918157 -227.729003) (xy 88.871267 -227.670457) (xy 88.830794 -227.607304)
			(xy 88.797186 -227.540246) (xy 88.770816 -227.470025) (xy 88.751977 -227.397421) (xy 88.740877 -227.323238)
			(xy 88.73764 -227.248299) (xy 88.742301 -227.173435) (xy 88.754809 -227.099476) (xy 88.775025 -227.027243)
			(xy 88.802725 -226.957536) (xy 88.819736 -226.924108) (xy 88.829422 -226.904647) (xy 88.842735 -226.863268)
			(xy 88.848811 -226.820228) (xy 88.847475 -226.776781) (xy 88.838764 -226.734195) (xy 88.822934 -226.693713)
			(xy 88.800445 -226.656515) (xy 88.771954 -226.623687) (xy 88.738292 -226.596186) (xy 88.700441 -226.574815)
			(xy 88.659505 -226.560197) (xy 88.616679 -226.552758) (xy 88.594946 -226.552252) (xy 87.764874 -226.552252)
			(xy 87.743127 -226.552692) (xy 87.700267 -226.56009) (xy 87.659294 -226.574683) (xy 87.621407 -226.596044)
			(xy 87.587713 -226.623547) (xy 87.559198 -226.65639) (xy 87.536696 -226.69361) (xy 87.520865 -226.734121)
			(xy 87.512168 -226.776736) (xy 87.510859 -226.82021) (xy 87.516976 -226.863272) (xy 87.530341 -226.904661)
			(xy 87.540084 -226.924108) (xy 87.558364 -226.960131) (xy 87.587584 -227.035446) (xy 87.608087 -227.113585)
			(xy 87.61961 -227.193543) (xy 87.622005 -227.274291) (xy 87.615241 -227.354792) (xy 87.607902 -227.394516)
			(xy 87.603285 -227.41667) (xy 87.591591 -227.460391) (xy 87.584534 -227.481892) (xy 87.57099 -227.520357)
			(xy 87.53631 -227.594168) (xy 87.493423 -227.663532) (xy 87.442889 -227.72754) (xy 87.385371 -227.785354)
			(xy 87.321624 -227.836216) (xy 87.287354 -227.85832) (xy 87.27396 -227.867253) (xy 87.251812 -227.890607)
			(xy 87.236216 -227.918761) (xy 87.228163 -227.949923) (xy 87.227664 -227.966016) (xy 87.227664 -228.37267)
			(xy 87.228204 -228.389323) (xy 87.236816 -228.421495) (xy 87.253461 -228.450342) (xy 87.277005 -228.473899)
			(xy 87.305844 -228.490559) (xy 87.338012 -228.499188) (xy 87.354664 -228.49967) (xy 87.400892 -228.49967)
			(xy 87.47125 -228.440996) (xy 87.479632 -228.395784) (xy 87.486905 -228.358914) (xy 87.508205 -228.28684)
			(xy 87.536979 -228.217411) (xy 87.572908 -228.1514) (xy 87.61559 -228.089541) (xy 87.664552 -228.032523)
			(xy 87.719248 -227.98098) (xy 87.77907 -227.935486) (xy 87.843351 -227.896547) (xy 87.911377 -227.864597)
			(xy 87.98239 -227.839992) (xy 88.055601 -227.823004) (xy 88.130193 -227.813823) (xy 88.205338 -227.812552)
			(xy 88.280198 -227.819204) (xy 88.353941 -227.833705) (xy 88.425746 -227.855895) (xy 88.494814 -227.885525)
			(xy 88.560376 -227.922267) (xy 88.621702 -227.965712) (xy 88.678111 -228.015375) (xy 88.728973 -228.070704)
			(xy 88.773724 -228.131084) (xy 88.811865 -228.195842) (xy 88.842971 -228.264257) (xy 88.866697 -228.33557)
			(xy 88.882778 -228.408984) (xy 88.891036 -228.483685) (xy 88.891618 -228.52126) (xy 88.891264 -228.561792)
			(xy 88.88249 -228.642374) (xy 88.864617 -228.721437) (xy 88.837877 -228.797958) (xy 88.820752 -228.834696)
			(xy 88.803993 -228.868272) (xy 88.764413 -228.932033) (xy 88.741758 -228.96195) (xy 88.71599 -228.994165)
			(xy 88.658191 -229.053031) (xy 88.593969 -229.104813) (xy 88.559386 -229.127304) (xy 88.527429 -229.146879)
			(xy 88.460181 -229.17996) (xy 88.389828 -229.205791) (xy 88.31715 -229.224085) (xy 88.242952 -229.234639)
			(xy 88.168056 -229.237337) (xy 88.093291 -229.23215) (xy 88.019485 -229.219133) (xy 87.947455 -229.198432)
			(xy 87.878001 -229.170276) (xy 87.811889 -229.134977) (xy 87.749854 -229.092925) (xy 87.692582 -229.044586)
			(xy 87.640706 -228.990497) (xy 87.594803 -228.931254) (xy 87.55538 -228.867516) (xy 87.522873 -228.799988)
			(xy 87.509858 -228.764846) (xy 87.500835 -228.743911) (xy 87.476473 -228.705386) (xy 87.445632 -228.671822)
			(xy 87.409302 -228.644293) (xy 87.368646 -228.623683) (xy 87.324967 -228.610652) (xy 87.279664 -228.605617)
			(xy 87.234189 -228.60874) (xy 87.19 -228.61992) (xy 87.148511 -228.638799) (xy 87.111054 -228.664773)
			(xy 87.094568 -228.680518) (xy 87.065358 -228.709728) (xy 87.049582 -228.726195) (xy 87.023577 -228.763648)
			(xy 87.004671 -228.80514) (xy 86.993472 -228.84934) (xy 86.99034 -228.894829) (xy 86.995374 -228.940147)
			(xy 87.008413 -228.983839) (xy 87.029039 -229.024503) (xy 87.05659 -229.060835) (xy 87.090182 -229.091668)
			(xy 87.128736 -229.116012) (xy 87.149686 -229.125018) (xy 87.185017 -229.138185) (xy 87.252929 -229.170954)
			(xy 87.316995 -229.21072) (xy 87.376497 -229.257036) (xy 87.43077 -229.309383) (xy 87.479204 -229.367175)
			(xy 87.521256 -229.429764) (xy 87.556455 -229.496448) (xy 87.584407 -229.56648) (xy 87.604797 -229.639075)
			(xy 87.617399 -229.713418) (xy 87.622069 -229.788677) (xy 87.621788 -229.79507) (xy 88.737697 -229.79507)
			(xy 88.741732 -229.719366) (xy 88.753791 -229.644521) (xy 88.773737 -229.57138) (xy 88.801344 -229.500775)
			(xy 88.8363 -229.433504) (xy 88.878208 -229.370329) (xy 88.926594 -229.311967) (xy 88.98091 -229.259079)
			(xy 89.040539 -229.212264) (xy 89.104807 -229.172052) (xy 89.172984 -229.1389) (xy 89.2443 -229.113182)
			(xy 89.317945 -229.09519) (xy 89.393085 -229.085128) (xy 89.468869 -229.083109) (xy 89.544439 -229.089158)
			(xy 89.618937 -229.103205) (xy 89.69152 -229.125091) (xy 89.761366 -229.154568) (xy 89.827683 -229.191303)
			(xy 89.889719 -229.234878) (xy 89.946772 -229.2848) (xy 89.998196 -229.340504) (xy 90.043407 -229.401359)
			(xy 90.081894 -229.466674) (xy 90.11322 -229.53571) (xy 90.13703 -229.607685) (xy 90.153055 -229.681783)
			(xy 90.161114 -229.757164) (xy 90.161618 -229.79507) (xy 90.161114 -229.832976) (xy 90.153055 -229.908357)
			(xy 90.13703 -229.982455) (xy 90.11322 -230.05443) (xy 90.081894 -230.123466) (xy 90.043407 -230.188781)
			(xy 89.998196 -230.249636) (xy 89.946772 -230.30534) (xy 89.889719 -230.355262) (xy 89.827683 -230.398837)
			(xy 89.761366 -230.435572) (xy 89.69152 -230.465049) (xy 89.618937 -230.486935) (xy 89.544439 -230.500982)
			(xy 89.468869 -230.507031) (xy 89.393085 -230.505012) (xy 89.317945 -230.49495) (xy 89.2443 -230.476958)
			(xy 89.172984 -230.45124) (xy 89.104807 -230.418088) (xy 89.040539 -230.377876) (xy 88.98091 -230.331061)
			(xy 88.926594 -230.278173) (xy 88.878208 -230.219811) (xy 88.8363 -230.156636) (xy 88.801344 -230.089365)
			(xy 88.773737 -230.01876) (xy 88.753791 -229.945619) (xy 88.741732 -229.870774) (xy 88.737697 -229.79507)
			(xy 87.621788 -229.79507) (xy 87.618757 -229.864009) (xy 87.607498 -229.938567) (xy 87.58842 -230.011518)
			(xy 87.561736 -230.082042) (xy 87.527745 -230.14935) (xy 87.486829 -230.212688) (xy 87.439445 -230.271344)
			(xy 87.386126 -230.324661) (xy 87.327468 -230.372043) (xy 87.264129 -230.412957) (xy 87.19682 -230.446946)
			(xy 87.126295 -230.473628) (xy 87.053344 -230.492703) (xy 86.978784 -230.503959) (xy 86.903453 -230.507269)
			(xy 86.828194 -230.502596) (xy 86.753851 -230.489992) (xy 86.681257 -230.469599) (xy 86.611226 -230.441645)
			(xy 86.544543 -230.406443) (xy 86.481956 -230.364389) (xy 86.424166 -230.315953) (xy 86.37182 -230.261679)
			(xy 86.325506 -230.202175) (xy 86.285743 -230.138107) (xy 86.252976 -230.070195) (xy 86.239858 -230.034846)
			(xy 86.230835 -230.013911) (xy 86.206473 -229.975386) (xy 86.175632 -229.941822) (xy 86.139302 -229.914293)
			(xy 86.098646 -229.893683) (xy 86.054967 -229.880652) (xy 86.009664 -229.875617) (xy 85.964189 -229.87874)
			(xy 85.92 -229.88992) (xy 85.878511 -229.908799) (xy 85.841054 -229.934773) (xy 85.824568 -229.950518)
			(xy 85.795358 -229.979728) (xy 85.779582 -229.996195) (xy 85.753577 -230.033648) (xy 85.734671 -230.07514)
			(xy 85.723472 -230.11934) (xy 85.72034 -230.164829) (xy 85.725374 -230.210147) (xy 85.738413 -230.253839)
			(xy 85.759039 -230.294503) (xy 85.78659 -230.330835) (xy 85.820182 -230.361668) (xy 85.858736 -230.386012)
			(xy 85.879686 -230.395018) (xy 85.914931 -230.408153) (xy 85.982682 -230.440829) (xy 86.046612 -230.480465)
			(xy 86.106006 -230.52662) (xy 86.160205 -230.578779) (xy 86.208603 -230.63636) (xy 86.250661 -230.698722)
			(xy 86.285911 -230.765171) (xy 86.313959 -230.834966) (xy 86.324694 -230.871014) (xy 86.334731 -230.908285)
			(xy 86.347618 -230.984392) (xy 86.352195 -231.061447) (xy 86.352017 -231.06507) (xy 87.467697 -231.06507)
			(xy 87.471732 -230.989366) (xy 87.483791 -230.914521) (xy 87.503737 -230.84138) (xy 87.531344 -230.770775)
			(xy 87.5663 -230.703504) (xy 87.608208 -230.640329) (xy 87.656594 -230.581967) (xy 87.71091 -230.529079)
			(xy 87.770539 -230.482264) (xy 87.834807 -230.442052) (xy 87.902984 -230.4089) (xy 87.9743 -230.383182)
			(xy 88.047945 -230.36519) (xy 88.123085 -230.355128) (xy 88.198869 -230.353109) (xy 88.274439 -230.359158)
			(xy 88.348937 -230.373205) (xy 88.42152 -230.395091) (xy 88.491366 -230.424568) (xy 88.557683 -230.461303)
			(xy 88.619719 -230.504878) (xy 88.676772 -230.5548) (xy 88.728196 -230.610504) (xy 88.773407 -230.671359)
			(xy 88.811894 -230.736674) (xy 88.84322 -230.80571) (xy 88.86703 -230.877685) (xy 88.883055 -230.951783)
			(xy 88.891114 -231.027164) (xy 88.891618 -231.06507) (xy 88.891114 -231.102976) (xy 88.883055 -231.178357)
			(xy 88.86703 -231.252455) (xy 88.84322 -231.32443) (xy 88.811894 -231.393466) (xy 88.773407 -231.458781)
			(xy 88.728196 -231.519636) (xy 88.676772 -231.57534) (xy 88.619719 -231.625262) (xy 88.557683 -231.668837)
			(xy 88.491366 -231.705572) (xy 88.42152 -231.735049) (xy 88.348937 -231.756935) (xy 88.274439 -231.770982)
			(xy 88.198869 -231.777031) (xy 88.123085 -231.775012) (xy 88.047945 -231.76495) (xy 87.9743 -231.746958)
			(xy 87.902984 -231.72124) (xy 87.834807 -231.688088) (xy 87.770539 -231.647876) (xy 87.71091 -231.601061)
			(xy 87.656594 -231.548173) (xy 87.608208 -231.489811) (xy 87.5663 -231.426636) (xy 87.531344 -231.359365)
			(xy 87.503737 -231.28876) (xy 87.483791 -231.215619) (xy 87.471732 -231.140774) (xy 87.467697 -231.06507)
			(xy 86.352017 -231.06507) (xy 86.348409 -231.138544) (xy 86.336303 -231.21478) (xy 86.31602 -231.289258)
			(xy 86.287798 -231.361104) (xy 86.251969 -231.429475) (xy 86.208953 -231.493569) (xy 86.159254 -231.552632)
			(xy 86.103458 -231.605972) (xy 86.042217 -231.652961) (xy 85.976253 -231.693049) (xy 85.906338 -231.725765)
			(xy 85.833294 -231.750724) (xy 85.757979 -231.767634) (xy 85.681276 -231.776296) (xy 85.604086 -231.776609)
			(xy 85.527315 -231.768568) (xy 85.451865 -231.752269) (xy 85.41512 -231.740456) (xy 85.393178 -231.734849)
			(xy 85.348096 -231.730596) (xy 85.302972 -231.73439) (xy 85.259233 -231.746112) (xy 85.218259 -231.765391)
			(xy 85.181345 -231.791618) (xy 85.149656 -231.823965) (xy 85.124194 -231.861411) (xy 85.105762 -231.902772)
			(xy 85.094942 -231.946743) (xy 85.093048 -231.96931) (xy 85.093048 -234.125262) (xy 85.595968 -234.628182)
			(xy 85.595968 -236.806486) (xy 85.597941 -236.829582) (xy 85.609192 -236.874545) (xy 85.628393 -236.91673)
			(xy 85.654911 -236.954744) (xy 85.68787 -236.987333) (xy 85.726181 -237.013419) (xy 85.76858 -237.032143)
			(xy 85.813667 -237.042885) (xy 85.859954 -237.045292) (xy 85.882988 -237.042706) (xy 90.349832 -232.575862)
			(xy 90.349832 -231.740456) (xy 90.34942 -231.725558) (xy 90.342494 -231.696577) (xy 90.329031 -231.669995)
			(xy 90.309766 -231.647265) (xy 90.298016 -231.638094) (xy 90.26757 -231.615081) (xy 90.21128 -231.563539)
			(xy 90.16083 -231.506268) (xy 90.116802 -231.443925) (xy 90.0797 -231.377226) (xy 90.049952 -231.30694)
			(xy 90.038428 -231.270556) (xy 90.032358 -231.249816) (xy 90.022443 -231.20775) (xy 90.018616 -231.186482)
			(xy 90.013182 -231.152698) (xy 90.008034 -231.08446) (xy 90.009451 -231.016043) (xy 90.013028 -230.982012)
			(xy 90.017594 -230.946901) (xy 90.032799 -230.877744) (xy 90.054794 -230.810438) (xy 90.083362 -230.745648)
			(xy 90.11822 -230.684014) (xy 90.159026 -230.626146) (xy 90.205374 -230.572614) (xy 90.256808 -230.523948)
			(xy 90.284554 -230.501952) (xy 90.315205 -230.478879) (xy 90.380578 -230.438722) (xy 90.449891 -230.405829)
			(xy 90.52234 -230.38058) (xy 90.597084 -230.36327) (xy 90.673256 -230.354099) (xy 90.749972 -230.353173)
			(xy 90.826343 -230.360503) (xy 90.901483 -230.376003) (xy 90.97452 -230.399495) (xy 91.044607 -230.430706)
			(xy 91.110931 -230.469273) (xy 91.172722 -230.514749) (xy 91.229264 -230.566607) (xy 91.279901 -230.624246)
			(xy 91.324046 -230.686995) (xy 91.361186 -230.754129) (xy 91.390891 -230.824867) (xy 91.412816 -230.89839)
			(xy 91.420188 -230.936038) (xy 91.42857 -230.98125) (xy 91.498928 -231.039924) (xy 91.545156 -231.039924)
			(xy 91.561816 -231.039435) (xy 91.594002 -231.030821) (xy 91.622862 -231.01417) (xy 91.646429 -230.990617)
			(xy 91.663095 -230.961765) (xy 91.671726 -230.929583) (xy 91.672156 -230.912924) (xy 91.672156 -230.506016)
			(xy 91.671686 -230.489921) (xy 91.663628 -230.458756) (xy 91.648022 -230.430602) (xy 91.625862 -230.407254)
			(xy 91.612466 -230.39832) (xy 91.580921 -230.378012) (xy 91.521858 -230.331746) (xy 91.46799 -230.279522)
			(xy 91.419917 -230.22192) (xy 91.37817 -230.15958) (xy 91.343214 -230.093194) (xy 91.315437 -230.023498)
			(xy 91.295147 -229.951267) (xy 91.282569 -229.877302) (xy 91.277843 -229.802424) (xy 91.281021 -229.727464)
			(xy 91.292069 -229.653255) (xy 91.310863 -229.58062) (xy 91.337195 -229.510366) (xy 91.370772 -229.443272)
			(xy 91.411223 -229.380083) (xy 91.458097 -229.321501) (xy 91.510874 -229.268175) (xy 91.568969 -229.220699)
			(xy 91.631737 -229.179598) (xy 91.69848 -229.14533) (xy 91.768459 -229.118274) (xy 91.840896 -229.098731)
			(xy 91.914987 -229.086917) (xy 91.98991 -229.082965) (xy 92.064833 -229.086917) (xy 92.138924 -229.098731)
			(xy 92.211361 -229.118274) (xy 92.28134 -229.14533) (xy 92.348083 -229.179598) (xy 92.410851 -229.220699)
			(xy 92.468946 -229.268175) (xy 92.521723 -229.321501) (xy 92.568597 -229.380083) (xy 92.609048 -229.443272)
			(xy 92.642625 -229.510366) (xy 92.668957 -229.58062) (xy 92.687751 -229.653255) (xy 92.698799 -229.727464)
			(xy 92.701977 -229.802424) (xy 92.697251 -229.877302) (xy 92.684673 -229.951267) (xy 92.664383 -230.023498)
			(xy 92.636606 -230.093194) (xy 92.60165 -230.15958) (xy 92.559903 -230.22192) (xy 92.51183 -230.279522)
			(xy 92.457962 -230.331746) (xy 92.398899 -230.378012) (xy 92.367354 -230.39832) (xy 92.35396 -230.407253)
			(xy 92.331812 -230.430607) (xy 92.316216 -230.458761) (xy 92.308163 -230.489923) (xy 92.307664 -230.506016)
			(xy 92.307664 -230.51008) (xy 93.154506 -230.51008) (xy 93.158522 -230.39381) (xy 93.170549 -230.278095)
			(xy 93.190531 -230.163485) (xy 93.218373 -230.050526) (xy 93.253942 -229.939758) (xy 93.297068 -229.831707)
			(xy 93.347545 -229.726889) (xy 93.405134 -229.625804) (xy 93.46956 -229.528932) (xy 93.540515 -229.436736)
			(xy 93.617662 -229.349655) (xy 93.700633 -229.268104) (xy 93.789033 -229.192472) (xy 93.88244 -229.123118)
			(xy 93.980409 -229.060375) (xy 94.082473 -229.004539) (xy 94.188147 -228.955878) (xy 94.296926 -228.914624)
			(xy 94.408291 -228.880973) (xy 94.521714 -228.855085) (xy 94.636651 -228.837084) (xy 94.752557 -228.827055)
			(xy 94.868879 -228.825047) (xy 94.985062 -228.831069) (xy 95.100553 -228.845092) (xy 95.214801 -228.86705)
			(xy 95.327262 -228.896837) (xy 95.4374 -228.934312) (xy 95.54469 -228.979297) (xy 95.648621 -229.031576)
			(xy 95.748697 -229.090901) (xy 95.844443 -229.156989) (xy 95.9354 -229.229525) (xy 96.021136 -229.308164)
			(xy 96.101243 -229.39253) (xy 96.175339 -229.482222) (xy 96.243069 -229.576812) (xy 96.304113 -229.67585)
			(xy 96.358178 -229.778863) (xy 96.405008 -229.88536) (xy 96.444379 -229.994835) (xy 96.476103 -230.106765)
			(xy 96.500029 -230.220617) (xy 96.516043 -230.335849) (xy 96.52407 -230.451911) (xy 96.524572 -230.51008)
			(xy 96.52407 -230.568249) (xy 96.516043 -230.684311) (xy 96.500029 -230.799543) (xy 96.476103 -230.913395)
			(xy 96.444379 -231.025325) (xy 96.405008 -231.1348) (xy 96.358178 -231.241297) (xy 96.304113 -231.34431)
			(xy 96.243069 -231.443348) (xy 96.175339 -231.537938) (xy 96.101243 -231.62763) (xy 96.021136 -231.711996)
			(xy 95.9354 -231.790635) (xy 95.844443 -231.863171) (xy 95.748697 -231.929259) (xy 95.648621 -231.988584)
			(xy 95.54469 -232.040863) (xy 95.4374 -232.085848) (xy 95.327262 -232.123323) (xy 95.214801 -232.15311)
			(xy 95.100553 -232.175068) (xy 94.985062 -232.189091) (xy 94.868879 -232.195113) (xy 94.752557 -232.193105)
			(xy 94.636651 -232.183076) (xy 94.521714 -232.165075) (xy 94.408291 -232.139187) (xy 94.296926 -232.105536)
			(xy 94.188147 -232.064282) (xy 94.082473 -232.015621) (xy 93.980409 -231.959785) (xy 93.88244 -231.897042)
			(xy 93.789033 -231.827688) (xy 93.700633 -231.752056) (xy 93.617662 -231.670505) (xy 93.540515 -231.583424)
			(xy 93.46956 -231.491228) (xy 93.405134 -231.394356) (xy 93.347545 -231.293271) (xy 93.297068 -231.188453)
			(xy 93.253942 -231.080402) (xy 93.218373 -230.969634) (xy 93.190531 -230.856675) (xy 93.170549 -230.742065)
			(xy 93.158522 -230.62635) (xy 93.154506 -230.51008) (xy 92.307664 -230.51008) (xy 92.307664 -232.596436)
			(xy 87.66429 -237.240064) (xy 87.6554 -237.27156) (xy 87.647382 -237.29776) (xy 87.624876 -237.347715)
			(xy 87.595452 -237.393934) (xy 87.559715 -237.435466) (xy 87.518402 -237.471456) (xy 87.495634 -237.486698)
			(xy 87.484204 -237.494064) (xy 85.694012 -239.284256) (xy 85.694012 -241.67211) (xy 85.641688 -241.724434)
			(xy 85.641688 -242.000786) (xy 85.382367 -242.26012) (xy 86.877404 -242.26012) (xy 86.881424 -242.069469)
			(xy 86.893478 -241.879156) (xy 86.913544 -241.689521) (xy 86.941587 -241.5009) (xy 86.977556 -241.31363)
			(xy 87.021388 -241.128042) (xy 87.073005 -240.944467) (xy 87.132315 -240.763231) (xy 87.199213 -240.584656)
			(xy 87.273579 -240.409061) (xy 87.355281 -240.236756) (xy 87.444175 -240.068049) (xy 87.540101 -239.903239)
			(xy 87.64289 -239.74262) (xy 87.752359 -239.586477) (xy 87.868313 -239.435088) (xy 87.990547 -239.288721)
			(xy 88.118841 -239.147637) (xy 88.252969 -239.012088) (xy 88.392693 -238.882313) (xy 88.537763 -238.758543)
			(xy 88.687921 -238.641) (xy 88.842902 -238.529891) (xy 89.002429 -238.425414) (xy 89.166218 -238.327755)
			(xy 89.333978 -238.237088) (xy 89.505412 -238.153574) (xy 89.680214 -238.077361) (xy 89.858073 -238.008585)
			(xy 90.038674 -237.947367) (xy 90.221694 -237.893818) (xy 90.40681 -237.848032) (xy 90.593691 -237.81009)
			(xy 90.782006 -237.780061) (xy 90.971419 -237.757996) (xy 91.161593 -237.743937) (xy 91.352192 -237.737907)
			(xy 91.542875 -237.739917) (xy 91.733304 -237.749964) (xy 91.92314 -237.76803) (xy 92.112046 -237.794083)
			(xy 92.299685 -237.828076) (xy 92.485725 -237.869949) (xy 92.669834 -237.919628) (xy 92.851685 -237.977024)
			(xy 93.030955 -238.042035) (xy 93.207325 -238.114546) (xy 93.380481 -238.194427) (xy 93.550116 -238.281537)
			(xy 93.715928 -238.375721) (xy 93.877622 -238.476812) (xy 94.03491 -238.584628) (xy 94.187513 -238.69898)
			(xy 94.335161 -238.819663) (xy 94.477589 -238.946464) (xy 94.614545 -239.079155) (xy 94.745786 -239.217503)
			(xy 94.871078 -239.36126) (xy 94.990198 -239.510171) (xy 95.102934 -239.663972) (xy 95.209087 -239.822388)
			(xy 95.308467 -239.985139) (xy 95.400897 -240.151934) (xy 95.486214 -240.322478) (xy 95.564266 -240.496466)
			(xy 95.634913 -240.673591) (xy 95.698031 -240.853536) (xy 95.753507 -241.035982) (xy 95.801242 -241.220605)
			(xy 95.841152 -241.407075) (xy 95.873165 -241.595063) (xy 95.897225 -241.784233) (xy 95.913288 -241.974249)
			(xy 95.921327 -242.164773) (xy 95.92183 -242.26012) (xy 95.921327 -242.355467) (xy 95.913288 -242.545991)
			(xy 95.897225 -242.736007) (xy 95.873165 -242.925177) (xy 95.841152 -243.113165) (xy 95.801242 -243.299635)
			(xy 95.753507 -243.484258) (xy 95.698031 -243.666704) (xy 95.634913 -243.846649) (xy 95.564266 -244.023774)
			(xy 95.486214 -244.197762) (xy 95.400897 -244.368306) (xy 95.308467 -244.535101) (xy 95.209087 -244.697852)
			(xy 95.102934 -244.856268) (xy 94.990198 -245.010069) (xy 94.871078 -245.15898) (xy 94.745786 -245.302737)
			(xy 94.614545 -245.441085) (xy 94.477589 -245.573776) (xy 94.335161 -245.700577) (xy 94.187513 -245.82126)
			(xy 94.03491 -245.935612) (xy 93.877622 -246.043428) (xy 93.715928 -246.144519) (xy 93.550116 -246.238703)
			(xy 93.380481 -246.325813) (xy 93.207325 -246.405694) (xy 93.030955 -246.478205) (xy 92.851685 -246.543216)
			(xy 92.669834 -246.600612) (xy 92.485725 -246.650291) (xy 92.299685 -246.692164) (xy 92.112046 -246.726157)
			(xy 91.92314 -246.75221) (xy 91.733304 -246.770276) (xy 91.542875 -246.780323) (xy 91.352192 -246.782333)
			(xy 91.161593 -246.776303) (xy 90.971419 -246.762244) (xy 90.782006 -246.740179) (xy 90.593691 -246.71015)
			(xy 90.40681 -246.672208) (xy 90.221694 -246.626422) (xy 90.038674 -246.572873) (xy 89.858073 -246.511655)
			(xy 89.680214 -246.442879) (xy 89.505412 -246.366666) (xy 89.333978 -246.283152) (xy 89.166218 -246.192485)
			(xy 89.002429 -246.094826) (xy 88.842902 -245.990349) (xy 88.687921 -245.87924) (xy 88.537763 -245.761697)
			(xy 88.392693 -245.637927) (xy 88.252969 -245.508152) (xy 88.118841 -245.372603) (xy 87.990547 -245.231519)
			(xy 87.868313 -245.085152) (xy 87.752359 -244.933763) (xy 87.64289 -244.77762) (xy 87.540101 -244.617001)
			(xy 87.444175 -244.452191) (xy 87.355281 -244.283484) (xy 87.273579 -244.111179) (xy 87.199213 -243.935584)
			(xy 87.132315 -243.757009) (xy 87.073005 -243.575773) (xy 87.021388 -243.392198) (xy 86.977556 -243.20661)
			(xy 86.941587 -243.01934) (xy 86.913544 -242.830719) (xy 86.893478 -242.641084) (xy 86.881424 -242.450771)
			(xy 86.877404 -242.26012) (xy 85.382367 -242.26012) (xy 80.426052 -247.216676) (xy 80.411054 -247.232302)
			(xy 80.386076 -247.267682) (xy 80.367456 -247.306784) (xy 80.355732 -247.348475) (xy 80.351244 -247.391551)
			(xy 80.354122 -247.434764) (xy 80.364283 -247.476864) (xy 80.381432 -247.516633) (xy 80.405073 -247.55292)
			(xy 80.434522 -247.584675) (xy 80.451452 -247.598184) (xy 93.095318 -247.598184) (xy 99.119436 -241.574066)
			(xy 99.119436 -198.755254) (xy 91.898978 -191.534796) (xy 91.887548 -191.52743) (xy 91.864794 -191.51217)
			(xy 91.823493 -191.476171) (xy 91.78776 -191.434641) (xy 91.758328 -191.388431) (xy 91.7358 -191.33849)
			(xy 91.727782 -191.312292) (xy 91.718892 -191.280796) (xy 91.259152 -190.821056) (xy 88.558878 -190.821056)
			(xy 85.322156 -187.584588) (xy 85.322156 -187.326016) (xy 85.321686 -187.309921) (xy 85.313628 -187.278756)
			(xy 85.298022 -187.250602) (xy 85.275862 -187.227254) (xy 85.262466 -187.21832) (xy 85.231854 -187.198609)
			(xy 85.174406 -187.153871) (xy 85.121817 -187.10351) (xy 85.097874 -187.07608) (xy 85.075728 -187.049372)
			(xy 85.036159 -186.992375) (xy 85.01888 -186.962288) (xy 85.000506 -186.92838) (xy 84.97038 -186.85738)
			(xy 84.948109 -186.78354) (xy 84.933952 -186.707724) (xy 84.928077 -186.630821) (xy 84.930552 -186.553735)
			(xy 84.941348 -186.477368) (xy 84.960339 -186.402616) (xy 84.987302 -186.330356) (xy 85.021921 -186.261436)
			(xy 85.063789 -186.196663) (xy 85.112416 -186.136797) (xy 85.167231 -186.082541) (xy 85.227592 -186.03453)
			(xy 85.292791 -185.993328) (xy 85.362063 -185.959418) (xy 85.434595 -185.933197) (xy 85.509538 -185.914973)
			(xy 85.547708 -185.909458) (xy 85.593174 -185.903362) (xy 85.70976 -185.778394) (xy 85.70976 -184.911746)
			(xy 85.636354 -184.833006) (xy 85.593174 -184.786778) (xy 85.547962 -184.780682) (xy 85.509364 -184.775119)
			(xy 85.433596 -184.756646) (xy 85.360302 -184.730003) (xy 85.290358 -184.695509) (xy 85.224603 -184.653577)
			(xy 85.193886 -184.629552) (xy 85.162854 -184.603858) (xy 85.106205 -184.546566) (xy 85.080856 -184.515252)
			(xy 85.057016 -184.484085) (xy 85.015565 -184.417457) (xy 84.981692 -184.346674) (xy 84.95581 -184.272595)
			(xy 84.938231 -184.196119) (xy 84.929169 -184.118174) (xy 84.928735 -184.039705) (xy 84.936933 -183.961664)
			(xy 84.953663 -183.884999) (xy 84.978724 -183.810638) (xy 85.01181 -183.739484) (xy 85.052521 -183.6724)
			(xy 85.07603 -183.640984) (xy 85.099247 -183.611586) (xy 85.150904 -183.557329) (xy 85.207974 -183.508799)
			(xy 85.269825 -183.466531) (xy 85.335775 -183.430994) (xy 85.405092 -183.40258) (xy 85.47701 -183.381604)
			(xy 85.550733 -183.368299) (xy 85.625446 -183.36281) (xy 85.700323 -183.365199) (xy 85.774534 -183.37544)
			(xy 85.847259 -183.393419) (xy 85.917693 -183.418937) (xy 85.985058 -183.451712) (xy 86.048607 -183.491382)
			(xy 86.107638 -183.537507) (xy 86.161498 -183.589577) (xy 86.209591 -183.647017) (xy 86.251384 -183.70919)
			(xy 86.269322 -183.742076) (xy 86.279799 -183.760953) (xy 86.30615 -183.795149) (xy 86.337902 -183.824398)
			(xy 86.374141 -183.847858) (xy 86.413826 -183.864855) (xy 86.455812 -183.874898) (xy 86.498891 -183.877699)
			(xy 86.541825 -183.873177) (xy 86.583375 -183.861462) (xy 86.622348 -183.842891) (xy 86.65762 -183.817999)
			(xy 86.673182 -183.803036) (xy 86.684104 -183.792114) (xy 86.701884 -183.774588) (xy 87.50554 -183.774588)
			(xy 87.567262 -183.712866) (xy 87.575136 -183.70042) (xy 87.595366 -183.668679) (xy 87.641527 -183.609222)
			(xy 87.693707 -183.554969) (xy 87.751322 -183.506529) (xy 87.813729 -183.464441) (xy 87.88023 -183.429176)
			(xy 87.950083 -183.401129) (xy 88.022505 -183.380612) (xy 88.09669 -183.367856) (xy 88.171806 -183.363002)
			(xy 88.247015 -183.366104) (xy 88.321476 -183.377129) (xy 88.394357 -183.395953) (xy 88.464844 -183.422366)
			(xy 88.532149 -183.456072) (xy 88.595519 -183.496695) (xy 88.654247 -183.54378) (xy 88.707677 -183.596802)
			(xy 88.75521 -183.655168) (xy 88.796316 -183.718226) (xy 88.830536 -183.785271) (xy 88.857487 -183.855553)
			(xy 88.876868 -183.928289) (xy 88.888463 -184.002663) (xy 88.892005 -184.07507) (xy 90.007951 -184.07507)
			(xy 90.011986 -183.999366) (xy 90.024045 -183.924521) (xy 90.043991 -183.85138) (xy 90.071598 -183.780775)
			(xy 90.106554 -183.713504) (xy 90.148462 -183.650329) (xy 90.196848 -183.591967) (xy 90.251164 -183.539079)
			(xy 90.310793 -183.492264) (xy 90.375061 -183.452052) (xy 90.443238 -183.4189) (xy 90.514554 -183.393182)
			(xy 90.588199 -183.37519) (xy 90.663339 -183.365128) (xy 90.739123 -183.363109) (xy 90.814693 -183.369158)
			(xy 90.889191 -183.383205) (xy 90.961774 -183.405091) (xy 91.03162 -183.434568) (xy 91.097937 -183.471303)
			(xy 91.159973 -183.514878) (xy 91.217026 -183.5648) (xy 91.26845 -183.620504) (xy 91.313661 -183.681359)
			(xy 91.352148 -183.746674) (xy 91.383474 -183.81571) (xy 91.407284 -183.887685) (xy 91.423309 -183.961783)
			(xy 91.431368 -184.037164) (xy 91.431872 -184.07507) (xy 91.431368 -184.112976) (xy 91.423309 -184.188357)
			(xy 91.407284 -184.262455) (xy 91.383474 -184.33443) (xy 91.352148 -184.403466) (xy 91.313661 -184.468781)
			(xy 91.26845 -184.529636) (xy 91.217026 -184.58534) (xy 91.159973 -184.635262) (xy 91.097937 -184.678837)
			(xy 91.03162 -184.715572) (xy 90.961774 -184.745049) (xy 90.889191 -184.766935) (xy 90.814693 -184.780982)
			(xy 90.739123 -184.787031) (xy 90.663339 -184.785012) (xy 90.588199 -184.77495) (xy 90.514554 -184.756958)
			(xy 90.443238 -184.73124) (xy 90.375061 -184.698088) (xy 90.310793 -184.657876) (xy 90.251164 -184.611061)
			(xy 90.196848 -184.558173) (xy 90.148462 -184.499811) (xy 90.106554 -184.436636) (xy 90.071598 -184.369365)
			(xy 90.043991 -184.29876) (xy 90.024045 -184.225619) (xy 90.011986 -184.150774) (xy 90.007951 -184.07507)
			(xy 88.892005 -184.07507) (xy 88.892141 -184.077846) (xy 88.890602 -184.115456) (xy 88.888006 -184.152453)
			(xy 88.87609 -184.22566) (xy 88.856625 -184.297231) (xy 88.829821 -184.366388) (xy 88.79597 -184.432383)
			(xy 88.755438 -184.494499) (xy 88.708666 -184.552063) (xy 88.65616 -184.60445) (xy 88.59849 -184.651091)
			(xy 88.536282 -184.691482) (xy 88.47021 -184.725183) (xy 88.400991 -184.751829) (xy 88.329377 -184.771132)
			(xy 88.256143 -184.782881) (xy 88.182085 -184.78695) (xy 88.108004 -184.783294) (xy 88.034706 -184.771953)
			(xy 87.962985 -184.75305) (xy 87.893619 -184.726789) (xy 87.827361 -184.693457) (xy 87.764928 -184.653414)
			(xy 87.707 -184.607095) (xy 87.654203 -184.555001) (xy 87.60711 -184.497699) (xy 87.586312 -184.466992)
			(xy 87.577257 -184.454141) (xy 87.554038 -184.43296) (xy 87.526343 -184.418105) (xy 87.495855 -184.410477)
			(xy 87.48014 -184.410096) (xy 87.246714 -184.410096) (xy 87.231486 -184.410549) (xy 87.201901 -184.417777)
			(xy 87.174866 -184.431801) (xy 87.151918 -184.451825) (xy 87.134361 -184.476711) (xy 87.123193 -184.505045)
			(xy 87.12073 -184.520078) (xy 87.113618 -184.57291) (xy 87.19058 -184.68975) (xy 87.221822 -184.70499)
			(xy 87.255466 -184.721902) (xy 87.319328 -184.761808) (xy 87.37862 -184.808234) (xy 87.432678 -184.860662)
			(xy 87.480898 -184.918503) (xy 87.522741 -184.981113) (xy 87.55774 -185.047791) (xy 87.585503 -185.117792)
			(xy 87.60572 -185.190332) (xy 87.618165 -185.264602) (xy 87.622698 -185.339771) (xy 87.622456 -185.34507)
			(xy 88.737951 -185.34507) (xy 88.741986 -185.269366) (xy 88.754045 -185.194521) (xy 88.773991 -185.12138)
			(xy 88.801598 -185.050775) (xy 88.836554 -184.983504) (xy 88.878462 -184.920329) (xy 88.926848 -184.861967)
			(xy 88.981164 -184.809079) (xy 89.040793 -184.762264) (xy 89.105061 -184.722052) (xy 89.173238 -184.6889)
			(xy 89.244554 -184.663182) (xy 89.318199 -184.64519) (xy 89.393339 -184.635128) (xy 89.469123 -184.633109)
			(xy 89.544693 -184.639158) (xy 89.619191 -184.653205) (xy 89.691774 -184.675091) (xy 89.76162 -184.704568)
			(xy 89.827937 -184.741303) (xy 89.889973 -184.784878) (xy 89.947026 -184.8348) (xy 89.99845 -184.890504)
			(xy 90.043661 -184.951359) (xy 90.082148 -185.016674) (xy 90.113474 -185.08571) (xy 90.137284 -185.157685)
			(xy 90.153309 -185.231783) (xy 90.161368 -185.307164) (xy 90.161872 -185.34507) (xy 91.277951 -185.34507)
			(xy 91.281986 -185.269366) (xy 91.294045 -185.194521) (xy 91.313991 -185.12138) (xy 91.341598 -185.050775)
			(xy 91.376554 -184.983504) (xy 91.418462 -184.920329) (xy 91.466848 -184.861967) (xy 91.521164 -184.809079)
			(xy 91.580793 -184.762264) (xy 91.645061 -184.722052) (xy 91.713238 -184.6889) (xy 91.784554 -184.663182)
			(xy 91.858199 -184.64519) (xy 91.933339 -184.635128) (xy 92.009123 -184.633109) (xy 92.084693 -184.639158)
			(xy 92.159191 -184.653205) (xy 92.231774 -184.675091) (xy 92.30162 -184.704568) (xy 92.367937 -184.741303)
			(xy 92.429973 -184.784878) (xy 92.487026 -184.8348) (xy 92.53845 -184.890504) (xy 92.583661 -184.951359)
			(xy 92.622148 -185.016674) (xy 92.653474 -185.08571) (xy 92.677284 -185.157685) (xy 92.693309 -185.231783)
			(xy 92.701368 -185.307164) (xy 92.701872 -185.34507) (xy 92.701368 -185.382976) (xy 92.693309 -185.458357)
			(xy 92.677284 -185.532455) (xy 92.653474 -185.60443) (xy 92.622148 -185.673466) (xy 92.583661 -185.738781)
			(xy 92.53845 -185.799636) (xy 92.487026 -185.85534) (xy 92.429973 -185.905262) (xy 92.367937 -185.948837)
			(xy 92.30162 -185.985572) (xy 92.231774 -186.015049) (xy 92.159191 -186.036935) (xy 92.084693 -186.050982)
			(xy 92.009123 -186.057031) (xy 91.933339 -186.055012) (xy 91.858199 -186.04495) (xy 91.784554 -186.026958)
			(xy 91.713238 -186.00124) (xy 91.645061 -185.968088) (xy 91.580793 -185.927876) (xy 91.521164 -185.881061)
			(xy 91.466848 -185.828173) (xy 91.418462 -185.769811) (xy 91.376554 -185.706636) (xy 91.341598 -185.639365)
			(xy 91.313991 -185.56876) (xy 91.294045 -185.495619) (xy 91.281986 -185.420774) (xy 91.277951 -185.34507)
			(xy 90.161872 -185.34507) (xy 90.161368 -185.382976) (xy 90.153309 -185.458357) (xy 90.137284 -185.532455)
			(xy 90.113474 -185.60443) (xy 90.082148 -185.673466) (xy 90.043661 -185.738781) (xy 89.99845 -185.799636)
			(xy 89.947026 -185.85534) (xy 89.889973 -185.905262) (xy 89.827937 -185.948837) (xy 89.76162 -185.985572)
			(xy 89.691774 -186.015049) (xy 89.619191 -186.036935) (xy 89.544693 -186.050982) (xy 89.469123 -186.057031)
			(xy 89.393339 -186.055012) (xy 89.318199 -186.04495) (xy 89.244554 -186.026958) (xy 89.173238 -186.00124)
			(xy 89.105061 -185.968088) (xy 89.040793 -185.927876) (xy 88.981164 -185.881061) (xy 88.926848 -185.828173)
			(xy 88.878462 -185.769811) (xy 88.836554 -185.706636) (xy 88.801598 -185.639365) (xy 88.773991 -185.56876)
			(xy 88.754045 -185.495619) (xy 88.741986 -185.420774) (xy 88.737951 -185.34507) (xy 87.622456 -185.34507)
			(xy 87.619269 -185.414998) (xy 87.607916 -185.489442) (xy 87.588767 -185.562272) (xy 87.562035 -185.632673)
			(xy 87.528019 -185.699857) (xy 87.487099 -185.763075) (xy 87.439734 -185.821618) (xy 87.386451 -185.874834)
			(xy 87.327848 -185.922125) (xy 87.296498 -185.942986) (xy 87.283441 -185.951996) (xy 87.261866 -185.975239)
			(xy 87.246686 -186.003083) (xy 87.238837 -186.03381) (xy 87.238332 -186.049666) (xy 87.238332 -186.464702)
			(xy 87.2388 -186.480414) (xy 87.246488 -186.510884) (xy 87.261397 -186.538547) (xy 87.282621 -186.561722)
			(xy 87.308869 -186.579001) (xy 87.338547 -186.589333) (xy 87.354156 -186.591194) (xy 87.393272 -186.59475)
			(xy 87.47125 -186.535314) (xy 87.48014 -186.4868) (xy 87.48741 -186.44978) (xy 87.508749 -186.377414)
			(xy 87.537622 -186.307711) (xy 87.573705 -186.241452) (xy 87.616594 -186.179381) (xy 87.665806 -186.122194)
			(xy 87.720791 -186.070533) (xy 87.780931 -186.024976) (xy 87.845552 -185.986036) (xy 87.913929 -185.954148)
			(xy 87.985295 -185.929671) (xy 88.05885 -185.912879) (xy 88.133768 -185.903961) (xy 88.209209 -185.903015)
			(xy 88.284326 -185.910054) (xy 88.358278 -185.924998) (xy 88.430235 -185.94768) (xy 88.49939 -185.977844)
			(xy 88.564966 -186.015153) (xy 88.626229 -186.059189) (xy 88.682491 -186.109456) (xy 88.73312 -186.165392)
			(xy 88.777551 -186.226369) (xy 88.815282 -186.291703) (xy 88.845893 -186.360661) (xy 88.869039 -186.43247)
			(xy 88.88446 -186.506324) (xy 88.891984 -186.581395) (xy 88.89178 -186.61507) (xy 90.007951 -186.61507)
			(xy 90.011986 -186.539366) (xy 90.024045 -186.464521) (xy 90.043991 -186.39138) (xy 90.071598 -186.320775)
			(xy 90.106554 -186.253504) (xy 90.148462 -186.190329) (xy 90.196848 -186.131967) (xy 90.251164 -186.079079)
			(xy 90.310793 -186.032264) (xy 90.375061 -185.992052) (xy 90.443238 -185.9589) (xy 90.514554 -185.933182)
			(xy 90.588199 -185.91519) (xy 90.663339 -185.905128) (xy 90.739123 -185.903109) (xy 90.814693 -185.909158)
			(xy 90.889191 -185.923205) (xy 90.961774 -185.945091) (xy 91.03162 -185.974568) (xy 91.097937 -186.011303)
			(xy 91.159973 -186.054878) (xy 91.165918 -186.06008) (xy 93.15476 -186.06008) (xy 93.158776 -185.94381)
			(xy 93.170803 -185.828095) (xy 93.190785 -185.713485) (xy 93.218627 -185.600526) (xy 93.254196 -185.489758)
			(xy 93.297322 -185.381707) (xy 93.347799 -185.276889) (xy 93.405388 -185.175804) (xy 93.469814 -185.078932)
			(xy 93.540769 -184.986736) (xy 93.617916 -184.899655) (xy 93.700887 -184.818104) (xy 93.789287 -184.742472)
			(xy 93.882694 -184.673118) (xy 93.980663 -184.610375) (xy 94.082727 -184.554539) (xy 94.188401 -184.505878)
			(xy 94.29718 -184.464624) (xy 94.408545 -184.430973) (xy 94.521968 -184.405085) (xy 94.636905 -184.387084)
			(xy 94.752811 -184.377055) (xy 94.869133 -184.375047) (xy 94.985316 -184.381069) (xy 95.100807 -184.395092)
			(xy 95.215055 -184.41705) (xy 95.327516 -184.446837) (xy 95.437654 -184.484312) (xy 95.544944 -184.529297)
			(xy 95.648875 -184.581576) (xy 95.748951 -184.640901) (xy 95.844697 -184.706989) (xy 95.935654 -184.779525)
			(xy 96.02139 -184.858164) (xy 96.101497 -184.94253) (xy 96.175593 -185.032222) (xy 96.243323 -185.126812)
			(xy 96.304367 -185.22585) (xy 96.358432 -185.328863) (xy 96.405262 -185.43536) (xy 96.444633 -185.544835)
			(xy 96.476357 -185.656765) (xy 96.500283 -185.770617) (xy 96.516297 -185.885849) (xy 96.524324 -186.001911)
			(xy 96.524826 -186.06008) (xy 96.524324 -186.118249) (xy 96.516297 -186.234311) (xy 96.500283 -186.349543)
			(xy 96.476357 -186.463395) (xy 96.444633 -186.575325) (xy 96.405262 -186.6848) (xy 96.358432 -186.791297)
			(xy 96.304367 -186.89431) (xy 96.243323 -186.993348) (xy 96.175593 -187.087938) (xy 96.101497 -187.17763)
			(xy 96.02139 -187.261996) (xy 95.935654 -187.340635) (xy 95.844697 -187.413171) (xy 95.748951 -187.479259)
			(xy 95.648875 -187.538584) (xy 95.544944 -187.590863) (xy 95.437654 -187.635848) (xy 95.327516 -187.673323)
			(xy 95.215055 -187.70311) (xy 95.100807 -187.725068) (xy 94.985316 -187.739091) (xy 94.869133 -187.745113)
			(xy 94.752811 -187.743105) (xy 94.636905 -187.733076) (xy 94.521968 -187.715075) (xy 94.408545 -187.689187)
			(xy 94.29718 -187.655536) (xy 94.188401 -187.614282) (xy 94.082727 -187.565621) (xy 93.980663 -187.509785)
			(xy 93.882694 -187.447042) (xy 93.789287 -187.377688) (xy 93.700887 -187.302056) (xy 93.617916 -187.220505)
			(xy 93.540769 -187.133424) (xy 93.469814 -187.041228) (xy 93.405388 -186.944356) (xy 93.347799 -186.843271)
			(xy 93.297322 -186.738453) (xy 93.254196 -186.630402) (xy 93.218627 -186.519634) (xy 93.190785 -186.406675)
			(xy 93.170803 -186.292065) (xy 93.158776 -186.17635) (xy 93.15476 -186.06008) (xy 91.165918 -186.06008)
			(xy 91.217026 -186.1048) (xy 91.26845 -186.160504) (xy 91.313661 -186.221359) (xy 91.352148 -186.286674)
			(xy 91.383474 -186.35571) (xy 91.407284 -186.427685) (xy 91.423309 -186.501783) (xy 91.431368 -186.577164)
			(xy 91.431872 -186.61507) (xy 91.431368 -186.652976) (xy 91.423309 -186.728357) (xy 91.407284 -186.802455)
			(xy 91.383474 -186.87443) (xy 91.352148 -186.943466) (xy 91.313661 -187.008781) (xy 91.26845 -187.069636)
			(xy 91.217026 -187.12534) (xy 91.159973 -187.175262) (xy 91.097937 -187.218837) (xy 91.03162 -187.255572)
			(xy 90.961774 -187.285049) (xy 90.889191 -187.306935) (xy 90.814693 -187.320982) (xy 90.739123 -187.327031)
			(xy 90.663339 -187.325012) (xy 90.588199 -187.31495) (xy 90.514554 -187.296958) (xy 90.443238 -187.27124)
			(xy 90.375061 -187.238088) (xy 90.310793 -187.197876) (xy 90.251164 -187.151061) (xy 90.196848 -187.098173)
			(xy 90.148462 -187.039811) (xy 90.106554 -186.976636) (xy 90.071598 -186.909365) (xy 90.043991 -186.83876)
			(xy 90.024045 -186.765619) (xy 90.011986 -186.690774) (xy 90.007951 -186.61507) (xy 88.89178 -186.61507)
			(xy 88.891526 -186.65684) (xy 88.883091 -186.731814) (xy 88.875362 -186.76874) (xy 88.873838 -186.77509)
			(xy 88.87206 -186.789568) (xy 88.870793 -186.803845) (xy 88.873966 -186.832325) (xy 88.883438 -186.85937)
			(xy 88.898728 -186.883606) (xy 88.908636 -186.893962) (xy 90.325702 -188.311028) (xy 92.724732 -188.311028)
			(xy 95.74403 -191.330326) (xy 95.775526 -191.339216) (xy 95.801892 -191.3473) (xy 95.852149 -191.370004)
			(xy 95.898615 -191.399706) (xy 95.940321 -191.435786) (xy 95.9764 -191.477493) (xy 96.006101 -191.52396)
			(xy 96.028804 -191.574217) (xy 96.036892 -191.600582) (xy 96.045782 -191.632078) (xy 101.041454 -196.62775)
			(xy 101.058096 -196.643676) (xy 101.096009 -196.669831) (xy 101.138013 -196.688726) (xy 101.182736 -196.699741)
			(xy 101.228711 -196.702517) (xy 101.274434 -196.696962) (xy 101.318407 -196.683258) (xy 101.35919 -196.661855)
			(xy 101.395449 -196.633451) (xy 101.425995 -196.598979) (xy 101.449829 -196.559566) (xy 101.46617 -196.516504)
			(xy 101.474483 -196.471201) (xy 101.475032 -196.448172) (xy 101.475032 -53.653944) (xy 101.474535 -53.630909)
			(xy 101.466237 -53.585594) (xy 101.449905 -53.542517) (xy 101.426074 -53.50309) (xy 101.395526 -53.468607)
			(xy 101.359261 -53.440195) (xy 101.318467 -53.418788) (xy 101.274483 -53.405086) (xy 101.228749 -53.399539)
			(xy 101.182765 -53.402328) (xy 101.138037 -53.413362) (xy 101.096031 -53.432279) (xy 101.058124 -53.45846)
			(xy 101.041454 -53.474366) (xy 96.465136 -58.050684) (xy 89.866978 -58.050684) (xy 83.457542 -64.46012)
			(xy 86.877404 -64.46012) (xy 86.881424 -64.269469) (xy 86.893478 -64.079156) (xy 86.913544 -63.889521)
			(xy 86.941587 -63.7009) (xy 86.977556 -63.51363) (xy 87.021388 -63.328042) (xy 87.073005 -63.144467)
			(xy 87.132315 -62.963231) (xy 87.199213 -62.784656) (xy 87.273579 -62.609061) (xy 87.355281 -62.436756)
			(xy 87.444175 -62.268049) (xy 87.540101 -62.103239) (xy 87.64289 -61.94262) (xy 87.752359 -61.786477)
			(xy 87.868313 -61.635088) (xy 87.990547 -61.488721) (xy 88.118841 -61.347637) (xy 88.252969 -61.212088)
			(xy 88.392693 -61.082313) (xy 88.537763 -60.958543) (xy 88.687921 -60.841) (xy 88.842902 -60.729891)
			(xy 89.002429 -60.625414) (xy 89.166218 -60.527755) (xy 89.333978 -60.437088) (xy 89.505412 -60.353574)
			(xy 89.680214 -60.277361) (xy 89.858073 -60.208585) (xy 90.038674 -60.147367) (xy 90.221694 -60.093818)
			(xy 90.40681 -60.048032) (xy 90.593691 -60.01009) (xy 90.782006 -59.980061) (xy 90.971419 -59.957996)
			(xy 91.161593 -59.943937) (xy 91.352192 -59.937907) (xy 91.542875 -59.939917) (xy 91.733304 -59.949964)
			(xy 91.92314 -59.96803) (xy 92.112046 -59.994083) (xy 92.299685 -60.028076) (xy 92.485725 -60.069949)
			(xy 92.669834 -60.119628) (xy 92.851685 -60.177024) (xy 93.030955 -60.242035) (xy 93.207325 -60.314546)
			(xy 93.380481 -60.394427) (xy 93.550116 -60.481537) (xy 93.715928 -60.575721) (xy 93.877622 -60.676812)
			(xy 94.03491 -60.784628) (xy 94.187513 -60.89898) (xy 94.335161 -61.019663) (xy 94.477589 -61.146464)
			(xy 94.614545 -61.279155) (xy 94.745786 -61.417503) (xy 94.871078 -61.56126) (xy 94.990198 -61.710171)
			(xy 95.102934 -61.863972) (xy 95.209087 -62.022388) (xy 95.308467 -62.185139) (xy 95.400897 -62.351934)
			(xy 95.486214 -62.522478) (xy 95.564266 -62.696466) (xy 95.634913 -62.873591) (xy 95.698031 -63.053536)
			(xy 95.753507 -63.235982) (xy 95.801242 -63.420605) (xy 95.841152 -63.607075) (xy 95.873165 -63.795063)
			(xy 95.897225 -63.984233) (xy 95.913288 -64.174249) (xy 95.921327 -64.364773) (xy 95.92183 -64.46012)
			(xy 95.921327 -64.555467) (xy 95.913288 -64.745991) (xy 95.897225 -64.936007) (xy 95.873165 -65.125177)
			(xy 95.841152 -65.313165) (xy 95.801242 -65.499635) (xy 95.753507 -65.684258) (xy 95.698031 -65.866704)
			(xy 95.634913 -66.046649) (xy 95.564266 -66.223774) (xy 95.486214 -66.397762) (xy 95.400897 -66.568306)
			(xy 95.308467 -66.735101) (xy 95.209087 -66.897852) (xy 95.102934 -67.056268) (xy 94.990198 -67.210069)
			(xy 94.871078 -67.35898) (xy 94.745786 -67.502737) (xy 94.614545 -67.641085) (xy 94.477589 -67.773776)
			(xy 94.335161 -67.900577) (xy 94.187513 -68.02126) (xy 94.03491 -68.135612) (xy 93.877622 -68.243428)
			(xy 93.715928 -68.344519) (xy 93.550116 -68.438703) (xy 93.380481 -68.525813) (xy 93.207325 -68.605694)
			(xy 93.030955 -68.678205) (xy 92.851685 -68.743216) (xy 92.669834 -68.800612) (xy 92.485725 -68.850291)
			(xy 92.299685 -68.892164) (xy 92.112046 -68.926157) (xy 91.92314 -68.95221) (xy 91.733304 -68.970276)
			(xy 91.542875 -68.980323) (xy 91.352192 -68.982333) (xy 91.161593 -68.976303) (xy 90.971419 -68.962244)
			(xy 90.782006 -68.940179) (xy 90.593691 -68.91015) (xy 90.40681 -68.872208) (xy 90.221694 -68.826422)
			(xy 90.038674 -68.772873) (xy 89.858073 -68.711655) (xy 89.680214 -68.642879) (xy 89.505412 -68.566666)
			(xy 89.333978 -68.483152) (xy 89.166218 -68.392485) (xy 89.002429 -68.294826) (xy 88.842902 -68.190349)
			(xy 88.687921 -68.07924) (xy 88.537763 -67.961697) (xy 88.392693 -67.837927) (xy 88.252969 -67.708152)
			(xy 88.118841 -67.572603) (xy 87.990547 -67.431519) (xy 87.868313 -67.285152) (xy 87.752359 -67.133763)
			(xy 87.64289 -66.97762) (xy 87.540101 -66.817001) (xy 87.444175 -66.652191) (xy 87.355281 -66.483484)
			(xy 87.273579 -66.311179) (xy 87.199213 -66.135584) (xy 87.132315 -65.957009) (xy 87.073005 -65.775773)
			(xy 87.021388 -65.592198) (xy 86.977556 -65.40661) (xy 86.941587 -65.21934) (xy 86.913544 -65.030719)
			(xy 86.893478 -64.841084) (xy 86.881424 -64.650771) (xy 86.877404 -64.46012) (xy 83.457542 -64.46012)
			(xy 79.290418 -68.627244) (xy 78.95082 -68.627244) (xy 78.508606 -69.069458) (xy 77.550518 -69.069458)
			(xy 68.241303 -78.378673) (xy 74.888081 -78.378673) (xy 74.888081 -78.220963) (xy 74.896069 -78.063456)
			(xy 74.912025 -77.906556) (xy 74.935906 -77.750665) (xy 74.967653 -77.596184) (xy 75.007183 -77.443509)
			(xy 75.054395 -77.293033) (xy 75.109169 -77.14514) (xy 75.171362 -77.000212) (xy 75.240817 -76.85862)
			(xy 75.317353 -76.720727) (xy 75.400776 -76.586888) (xy 75.49087 -76.457446) (xy 75.587405 -76.332733)
			(xy 75.690133 -76.21307) (xy 75.798789 -76.098763) (xy 75.913096 -75.990107) (xy 76.032759 -75.887379)
			(xy 76.157472 -75.790844) (xy 76.286914 -75.70075) (xy 76.420753 -75.617327) (xy 76.558646 -75.540791)
			(xy 76.700238 -75.471336) (xy 76.845166 -75.409143) (xy 76.993059 -75.354369) (xy 77.143535 -75.307157)
			(xy 77.29621 -75.267627) (xy 77.450691 -75.23588) (xy 77.606582 -75.211999) (xy 77.763482 -75.196043)
			(xy 77.920989 -75.188055) (xy 78.078699 -75.188055) (xy 78.236206 -75.196043) (xy 78.393106 -75.211999)
			(xy 78.548997 -75.23588) (xy 78.703478 -75.267627) (xy 78.856153 -75.307157) (xy 79.006629 -75.354369)
			(xy 79.154522 -75.409143) (xy 79.29945 -75.471336) (xy 79.441042 -75.540791) (xy 79.578935 -75.617327)
			(xy 79.712774 -75.70075) (xy 79.842216 -75.790844) (xy 79.966929 -75.887379) (xy 80.086592 -75.990107)
			(xy 80.200899 -76.098763) (xy 80.309555 -76.21307) (xy 80.412283 -76.332733) (xy 80.508818 -76.457446)
			(xy 80.598912 -76.586888) (xy 80.682335 -76.720727) (xy 80.758871 -76.85862) (xy 80.828326 -77.000212)
			(xy 80.890519 -77.14514) (xy 80.945293 -77.293033) (xy 80.992505 -77.443509) (xy 81.032035 -77.596184)
			(xy 81.063782 -77.750665) (xy 81.087663 -77.906556) (xy 81.103619 -78.063456) (xy 81.111607 -78.220963)
			(xy 81.112106 -78.299818) (xy 81.111607 -78.378673) (xy 81.103619 -78.53618) (xy 81.087663 -78.69308)
			(xy 81.063782 -78.848971) (xy 81.032035 -79.003452) (xy 80.992505 -79.156127) (xy 80.965284 -79.242888)
			(xy 83.360086 -79.242888) (xy 83.363976 -79.188532) (xy 83.375562 -79.135284) (xy 83.394609 -79.084226)
			(xy 83.420728 -79.036399) (xy 83.453389 -78.992777) (xy 83.491926 -78.954247) (xy 83.535554 -78.921593)
			(xy 83.583385 -78.895482) (xy 83.634446 -78.876444) (xy 83.687696 -78.864867) (xy 83.742053 -78.860986)
			(xy 83.796408 -78.864882) (xy 83.849655 -78.876473) (xy 83.900711 -78.895526) (xy 83.948535 -78.92165)
			(xy 83.970622 -78.937612) (xy 83.989634 -78.951208) (xy 84.031517 -78.97194) (xy 84.076485 -78.984666)
			(xy 84.123022 -78.988956) (xy 84.169559 -78.984666) (xy 84.214527 -78.97194) (xy 84.25641 -78.951208)
			(xy 84.275422 -78.937612) (xy 84.297491 -78.921627) (xy 84.345316 -78.895507) (xy 84.396372 -78.87646)
			(xy 84.449619 -78.864872) (xy 84.503972 -78.860981) (xy 84.558327 -78.864864) (xy 84.611575 -78.876444)
			(xy 84.662634 -78.895484) (xy 84.710463 -78.921597) (xy 84.754089 -78.954251) (xy 84.792623 -78.992782)
			(xy 84.825281 -79.036404) (xy 84.851399 -79.08423) (xy 84.870445 -79.135287) (xy 84.88203 -79.188534)
			(xy 84.885919 -79.242888) (xy 86.164478 -79.242888) (xy 86.168368 -79.188531) (xy 86.179954 -79.13528)
			(xy 86.199002 -79.084221) (xy 86.225123 -79.036392) (xy 86.257785 -78.992768) (xy 86.296323 -78.954237)
			(xy 86.339953 -78.921584) (xy 86.387787 -78.895472) (xy 86.43885 -78.876434) (xy 86.492102 -78.864857)
			(xy 86.546461 -78.860978) (xy 86.600817 -78.864875) (xy 86.654066 -78.876468) (xy 86.705123 -78.895522)
			(xy 86.752948 -78.921649) (xy 86.775036 -78.937612) (xy 86.794048 -78.951208) (xy 86.835931 -78.97194)
			(xy 86.880899 -78.984666) (xy 86.927436 -78.988956) (xy 86.973973 -78.984666) (xy 87.018941 -78.97194)
			(xy 87.060824 -78.951208) (xy 87.079836 -78.937612) (xy 87.101905 -78.921628) (xy 87.149729 -78.895511)
			(xy 87.200783 -78.876465) (xy 87.254028 -78.864879) (xy 87.30838 -78.860989) (xy 87.362733 -78.864874)
			(xy 87.415979 -78.876454) (xy 87.467036 -78.895494) (xy 87.514863 -78.921607) (xy 87.558486 -78.95426)
			(xy 87.597019 -78.99279) (xy 87.629676 -79.036411) (xy 87.655793 -79.084236) (xy 87.674837 -79.13529)
			(xy 87.686422 -79.188536) (xy 87.690311 -79.242888) (xy 87.686425 -79.29724) (xy 87.674844 -79.350487)
			(xy 87.655803 -79.401543) (xy 87.629689 -79.449369) (xy 87.597035 -79.492992) (xy 87.558504 -79.531524)
			(xy 87.514883 -79.56418) (xy 87.467057 -79.590296) (xy 87.416002 -79.609339) (xy 87.362757 -79.620923)
			(xy 87.308404 -79.624811) (xy 87.254052 -79.620924) (xy 87.200806 -79.609342) (xy 87.149751 -79.590299)
			(xy 87.101925 -79.564185) (xy 87.079836 -79.548228) (xy 87.060824 -79.534632) (xy 87.018941 -79.5139)
			(xy 86.973973 -79.501174) (xy 86.927436 -79.496884) (xy 86.880899 -79.501174) (xy 86.835931 -79.5139)
			(xy 86.794048 -79.534632) (xy 86.775036 -79.548228) (xy 86.752928 -79.564164) (xy 86.705101 -79.590288)
			(xy 86.654043 -79.609339) (xy 86.600794 -79.620929) (xy 86.546437 -79.624822) (xy 86.492079 -79.620939)
			(xy 86.438827 -79.609359) (xy 86.387765 -79.590318) (xy 86.339933 -79.564204) (xy 86.296305 -79.531547)
			(xy 86.257769 -79.493013) (xy 86.22511 -79.449387) (xy 86.198992 -79.401557) (xy 86.179948 -79.350497)
			(xy 86.168364 -79.297246) (xy 86.164478 -79.242888) (xy 84.885919 -79.242888) (xy 84.882033 -79.297242)
			(xy 84.870452 -79.35049) (xy 84.851409 -79.401548) (xy 84.825294 -79.449376) (xy 84.792639 -79.493)
			(xy 84.754107 -79.531533) (xy 84.710483 -79.56419) (xy 84.662656 -79.590306) (xy 84.611598 -79.609349)
			(xy 84.558351 -79.620932) (xy 84.503996 -79.624819) (xy 84.449642 -79.620931) (xy 84.396395 -79.609347)
			(xy 84.345338 -79.590303) (xy 84.297511 -79.564186) (xy 84.275422 -79.548228) (xy 84.25641 -79.534632)
			(xy 84.214527 -79.5139) (xy 84.169559 -79.501174) (xy 84.123022 -79.496884) (xy 84.076485 -79.501174)
			(xy 84.031517 -79.5139) (xy 83.989634 -79.534632) (xy 83.970622 -79.548228) (xy 83.948515 -79.564163)
			(xy 83.900689 -79.590284) (xy 83.849632 -79.609333) (xy 83.796384 -79.620922) (xy 83.742029 -79.624814)
			(xy 83.687673 -79.62093) (xy 83.634423 -79.609349) (xy 83.583363 -79.590308) (xy 83.535533 -79.564194)
			(xy 83.491907 -79.531538) (xy 83.453373 -79.493005) (xy 83.420715 -79.44938) (xy 83.394599 -79.401552)
			(xy 83.375555 -79.350493) (xy 83.363972 -79.297244) (xy 83.360086 -79.242888) (xy 80.965284 -79.242888)
			(xy 80.945293 -79.306603) (xy 80.890519 -79.454496) (xy 80.828326 -79.599424) (xy 80.758871 -79.741016)
			(xy 80.682335 -79.878909) (xy 80.598912 -80.012748) (xy 80.508818 -80.14219) (xy 80.412283 -80.266903)
			(xy 80.309555 -80.386566) (xy 80.200899 -80.500873) (xy 80.086592 -80.609529) (xy 79.966929 -80.712257)
			(xy 79.842216 -80.808792) (xy 79.712774 -80.898886) (xy 79.658079 -80.932978) (xy 83.380882 -80.932978)
			(xy 83.384774 -80.878621) (xy 83.396362 -80.825371) (xy 83.415411 -80.774312) (xy 83.441533 -80.726484)
			(xy 83.474197 -80.682861) (xy 83.512737 -80.644332) (xy 83.556368 -80.611679) (xy 83.604203 -80.585569)
			(xy 83.655266 -80.566534) (xy 83.70852 -80.554959) (xy 83.762878 -80.551082) (xy 83.817235 -80.554982)
			(xy 83.870483 -80.566578) (xy 83.921539 -80.585634) (xy 83.969363 -80.611764) (xy 83.99145 -80.627728)
			(xy 84.010462 -80.641324) (xy 84.052345 -80.662056) (xy 84.097313 -80.674782) (xy 84.14385 -80.679072)
			(xy 84.190387 -80.674782) (xy 84.235355 -80.662056) (xy 84.277238 -80.641324) (xy 84.29625 -80.627728)
			(xy 84.318306 -80.611715) (xy 84.366137 -80.585582) (xy 84.4172 -80.566522) (xy 84.470457 -80.554925)
			(xy 84.524822 -80.551025) (xy 84.579189 -80.554902) (xy 84.63245 -80.566478) (xy 84.683521 -80.585517)
			(xy 84.731363 -80.611631) (xy 84.775001 -80.644288) (xy 84.813547 -80.682824) (xy 84.846215 -80.726453)
			(xy 84.872342 -80.774288) (xy 84.891394 -80.825355) (xy 84.902984 -80.878613) (xy 84.906875 -80.932978)
			(xy 86.185434 -80.932978) (xy 86.189324 -80.878633) (xy 86.200909 -80.825394) (xy 86.219952 -80.774346)
			(xy 86.246067 -80.726527) (xy 86.278721 -80.682912) (xy 86.31725 -80.644388) (xy 86.36087 -80.611739)
			(xy 86.408692 -80.585631) (xy 86.459743 -80.566594) (xy 86.512983 -80.555017) (xy 86.567329 -80.551134)
			(xy 86.621675 -80.555025) (xy 86.674913 -80.566611) (xy 86.725961 -80.585655) (xy 86.773779 -80.611771)
			(xy 86.795864 -80.627728) (xy 86.814876 -80.641324) (xy 86.856759 -80.662056) (xy 86.901727 -80.674782)
			(xy 86.948264 -80.679072) (xy 86.994801 -80.674782) (xy 87.039769 -80.662056) (xy 87.081652 -80.641324)
			(xy 87.100664 -80.627728) (xy 87.122719 -80.611716) (xy 87.170549 -80.585585) (xy 87.221612 -80.566528)
			(xy 87.274867 -80.554932) (xy 87.32923 -80.551033) (xy 87.383595 -80.554912) (xy 87.436854 -80.566488)
			(xy 87.487923 -80.585527) (xy 87.535763 -80.611641) (xy 87.579399 -80.644297) (xy 87.617943 -80.682832)
			(xy 87.65061 -80.72646) (xy 87.676735 -80.774294) (xy 87.695786 -80.825358) (xy 87.707375 -80.878615)
			(xy 87.711267 -80.932978) (xy 87.707381 -80.987343) (xy 87.695798 -81.0406) (xy 87.676753 -81.091667)
			(xy 87.650633 -81.139504) (xy 87.617971 -81.183135) (xy 87.579431 -81.221675) (xy 87.535799 -81.254336)
			(xy 87.487962 -81.280455) (xy 87.436895 -81.2995) (xy 87.383637 -81.311082) (xy 87.329273 -81.314967)
			(xy 87.274909 -81.311075) (xy 87.221653 -81.299485) (xy 87.170589 -81.280433) (xy 87.122756 -81.254307)
			(xy 87.100664 -81.238344) (xy 87.081652 -81.224748) (xy 87.039769 -81.204016) (xy 86.994801 -81.19129)
			(xy 86.948264 -81.187) (xy 86.901727 -81.19129) (xy 86.856759 -81.204016) (xy 86.814876 -81.224748)
			(xy 86.795864 -81.238344) (xy 86.773743 -81.254252) (xy 86.725922 -81.280363) (xy 86.674872 -81.299401)
			(xy 86.621632 -81.310981) (xy 86.567286 -81.314866) (xy 86.51294 -81.310977) (xy 86.459701 -81.299394)
			(xy 86.408652 -81.280351) (xy 86.360833 -81.254237) (xy 86.317218 -81.221584) (xy 86.278693 -81.183055)
			(xy 86.246044 -81.139437) (xy 86.219934 -81.091615) (xy 86.200896 -81.040565) (xy 86.189318 -80.987325)
			(xy 86.185434 -80.932978) (xy 84.906875 -80.932978) (xy 84.90299 -80.987344) (xy 84.891406 -81.040604)
			(xy 84.87236 -81.091673) (xy 84.846239 -81.139511) (xy 84.813575 -81.183144) (xy 84.775034 -81.221684)
			(xy 84.731399 -81.254346) (xy 84.683561 -81.280465) (xy 84.632491 -81.29951) (xy 84.579231 -81.311092)
			(xy 84.524865 -81.314975) (xy 84.4705 -81.311082) (xy 84.417242 -81.29949) (xy 84.366176 -81.280436)
			(xy 84.318342 -81.254308) (xy 84.29625 -81.238344) (xy 84.277238 -81.224748) (xy 84.235355 -81.204016)
			(xy 84.190387 -81.19129) (xy 84.14385 -81.187) (xy 84.097313 -81.19129) (xy 84.052345 -81.204016)
			(xy 84.010462 -81.224748) (xy 83.99145 -81.238344) (xy 83.969327 -81.25426) (xy 83.9215 -81.280384)
			(xy 83.870442 -81.299435) (xy 83.817192 -81.311025) (xy 83.762835 -81.314918) (xy 83.708477 -81.311035)
			(xy 83.655225 -81.299454) (xy 83.604163 -81.280413) (xy 83.556332 -81.254297) (xy 83.512704 -81.22164)
			(xy 83.474169 -81.183106) (xy 83.44151 -81.139479) (xy 83.415393 -81.091649) (xy 83.396349 -81.040588)
			(xy 83.384767 -80.987336) (xy 83.380882 -80.932978) (xy 79.658079 -80.932978) (xy 79.578935 -80.982309)
			(xy 79.441042 -81.058845) (xy 79.29945 -81.1283) (xy 79.154522 -81.190493) (xy 79.006629 -81.245267)
			(xy 78.856153 -81.292479) (xy 78.703478 -81.332009) (xy 78.548997 -81.363756) (xy 78.393106 -81.387637)
			(xy 78.236206 -81.403593) (xy 78.078699 -81.411581) (xy 77.920989 -81.411581) (xy 77.763482 -81.403593)
			(xy 77.606582 -81.387637) (xy 77.450691 -81.363756) (xy 77.29621 -81.332009) (xy 77.143535 -81.292479)
			(xy 76.993059 -81.245267) (xy 76.845166 -81.190493) (xy 76.700238 -81.1283) (xy 76.558646 -81.058845)
			(xy 76.420753 -80.982309) (xy 76.286914 -80.898886) (xy 76.157472 -80.808792) (xy 76.032759 -80.712257)
			(xy 75.913096 -80.609529) (xy 75.798789 -80.500873) (xy 75.690133 -80.386566) (xy 75.587405 -80.266903)
			(xy 75.49087 -80.14219) (xy 75.400776 -80.012748) (xy 75.317353 -79.878909) (xy 75.240817 -79.741016)
			(xy 75.171362 -79.599424) (xy 75.109169 -79.454496) (xy 75.054395 -79.306603) (xy 75.007183 -79.156127)
			(xy 74.967653 -79.003452) (xy 74.935906 -78.848971) (xy 74.912025 -78.69308) (xy 74.896069 -78.53618)
			(xy 74.888081 -78.378673) (xy 68.241303 -78.378673) (xy 63.83247 -82.787506) (xy 83.380846 -82.787506)
			(xy 83.384733 -82.733143) (xy 83.396319 -82.679887) (xy 83.415366 -82.628822) (xy 83.441487 -82.580988)
			(xy 83.474151 -82.537358) (xy 83.512692 -82.498822) (xy 83.556325 -82.466163) (xy 83.604162 -82.440047)
			(xy 83.65523 -82.421006) (xy 83.708487 -82.409427) (xy 83.76285 -82.405546) (xy 83.817213 -82.409441)
			(xy 83.870467 -82.421034) (xy 83.92153 -82.440089) (xy 83.96936 -82.466218) (xy 83.99145 -82.482182)
			(xy 84.010462 -82.495778) (xy 84.052345 -82.51651) (xy 84.097313 -82.529236) (xy 84.14385 -82.533526)
			(xy 84.190387 -82.529236) (xy 84.235355 -82.51651) (xy 84.277238 -82.495778) (xy 84.29625 -82.482182)
			(xy 84.318349 -82.466231) (xy 84.366177 -82.440104) (xy 84.417237 -82.42105) (xy 84.470489 -82.409457)
			(xy 84.52485 -82.405562) (xy 84.579211 -82.409443) (xy 84.632466 -82.421021) (xy 84.683531 -82.440062)
			(xy 84.731366 -82.466177) (xy 84.774998 -82.498834) (xy 84.813537 -82.537369) (xy 84.846199 -82.580996)
			(xy 84.87232 -82.628828) (xy 84.891366 -82.679891) (xy 84.902951 -82.733145) (xy 84.906838 -82.787506)
			(xy 86.185397 -82.787506) (xy 86.189284 -82.733155) (xy 86.200865 -82.67991) (xy 86.219907 -82.628855)
			(xy 86.246021 -82.58103) (xy 86.278675 -82.537409) (xy 86.317205 -82.498878) (xy 86.360827 -82.466223)
			(xy 86.408651 -82.440109) (xy 86.459706 -82.421067) (xy 86.51295 -82.409484) (xy 86.567302 -82.405597)
			(xy 86.621653 -82.409485) (xy 86.674897 -82.421068) (xy 86.725952 -82.44011) (xy 86.773776 -82.466225)
			(xy 86.795864 -82.482182) (xy 86.814876 -82.495778) (xy 86.856759 -82.51651) (xy 86.901727 -82.529236)
			(xy 86.948264 -82.533526) (xy 86.994801 -82.529236) (xy 87.039769 -82.51651) (xy 87.081652 -82.495778)
			(xy 87.100664 -82.482182) (xy 87.122762 -82.466232) (xy 87.17059 -82.440107) (xy 87.221649 -82.421055)
			(xy 87.274899 -82.409464) (xy 87.329257 -82.40557) (xy 87.383617 -82.409452) (xy 87.43687 -82.421031)
			(xy 87.487933 -82.440072) (xy 87.535766 -82.466187) (xy 87.579396 -82.498843) (xy 87.617933 -82.537377)
			(xy 87.624151 -82.545682) (xy 91.625926 -82.545682) (xy 91.629997 -82.49006) (xy 91.642123 -82.435623)
			(xy 91.662046 -82.383532) (xy 91.689342 -82.334897) (xy 91.723428 -82.290754) (xy 91.763577 -82.252045)
			(xy 91.808935 -82.219594) (xy 91.858535 -82.194093) (xy 91.911319 -82.176086) (xy 91.966162 -82.165956)
			(xy 92.021896 -82.163919) (xy 92.077333 -82.170019) (xy 92.13129 -82.184125) (xy 92.182619 -82.205937)
			(xy 92.230225 -82.234991) (xy 92.273093 -82.270666) (xy 92.31031 -82.312203) (xy 92.341083 -82.358716)
			(xy 92.364755 -82.409213) (xy 92.380823 -82.46262) (xy 92.388943 -82.517796) (xy 92.389452 -82.545682)
			(xy 92.388943 -82.573568) (xy 92.380823 -82.628744) (xy 92.364755 -82.682151) (xy 92.341083 -82.732648)
			(xy 92.31031 -82.779161) (xy 92.273093 -82.820698) (xy 92.230225 -82.856373) (xy 92.182619 -82.885427)
			(xy 92.13129 -82.907239) (xy 92.077333 -82.921345) (xy 92.021896 -82.927445) (xy 91.966162 -82.925408)
			(xy 91.911319 -82.915278) (xy 91.858535 -82.897271) (xy 91.808935 -82.87177) (xy 91.763577 -82.839319)
			(xy 91.723428 -82.80061) (xy 91.689342 -82.756467) (xy 91.662046 -82.707832) (xy 91.642123 -82.655741)
			(xy 91.629997 -82.601304) (xy 91.625926 -82.545682) (xy 87.624151 -82.545682) (xy 87.650594 -82.581003)
			(xy 87.676713 -82.628834) (xy 87.695758 -82.679895) (xy 87.707343 -82.733147) (xy 87.71123 -82.787506)
			(xy 87.707341 -82.841865) (xy 87.695755 -82.895116) (xy 87.676708 -82.946177) (xy 87.650587 -82.994007)
			(xy 87.617925 -83.037632) (xy 87.579386 -83.076165) (xy 87.535756 -83.10882) (xy 87.487922 -83.134933)
			(xy 87.436858 -83.153972) (xy 87.383605 -83.16555) (xy 87.329245 -83.16943) (xy 87.274887 -83.165534)
			(xy 87.221637 -83.153941) (xy 87.170579 -83.134888) (xy 87.122752 -83.108761) (xy 87.100664 -83.092798)
			(xy 87.081652 -83.079202) (xy 87.039769 -83.05847) (xy 86.994801 -83.045744) (xy 86.948264 -83.041454)
			(xy 86.901727 -83.045744) (xy 86.856759 -83.05847) (xy 86.814876 -83.079202) (xy 86.795864 -83.092798)
			(xy 86.773786 -83.108768) (xy 86.725962 -83.134885) (xy 86.674909 -83.153929) (xy 86.621665 -83.165514)
			(xy 86.567314 -83.169403) (xy 86.512962 -83.165518) (xy 86.459717 -83.153937) (xy 86.408662 -83.134896)
			(xy 86.360837 -83.108783) (xy 86.317214 -83.07613) (xy 86.278683 -83.0376) (xy 86.246028 -82.99398)
			(xy 86.219912 -82.946156) (xy 86.200869 -82.895102) (xy 86.189285 -82.841857) (xy 86.185397 -82.787506)
			(xy 84.906838 -82.787506) (xy 84.902949 -82.841867) (xy 84.891363 -82.89512) (xy 84.872315 -82.946182)
			(xy 84.846193 -82.994014) (xy 84.813529 -83.03764) (xy 84.774989 -83.076174) (xy 84.731356 -83.10883)
			(xy 84.68352 -83.134943) (xy 84.632454 -83.153982) (xy 84.579199 -83.165559) (xy 84.524838 -83.169438)
			(xy 84.470478 -83.165541) (xy 84.417226 -83.153947) (xy 84.366166 -83.134891) (xy 84.318339 -83.108762)
			(xy 84.29625 -83.092798) (xy 84.277238 -83.079202) (xy 84.235355 -83.05847) (xy 84.190387 -83.045744)
			(xy 84.14385 -83.041454) (xy 84.097313 -83.045744) (xy 84.052345 -83.05847) (xy 84.010462 -83.079202)
			(xy 83.99145 -83.092798) (xy 83.96937 -83.108776) (xy 83.92154 -83.134906) (xy 83.870479 -83.153962)
			(xy 83.817225 -83.165557) (xy 83.762862 -83.169454) (xy 83.708499 -83.165575) (xy 83.655241 -83.153997)
			(xy 83.604173 -83.134958) (xy 83.556335 -83.108843) (xy 83.512701 -83.076186) (xy 83.474159 -83.037651)
			(xy 83.441494 -82.994023) (xy 83.415371 -82.946189) (xy 83.396322 -82.895125) (xy 83.384735 -82.841869)
			(xy 83.380846 -82.787506) (xy 63.83247 -82.787506) (xy 61.460869 -85.159107) (xy 83.380844 -85.159107)
			(xy 83.384731 -85.104744) (xy 83.396317 -85.051488) (xy 83.415364 -85.000422) (xy 83.441485 -84.952588)
			(xy 83.474149 -84.908958) (xy 83.51269 -84.870421) (xy 83.556323 -84.837763) (xy 83.604161 -84.811646)
			(xy 83.655228 -84.792605) (xy 83.708486 -84.781025) (xy 83.762849 -84.777144) (xy 83.817212 -84.781039)
			(xy 83.870467 -84.792633) (xy 83.921529 -84.811687) (xy 83.96936 -84.837816) (xy 83.99145 -84.85378)
			(xy 84.010462 -84.867376) (xy 84.052345 -84.888108) (xy 84.097313 -84.900834) (xy 84.14385 -84.905124)
			(xy 84.190387 -84.900834) (xy 84.235355 -84.888108) (xy 84.277238 -84.867376) (xy 84.29625 -84.85378)
			(xy 84.318351 -84.837832) (xy 84.366179 -84.811705) (xy 84.417239 -84.792651) (xy 84.470491 -84.781058)
			(xy 84.524851 -84.777163) (xy 84.579212 -84.781044) (xy 84.632467 -84.792623) (xy 84.683532 -84.811664)
			(xy 84.731366 -84.837779) (xy 84.774998 -84.870436) (xy 84.813537 -84.908971) (xy 84.846199 -84.952598)
			(xy 84.872319 -85.00043) (xy 84.891365 -85.051493) (xy 84.90295 -85.104747) (xy 84.906837 -85.159107)
			(xy 86.185395 -85.159107) (xy 86.189282 -85.104756) (xy 86.200864 -85.051511) (xy 86.219905 -85.000456)
			(xy 86.246019 -84.952631) (xy 86.278673 -84.909009) (xy 86.317203 -84.870478) (xy 86.360825 -84.837823)
			(xy 86.40865 -84.811708) (xy 86.459704 -84.792666) (xy 86.512949 -84.781083) (xy 86.5673 -84.777195)
			(xy 86.621652 -84.781083) (xy 86.674897 -84.792666) (xy 86.725951 -84.811708) (xy 86.773776 -84.837823)
			(xy 86.795864 -84.85378) (xy 86.814876 -84.867376) (xy 86.856759 -84.888108) (xy 86.901727 -84.900834)
			(xy 86.948264 -84.905124) (xy 86.994801 -84.900834) (xy 87.039769 -84.888108) (xy 87.081652 -84.867376)
			(xy 87.100664 -84.85378) (xy 87.122764 -84.837833) (xy 87.170592 -84.811708) (xy 87.22165 -84.792656)
			(xy 87.274901 -84.781065) (xy 87.329259 -84.777172) (xy 87.383618 -84.781054) (xy 87.436871 -84.792633)
			(xy 87.487933 -84.811674) (xy 87.535766 -84.837789) (xy 87.579395 -84.870445) (xy 87.617933 -84.908979)
			(xy 87.650593 -84.952605) (xy 87.676712 -85.000436) (xy 87.695757 -85.051497) (xy 87.707341 -85.104749)
			(xy 87.711228 -85.159107) (xy 87.707339 -85.213466) (xy 87.695753 -85.266717) (xy 87.676706 -85.317777)
			(xy 87.650585 -85.365607) (xy 87.617923 -85.409232) (xy 87.579385 -85.447764) (xy 87.535754 -85.480419)
			(xy 87.48792 -85.506532) (xy 87.436857 -85.525571) (xy 87.383603 -85.537148) (xy 87.329244 -85.541028)
			(xy 87.274886 -85.537132) (xy 87.221636 -85.52554) (xy 87.170578 -85.506486) (xy 87.122752 -85.480359)
			(xy 87.100664 -85.464396) (xy 87.081652 -85.4508) (xy 87.039769 -85.430068) (xy 86.994801 -85.417342)
			(xy 86.948264 -85.413052) (xy 86.901727 -85.417342) (xy 86.856759 -85.430068) (xy 86.814876 -85.4508)
			(xy 86.795864 -85.464396) (xy 86.773788 -85.480369) (xy 86.725964 -85.506486) (xy 86.67491 -85.52553)
			(xy 86.621666 -85.537115) (xy 86.567315 -85.541005) (xy 86.512963 -85.537119) (xy 86.459718 -85.525539)
			(xy 86.408663 -85.506498) (xy 86.360837 -85.480385) (xy 86.317214 -85.447732) (xy 86.278683 -85.409202)
			(xy 86.246027 -85.365582) (xy 86.219911 -85.317757) (xy 86.200868 -85.266703) (xy 86.189284 -85.213458)
			(xy 86.185395 -85.159107) (xy 84.906837 -85.159107) (xy 84.902948 -85.213467) (xy 84.891361 -85.266721)
			(xy 84.872313 -85.317783) (xy 84.846191 -85.365614) (xy 84.813527 -85.40924) (xy 84.774987 -85.447774)
			(xy 84.731354 -85.480429) (xy 84.683518 -85.506542) (xy 84.632453 -85.525581) (xy 84.579197 -85.537158)
			(xy 84.524836 -85.541037) (xy 84.470477 -85.53714) (xy 84.417225 -85.525545) (xy 84.366166 -85.506489)
			(xy 84.318338 -85.48036) (xy 84.29625 -85.464396) (xy 84.277238 -85.4508) (xy 84.235355 -85.430068)
			(xy 84.190387 -85.417342) (xy 84.14385 -85.413052) (xy 84.097313 -85.417342) (xy 84.052345 -85.430068)
			(xy 84.010462 -85.4508) (xy 83.99145 -85.464396) (xy 83.969372 -85.480376) (xy 83.921542 -85.506507)
			(xy 83.87048 -85.525563) (xy 83.817226 -85.537159) (xy 83.762864 -85.541056) (xy 83.7085 -85.537177)
			(xy 83.655242 -85.525599) (xy 83.604174 -85.50656) (xy 83.556335 -85.480445) (xy 83.512701 -85.447788)
			(xy 83.474158 -85.409253) (xy 83.441493 -85.365624) (xy 83.41537 -85.317791) (xy 83.396321 -85.266726)
			(xy 83.384733 -85.21347) (xy 83.380844 -85.159107) (xy 61.460869 -85.159107) (xy 59.634872 -86.985104)
			(xy 83.380849 -86.985104) (xy 83.384737 -86.930741) (xy 83.396322 -86.877485) (xy 83.41537 -86.826421)
			(xy 83.441491 -86.778587) (xy 83.474155 -86.734958) (xy 83.512696 -86.696423) (xy 83.556329 -86.663765)
			(xy 83.604166 -86.637649) (xy 83.655233 -86.618608) (xy 83.70849 -86.60703) (xy 83.762853 -86.603149)
			(xy 83.817215 -86.607045) (xy 83.870469 -86.618638) (xy 83.92153 -86.637693) (xy 83.96936 -86.663822)
			(xy 83.99145 -86.679786) (xy 84.010462 -86.693382) (xy 84.052345 -86.714114) (xy 84.097313 -86.72684)
			(xy 84.14385 -86.73113) (xy 84.190387 -86.72684) (xy 84.235355 -86.714114) (xy 84.277238 -86.693382)
			(xy 84.29625 -86.679786) (xy 84.318345 -86.66383) (xy 84.366174 -86.637702) (xy 84.417234 -86.618647)
			(xy 84.470487 -86.607054) (xy 84.524847 -86.603158) (xy 84.579209 -86.607039) (xy 84.632465 -86.618618)
			(xy 84.68353 -86.637658) (xy 84.731366 -86.663773) (xy 84.774998 -86.69643) (xy 84.813538 -86.734965)
			(xy 84.846201 -86.778592) (xy 84.872321 -86.826425) (xy 84.891368 -86.877488) (xy 84.902954 -86.930743)
			(xy 84.906842 -86.985104) (xy 86.1854 -86.985104) (xy 86.189287 -86.930753) (xy 86.200869 -86.877509)
			(xy 86.219911 -86.826455) (xy 86.246025 -86.77863) (xy 86.278679 -86.735009) (xy 86.317209 -86.696479)
			(xy 86.36083 -86.663825) (xy 86.408655 -86.637711) (xy 86.459709 -86.618669) (xy 86.512953 -86.607087)
			(xy 86.567304 -86.6032) (xy 86.621655 -86.607088) (xy 86.674899 -86.618671) (xy 86.725952 -86.637714)
			(xy 86.773776 -86.663829) (xy 86.795864 -86.679786) (xy 86.814876 -86.693382) (xy 86.856759 -86.714114)
			(xy 86.901727 -86.72684) (xy 86.948264 -86.73113) (xy 86.994801 -86.72684) (xy 87.039769 -86.714114)
			(xy 87.081652 -86.693382) (xy 87.100664 -86.679786) (xy 87.122759 -86.663831) (xy 87.170586 -86.637705)
			(xy 87.221645 -86.618653) (xy 87.274896 -86.607061) (xy 87.329255 -86.603167) (xy 87.383615 -86.607048)
			(xy 87.436868 -86.618628) (xy 87.487932 -86.637668) (xy 87.535766 -86.663783) (xy 87.579396 -86.696439)
			(xy 87.617934 -86.734973) (xy 87.650595 -86.778599) (xy 87.676715 -86.82643) (xy 87.695761 -86.877492)
			(xy 87.707346 -86.930744) (xy 87.711233 -86.985104) (xy 87.707345 -87.039463) (xy 87.695759 -87.092715)
			(xy 87.676712 -87.143776) (xy 87.650591 -87.191607) (xy 87.617929 -87.235233) (xy 87.57939 -87.273766)
			(xy 87.53576 -87.306421) (xy 87.487925 -87.332535) (xy 87.436861 -87.351575) (xy 87.383608 -87.363153)
			(xy 87.329248 -87.367033) (xy 87.274889 -87.363138) (xy 87.221638 -87.351545) (xy 87.17058 -87.332492)
			(xy 87.122753 -87.306365) (xy 87.100664 -87.290402) (xy 87.081652 -87.276806) (xy 87.039769 -87.256074)
			(xy 86.994801 -87.243348) (xy 86.948264 -87.239058) (xy 86.901727 -87.243348) (xy 86.856759 -87.256074)
			(xy 86.814876 -87.276806) (xy 86.795864 -87.290402) (xy 86.773782 -87.306367) (xy 86.725959 -87.332483)
			(xy 86.674906 -87.351527) (xy 86.621662 -87.363111) (xy 86.567311 -87.367) (xy 86.51296 -87.363114)
			(xy 86.459716 -87.351533) (xy 86.408661 -87.332492) (xy 86.360836 -87.306379) (xy 86.317215 -87.273726)
			(xy 86.278684 -87.235196) (xy 86.246029 -87.191576) (xy 86.219914 -87.143752) (xy 86.200871 -87.092698)
			(xy 86.189288 -87.039454) (xy 86.1854 -86.985104) (xy 84.906842 -86.985104) (xy 84.902953 -87.039465)
			(xy 84.891366 -87.092719) (xy 84.872318 -87.143782) (xy 84.846197 -87.191614) (xy 84.813533 -87.235241)
			(xy 84.774993 -87.273775) (xy 84.73136 -87.306431) (xy 84.683524 -87.332545) (xy 84.632458 -87.351584)
			(xy 84.579202 -87.363162) (xy 84.52484 -87.367042) (xy 84.470479 -87.363145) (xy 84.417227 -87.351551)
			(xy 84.366167 -87.332495) (xy 84.318339 -87.306366) (xy 84.29625 -87.290402) (xy 84.277238 -87.276806)
			(xy 84.235355 -87.256074) (xy 84.190387 -87.243348) (xy 84.14385 -87.239058) (xy 84.097313 -87.243348)
			(xy 84.052345 -87.256074) (xy 84.010462 -87.276806) (xy 83.99145 -87.290402) (xy 83.969366 -87.306374)
			(xy 83.921537 -87.332504) (xy 83.870476 -87.35156) (xy 83.817222 -87.363154) (xy 83.76286 -87.367051)
			(xy 83.708497 -87.363171) (xy 83.65524 -87.351594) (xy 83.604172 -87.332554) (xy 83.556335 -87.306439)
			(xy 83.512701 -87.273782) (xy 83.47416 -87.235247) (xy 83.441495 -87.191619) (xy 83.415373 -87.143786)
			(xy 83.396324 -87.092721) (xy 83.384738 -87.039466) (xy 83.380849 -86.985104) (xy 59.634872 -86.985104)
			(xy 58.061558 -88.558418) (xy 83.358065 -88.558418) (xy 83.361951 -88.504061) (xy 83.373533 -88.45081)
			(xy 83.392575 -88.399749) (xy 83.418691 -88.351919) (xy 83.451348 -88.308292) (xy 83.489882 -88.269757)
			(xy 83.533507 -88.237098) (xy 83.581337 -88.210981) (xy 83.632397 -88.191936) (xy 83.685647 -88.180353)
			(xy 83.740004 -88.176465) (xy 83.794361 -88.180354) (xy 83.847611 -88.191939) (xy 83.898671 -88.210984)
			(xy 83.9465 -88.237103) (xy 83.96859 -88.253062) (xy 83.987602 -88.266658) (xy 84.029485 -88.28739)
			(xy 84.074453 -88.300116) (xy 84.12099 -88.304406) (xy 84.167527 -88.300116) (xy 84.212495 -88.28739)
			(xy 84.254378 -88.266658) (xy 84.27339 -88.253062) (xy 84.295507 -88.237142) (xy 84.343331 -88.211023)
			(xy 84.394386 -88.191977) (xy 84.447632 -88.180391) (xy 84.501984 -88.176501) (xy 84.556337 -88.180387)
			(xy 84.609584 -88.191968) (xy 84.66064 -88.21101) (xy 84.708467 -88.237125) (xy 84.75209 -88.26978)
			(xy 84.790621 -88.308312) (xy 84.823277 -88.351935) (xy 84.849391 -88.399762) (xy 84.868432 -88.450818)
			(xy 84.880013 -88.504065) (xy 84.883899 -88.558418) (xy 86.162457 -88.558418) (xy 86.166343 -88.504059)
			(xy 86.177925 -88.450806) (xy 86.196968 -88.399744) (xy 86.223085 -88.351912) (xy 86.255744 -88.308284)
			(xy 86.294279 -88.269748) (xy 86.337907 -88.237088) (xy 86.385739 -88.210971) (xy 86.436801 -88.191927)
			(xy 86.490053 -88.180343) (xy 86.544412 -88.176457) (xy 86.598771 -88.180347) (xy 86.652023 -88.191933)
			(xy 86.703084 -88.210981) (xy 86.750914 -88.237102) (xy 86.773004 -88.253062) (xy 86.792016 -88.266658)
			(xy 86.833899 -88.28739) (xy 86.878867 -88.300116) (xy 86.925404 -88.304406) (xy 86.971941 -88.300116)
			(xy 87.016909 -88.28739) (xy 87.058792 -88.266658) (xy 87.077804 -88.253062) (xy 87.09992 -88.237143)
			(xy 87.147744 -88.211027) (xy 87.198797 -88.191983) (xy 87.252041 -88.180398) (xy 87.306392 -88.17651)
			(xy 87.360743 -88.180396) (xy 87.413988 -88.191978) (xy 87.465042 -88.21102) (xy 87.512867 -88.237134)
			(xy 87.556488 -88.269789) (xy 87.595017 -88.30832) (xy 87.627671 -88.351942) (xy 87.653784 -88.399767)
			(xy 87.672825 -88.450822) (xy 87.684405 -88.504067) (xy 87.68829 -88.558418) (xy 87.6844 -88.612769)
			(xy 87.672814 -88.666013) (xy 87.653769 -88.717066) (xy 87.627652 -88.764888) (xy 87.594994 -88.808507)
			(xy 87.556461 -88.847034) (xy 87.512836 -88.879685) (xy 87.465009 -88.905795) (xy 87.413953 -88.924832)
			(xy 87.360708 -88.936409) (xy 87.306356 -88.94029) (xy 87.252006 -88.936396) (xy 87.198763 -88.924807)
			(xy 87.147711 -88.905758) (xy 87.09989 -88.879638) (xy 87.077804 -88.863678) (xy 87.058792 -88.850082)
			(xy 87.016909 -88.82935) (xy 86.971941 -88.816624) (xy 86.925404 -88.812334) (xy 86.878867 -88.816624)
			(xy 86.833899 -88.82935) (xy 86.792016 -88.850082) (xy 86.773004 -88.863678) (xy 86.750944 -88.879679)
			(xy 86.703116 -88.905804) (xy 86.652057 -88.924856) (xy 86.598807 -88.936448) (xy 86.544448 -88.940343)
			(xy 86.490089 -88.936462) (xy 86.436835 -88.924884) (xy 86.385772 -88.905844) (xy 86.337937 -88.879731)
			(xy 86.294307 -88.847076) (xy 86.255768 -88.808543) (xy 86.223105 -88.764918) (xy 86.196983 -88.717089)
			(xy 86.177935 -88.666028) (xy 86.166348 -88.612777) (xy 86.162457 -88.558418) (xy 84.883899 -88.558418)
			(xy 84.880008 -88.612771) (xy 84.868422 -88.666016) (xy 84.849376 -88.717071) (xy 84.823257 -88.764895)
			(xy 84.790598 -88.808516) (xy 84.752063 -88.847043) (xy 84.708437 -88.879695) (xy 84.660608 -88.905805)
			(xy 84.609549 -88.924842) (xy 84.556302 -88.936418) (xy 84.501948 -88.940298) (xy 84.447596 -88.936404)
			(xy 84.394351 -88.924813) (xy 84.343298 -88.905762) (xy 84.295476 -88.879639) (xy 84.27339 -88.863678)
			(xy 84.254378 -88.850082) (xy 84.212495 -88.82935) (xy 84.167527 -88.816624) (xy 84.12099 -88.812334)
			(xy 84.074453 -88.816624) (xy 84.029485 -88.82935) (xy 83.987602 -88.850082) (xy 83.96859 -88.863678)
			(xy 83.94653 -88.879678) (xy 83.898704 -88.905801) (xy 83.847646 -88.924851) (xy 83.794397 -88.936441)
			(xy 83.74004 -88.940335) (xy 83.685683 -88.936452) (xy 83.632431 -88.924874) (xy 83.58137 -88.905834)
			(xy 83.533538 -88.879721) (xy 83.489909 -88.847067) (xy 83.451372 -88.808535) (xy 83.41871 -88.764911)
			(xy 83.39259 -88.717083) (xy 83.373543 -88.666025) (xy 83.361956 -88.612775) (xy 83.358065 -88.558418)
			(xy 58.061558 -88.558418) (xy 54.999128 -91.620848) (xy 26.928826 -91.620848) (xy 25.516316 -93.033358)
			(xy 29.519874 -93.033358) (xy 29.519874 -92.946458) (xy 29.527892 -92.859929) (xy 29.54386 -92.774509)
			(xy 29.567641 -92.690927) (xy 29.599033 -92.609895) (xy 29.637767 -92.532106) (xy 29.683514 -92.458222)
			(xy 29.735883 -92.388875) (xy 29.794427 -92.324655) (xy 29.858647 -92.266111) (xy 29.927994 -92.213742)
			(xy 30.001878 -92.167995) (xy 30.079667 -92.129261) (xy 30.160699 -92.097869) (xy 30.244281 -92.074088)
			(xy 30.329701 -92.05812) (xy 30.41623 -92.050102) (xy 30.50313 -92.050102) (xy 30.589659 -92.05812)
			(xy 30.675079 -92.074088) (xy 30.758661 -92.097869) (xy 30.839693 -92.129261) (xy 30.917482 -92.167995)
			(xy 30.991366 -92.213742) (xy 31.060713 -92.266111) (xy 31.124933 -92.324655) (xy 31.183477 -92.388875)
			(xy 31.235846 -92.458222) (xy 31.281593 -92.532106) (xy 31.320327 -92.609895) (xy 31.351719 -92.690927)
			(xy 31.3755 -92.774509) (xy 31.391468 -92.859929) (xy 31.399486 -92.946458) (xy 31.399988 -92.989908)
			(xy 31.399486 -93.033358) (xy 34.599874 -93.033358) (xy 34.599874 -92.946458) (xy 34.607892 -92.859929)
			(xy 34.62386 -92.774509) (xy 34.647641 -92.690927) (xy 34.679033 -92.609895) (xy 34.717767 -92.532106)
			(xy 34.763514 -92.458222) (xy 34.815883 -92.388875) (xy 34.874427 -92.324655) (xy 34.938647 -92.266111)
			(xy 35.007994 -92.213742) (xy 35.081878 -92.167995) (xy 35.159667 -92.129261) (xy 35.240699 -92.097869)
			(xy 35.324281 -92.074088) (xy 35.409701 -92.05812) (xy 35.49623 -92.050102) (xy 35.58313 -92.050102)
			(xy 35.669659 -92.05812) (xy 35.755079 -92.074088) (xy 35.838661 -92.097869) (xy 35.919693 -92.129261)
			(xy 35.997482 -92.167995) (xy 36.071366 -92.213742) (xy 36.140713 -92.266111) (xy 36.204933 -92.324655)
			(xy 36.263477 -92.388875) (xy 36.315846 -92.458222) (xy 36.361593 -92.532106) (xy 36.400327 -92.609895)
			(xy 36.431719 -92.690927) (xy 36.4555 -92.774509) (xy 36.471468 -92.859929) (xy 36.479486 -92.946458)
			(xy 36.479988 -92.989908) (xy 36.479486 -93.033358) (xy 36.471468 -93.119887) (xy 36.4555 -93.205307)
			(xy 36.431719 -93.288889) (xy 36.400327 -93.369921) (xy 36.361593 -93.44771) (xy 36.315846 -93.521594)
			(xy 36.263477 -93.590941) (xy 36.204933 -93.655161) (xy 36.140713 -93.713705) (xy 36.071366 -93.766074)
			(xy 35.997482 -93.811821) (xy 35.919693 -93.850555) (xy 35.838661 -93.881947) (xy 35.755079 -93.905728)
			(xy 35.669659 -93.921696) (xy 35.58313 -93.929714) (xy 35.49623 -93.929714) (xy 35.409701 -93.921696)
			(xy 35.324281 -93.905728) (xy 35.240699 -93.881947) (xy 35.159667 -93.850555) (xy 35.081878 -93.811821)
			(xy 35.007994 -93.766074) (xy 34.938647 -93.713705) (xy 34.874427 -93.655161) (xy 34.815883 -93.590941)
			(xy 34.763514 -93.521594) (xy 34.717767 -93.44771) (xy 34.679033 -93.369921) (xy 34.647641 -93.288889)
			(xy 34.62386 -93.205307) (xy 34.607892 -93.119887) (xy 34.599874 -93.033358) (xy 31.399486 -93.033358)
			(xy 31.391468 -93.119887) (xy 31.3755 -93.205307) (xy 31.351719 -93.288889) (xy 31.320327 -93.369921)
			(xy 31.281593 -93.44771) (xy 31.235846 -93.521594) (xy 31.183477 -93.590941) (xy 31.124933 -93.655161)
			(xy 31.060713 -93.713705) (xy 30.991366 -93.766074) (xy 30.917482 -93.811821) (xy 30.839693 -93.850555)
			(xy 30.758661 -93.881947) (xy 30.675079 -93.905728) (xy 30.589659 -93.921696) (xy 30.50313 -93.929714)
			(xy 30.41623 -93.929714) (xy 30.329701 -93.921696) (xy 30.244281 -93.905728) (xy 30.160699 -93.881947)
			(xy 30.079667 -93.850555) (xy 30.001878 -93.811821) (xy 29.927994 -93.766074) (xy 29.858647 -93.713705)
			(xy 29.794427 -93.655161) (xy 29.735883 -93.590941) (xy 29.683514 -93.521594) (xy 29.637767 -93.44771)
			(xy 29.599033 -93.369921) (xy 29.567641 -93.288889) (xy 29.54386 -93.205307) (xy 29.527892 -93.119887)
			(xy 29.519874 -93.033358) (xy 25.516316 -93.033358) (xy 23.551896 -94.997778) (xy 23.551896 -95.621094)
			(xy 26.754326 -95.621094) (xy 26.758397 -95.565472) (xy 26.770523 -95.511035) (xy 26.790446 -95.458944)
			(xy 26.817742 -95.410309) (xy 26.851828 -95.366166) (xy 26.891977 -95.327457) (xy 26.937335 -95.295006)
			(xy 26.986935 -95.269505) (xy 27.039719 -95.251498) (xy 27.094562 -95.241368) (xy 27.150296 -95.239331)
			(xy 27.205733 -95.245431) (xy 27.25969 -95.259537) (xy 27.311019 -95.281349) (xy 27.358625 -95.310403)
			(xy 27.401493 -95.346078) (xy 27.43871 -95.387615) (xy 27.469483 -95.434128) (xy 27.493155 -95.484625)
			(xy 27.509223 -95.538032) (xy 27.514422 -95.573358) (xy 29.519874 -95.573358) (xy 29.519874 -95.486458)
			(xy 29.527892 -95.399929) (xy 29.54386 -95.314509) (xy 29.567641 -95.230927) (xy 29.599033 -95.149895)
			(xy 29.637767 -95.072106) (xy 29.683514 -94.998222) (xy 29.735883 -94.928875) (xy 29.794427 -94.864655)
			(xy 29.858647 -94.806111) (xy 29.927994 -94.753742) (xy 30.001878 -94.707995) (xy 30.079667 -94.669261)
			(xy 30.160699 -94.637869) (xy 30.244281 -94.614088) (xy 30.329701 -94.59812) (xy 30.41623 -94.590102)
			(xy 30.50313 -94.590102) (xy 30.589659 -94.59812) (xy 30.675079 -94.614088) (xy 30.758661 -94.637869)
			(xy 30.839693 -94.669261) (xy 30.917482 -94.707995) (xy 30.991366 -94.753742) (xy 31.060713 -94.806111)
			(xy 31.124933 -94.864655) (xy 31.183477 -94.928875) (xy 31.235846 -94.998222) (xy 31.281593 -95.072106)
			(xy 31.320327 -95.149895) (xy 31.351719 -95.230927) (xy 31.3755 -95.314509) (xy 31.391468 -95.399929)
			(xy 31.399486 -95.486458) (xy 31.399988 -95.529908) (xy 31.399486 -95.573358) (xy 34.599874 -95.573358)
			(xy 34.599874 -95.486458) (xy 34.607892 -95.399929) (xy 34.62386 -95.314509) (xy 34.647641 -95.230927)
			(xy 34.679033 -95.149895) (xy 34.717767 -95.072106) (xy 34.763514 -94.998222) (xy 34.815883 -94.928875)
			(xy 34.874427 -94.864655) (xy 34.938647 -94.806111) (xy 35.007994 -94.753742) (xy 35.081878 -94.707995)
			(xy 35.159667 -94.669261) (xy 35.240699 -94.637869) (xy 35.324281 -94.614088) (xy 35.409701 -94.59812)
			(xy 35.49623 -94.590102) (xy 35.58313 -94.590102) (xy 35.669659 -94.59812) (xy 35.755079 -94.614088)
			(xy 35.838661 -94.637869) (xy 35.919693 -94.669261) (xy 35.997482 -94.707995) (xy 36.071366 -94.753742)
			(xy 36.140713 -94.806111) (xy 36.204933 -94.864655) (xy 36.263477 -94.928875) (xy 36.315846 -94.998222)
			(xy 36.361593 -95.072106) (xy 36.400327 -95.149895) (xy 36.431719 -95.230927) (xy 36.4555 -95.314509)
			(xy 36.471468 -95.399929) (xy 36.479486 -95.486458) (xy 36.479988 -95.529908) (xy 36.479486 -95.573358)
			(xy 36.471468 -95.659887) (xy 36.4555 -95.745307) (xy 36.437073 -95.81007) (xy 39.818564 -95.81007)
			(xy 39.819054 -95.752663) (xy 39.826889 -95.638117) (xy 39.842523 -95.524372) (xy 39.865882 -95.41196)
			(xy 39.896859 -95.301403) (xy 39.935308 -95.193218) (xy 39.98105 -95.08791) (xy 40.033872 -94.985968)
			(xy 40.093527 -94.887869) (xy 40.159738 -94.794069) (xy 40.232196 -94.705007) (xy 40.310562 -94.621096)
			(xy 40.394473 -94.54273) (xy 40.483535 -94.470272) (xy 40.577335 -94.404061) (xy 40.675434 -94.344406)
			(xy 40.777376 -94.291584) (xy 40.882684 -94.245842) (xy 40.990869 -94.207393) (xy 41.101426 -94.176416)
			(xy 41.213838 -94.153057) (xy 41.327583 -94.137423) (xy 41.442129 -94.129588) (xy 41.556943 -94.129588)
			(xy 41.671489 -94.137423) (xy 41.785234 -94.153057) (xy 41.897646 -94.176416) (xy 42.008203 -94.207393)
			(xy 42.116388 -94.245842) (xy 42.221696 -94.291584) (xy 42.323638 -94.344406) (xy 42.421737 -94.404061)
			(xy 42.50107 -94.46006) (xy 63.647577 -94.46006) (xy 63.651612 -94.384356) (xy 63.663671 -94.309511)
			(xy 63.683617 -94.23637) (xy 63.711224 -94.165765) (xy 63.74618 -94.098494) (xy 63.788088 -94.035319)
			(xy 63.836474 -93.976957) (xy 63.89079 -93.924069) (xy 63.950419 -93.877254) (xy 64.014687 -93.837042)
			(xy 64.082864 -93.80389) (xy 64.15418 -93.778172) (xy 64.227825 -93.76018) (xy 64.302965 -93.750118)
			(xy 64.378749 -93.748099) (xy 64.454319 -93.754148) (xy 64.528817 -93.768195) (xy 64.6014 -93.790081)
			(xy 64.671246 -93.819558) (xy 64.737563 -93.856293) (xy 64.799599 -93.899868) (xy 64.856652 -93.94979)
			(xy 64.908076 -94.005494) (xy 64.953287 -94.066349) (xy 64.991774 -94.131664) (xy 65.0231 -94.2007)
			(xy 65.04691 -94.272675) (xy 65.062935 -94.346773) (xy 65.070994 -94.422154) (xy 65.071498 -94.46006)
			(xy 66.187577 -94.46006) (xy 66.191612 -94.384356) (xy 66.203671 -94.309511) (xy 66.223617 -94.23637)
			(xy 66.251224 -94.165765) (xy 66.28618 -94.098494) (xy 66.328088 -94.035319) (xy 66.376474 -93.976957)
			(xy 66.43079 -93.924069) (xy 66.490419 -93.877254) (xy 66.554687 -93.837042) (xy 66.622864 -93.80389)
			(xy 66.69418 -93.778172) (xy 66.767825 -93.76018) (xy 66.842965 -93.750118) (xy 66.918749 -93.748099)
			(xy 66.994319 -93.754148) (xy 67.068817 -93.768195) (xy 67.1414 -93.790081) (xy 67.211246 -93.819558)
			(xy 67.277563 -93.856293) (xy 67.339599 -93.899868) (xy 67.396652 -93.94979) (xy 67.448076 -94.005494)
			(xy 67.493287 -94.066349) (xy 67.531774 -94.131664) (xy 67.5631 -94.2007) (xy 67.58691 -94.272675)
			(xy 67.602935 -94.346773) (xy 67.610994 -94.422154) (xy 67.611498 -94.46006) (xy 68.727577 -94.46006)
			(xy 68.731612 -94.384356) (xy 68.743671 -94.309511) (xy 68.763617 -94.23637) (xy 68.791224 -94.165765)
			(xy 68.82618 -94.098494) (xy 68.868088 -94.035319) (xy 68.916474 -93.976957) (xy 68.97079 -93.924069)
			(xy 69.030419 -93.877254) (xy 69.094687 -93.837042) (xy 69.162864 -93.80389) (xy 69.23418 -93.778172)
			(xy 69.307825 -93.76018) (xy 69.382965 -93.750118) (xy 69.458749 -93.748099) (xy 69.534319 -93.754148)
			(xy 69.608817 -93.768195) (xy 69.6814 -93.790081) (xy 69.751246 -93.819558) (xy 69.817563 -93.856293)
			(xy 69.879599 -93.899868) (xy 69.936652 -93.94979) (xy 69.988076 -94.005494) (xy 70.033287 -94.066349)
			(xy 70.071774 -94.131664) (xy 70.1031 -94.2007) (xy 70.12691 -94.272675) (xy 70.142935 -94.346773)
			(xy 70.150994 -94.422154) (xy 70.151498 -94.46006) (xy 71.267577 -94.46006) (xy 71.271612 -94.384356)
			(xy 71.283671 -94.309511) (xy 71.303617 -94.23637) (xy 71.331224 -94.165765) (xy 71.36618 -94.098494)
			(xy 71.408088 -94.035319) (xy 71.456474 -93.976957) (xy 71.51079 -93.924069) (xy 71.570419 -93.877254)
			(xy 71.634687 -93.837042) (xy 71.702864 -93.80389) (xy 71.77418 -93.778172) (xy 71.847825 -93.76018)
			(xy 71.922965 -93.750118) (xy 71.998749 -93.748099) (xy 72.074319 -93.754148) (xy 72.148817 -93.768195)
			(xy 72.2214 -93.790081) (xy 72.291246 -93.819558) (xy 72.357563 -93.856293) (xy 72.419599 -93.899868)
			(xy 72.476652 -93.94979) (xy 72.528076 -94.005494) (xy 72.573287 -94.066349) (xy 72.611774 -94.131664)
			(xy 72.6431 -94.2007) (xy 72.66691 -94.272675) (xy 72.682935 -94.346773) (xy 72.690994 -94.422154)
			(xy 72.691498 -94.46006) (xy 73.807577 -94.46006) (xy 73.811612 -94.384356) (xy 73.823671 -94.309511)
			(xy 73.843617 -94.23637) (xy 73.871224 -94.165765) (xy 73.90618 -94.098494) (xy 73.948088 -94.035319)
			(xy 73.996474 -93.976957) (xy 74.05079 -93.924069) (xy 74.110419 -93.877254) (xy 74.174687 -93.837042)
			(xy 74.242864 -93.80389) (xy 74.31418 -93.778172) (xy 74.387825 -93.76018) (xy 74.462965 -93.750118)
			(xy 74.538749 -93.748099) (xy 74.614319 -93.754148) (xy 74.688817 -93.768195) (xy 74.7614 -93.790081)
			(xy 74.831246 -93.819558) (xy 74.897563 -93.856293) (xy 74.959599 -93.899868) (xy 75.016652 -93.94979)
			(xy 75.068076 -94.005494) (xy 75.113287 -94.066349) (xy 75.151774 -94.131664) (xy 75.1831 -94.2007)
			(xy 75.20691 -94.272675) (xy 75.222935 -94.346773) (xy 75.230994 -94.422154) (xy 75.231498 -94.46006)
			(xy 76.347577 -94.46006) (xy 76.351612 -94.384356) (xy 76.363671 -94.309511) (xy 76.383617 -94.23637)
			(xy 76.411224 -94.165765) (xy 76.44618 -94.098494) (xy 76.488088 -94.035319) (xy 76.536474 -93.976957)
			(xy 76.59079 -93.924069) (xy 76.650419 -93.877254) (xy 76.714687 -93.837042) (xy 76.782864 -93.80389)
			(xy 76.85418 -93.778172) (xy 76.927825 -93.76018) (xy 77.002965 -93.750118) (xy 77.078749 -93.748099)
			(xy 77.154319 -93.754148) (xy 77.228817 -93.768195) (xy 77.3014 -93.790081) (xy 77.371246 -93.819558)
			(xy 77.437563 -93.856293) (xy 77.499599 -93.899868) (xy 77.556652 -93.94979) (xy 77.608076 -94.005494)
			(xy 77.653287 -94.066349) (xy 77.691774 -94.131664) (xy 77.7231 -94.2007) (xy 77.74691 -94.272675)
			(xy 77.762935 -94.346773) (xy 77.770994 -94.422154) (xy 77.771498 -94.46006) (xy 78.887577 -94.46006)
			(xy 78.891612 -94.384356) (xy 78.903671 -94.309511) (xy 78.923617 -94.23637) (xy 78.951224 -94.165765)
			(xy 78.98618 -94.098494) (xy 79.028088 -94.035319) (xy 79.076474 -93.976957) (xy 79.13079 -93.924069)
			(xy 79.190419 -93.877254) (xy 79.254687 -93.837042) (xy 79.322864 -93.80389) (xy 79.39418 -93.778172)
			(xy 79.467825 -93.76018) (xy 79.542965 -93.750118) (xy 79.618749 -93.748099) (xy 79.694319 -93.754148)
			(xy 79.768817 -93.768195) (xy 79.8414 -93.790081) (xy 79.911246 -93.819558) (xy 79.977563 -93.856293)
			(xy 80.039599 -93.899868) (xy 80.096652 -93.94979) (xy 80.148076 -94.005494) (xy 80.193287 -94.066349)
			(xy 80.231774 -94.131664) (xy 80.2631 -94.2007) (xy 80.28691 -94.272675) (xy 80.302935 -94.346773)
			(xy 80.310994 -94.422154) (xy 80.311498 -94.46006) (xy 81.427577 -94.46006) (xy 81.431612 -94.384356)
			(xy 81.443671 -94.309511) (xy 81.463617 -94.23637) (xy 81.491224 -94.165765) (xy 81.52618 -94.098494)
			(xy 81.568088 -94.035319) (xy 81.616474 -93.976957) (xy 81.67079 -93.924069) (xy 81.730419 -93.877254)
			(xy 81.794687 -93.837042) (xy 81.862864 -93.80389) (xy 81.93418 -93.778172) (xy 82.007825 -93.76018)
			(xy 82.082965 -93.750118) (xy 82.158749 -93.748099) (xy 82.234319 -93.754148) (xy 82.308817 -93.768195)
			(xy 82.3814 -93.790081) (xy 82.451246 -93.819558) (xy 82.517563 -93.856293) (xy 82.579599 -93.899868)
			(xy 82.636652 -93.94979) (xy 82.688076 -94.005494) (xy 82.733287 -94.066349) (xy 82.771774 -94.131664)
			(xy 82.8031 -94.2007) (xy 82.82691 -94.272675) (xy 82.842935 -94.346773) (xy 82.850994 -94.422154)
			(xy 82.851498 -94.46006) (xy 82.850994 -94.497966) (xy 82.842935 -94.573347) (xy 82.82691 -94.647445)
			(xy 82.8031 -94.71942) (xy 82.771774 -94.788456) (xy 82.733287 -94.853771) (xy 82.688076 -94.914626)
			(xy 82.636652 -94.97033) (xy 82.579599 -95.020252) (xy 82.517563 -95.063827) (xy 82.451246 -95.100562)
			(xy 82.3814 -95.130039) (xy 82.308817 -95.151925) (xy 82.234319 -95.165972) (xy 82.158749 -95.172021)
			(xy 82.082965 -95.170002) (xy 82.007825 -95.15994) (xy 81.93418 -95.141948) (xy 81.862864 -95.11623)
			(xy 81.794687 -95.083078) (xy 81.730419 -95.042866) (xy 81.67079 -94.996051) (xy 81.616474 -94.943163)
			(xy 81.568088 -94.884801) (xy 81.52618 -94.821626) (xy 81.491224 -94.754355) (xy 81.463617 -94.68375)
			(xy 81.443671 -94.610609) (xy 81.431612 -94.535764) (xy 81.427577 -94.46006) (xy 80.311498 -94.46006)
			(xy 80.310994 -94.497966) (xy 80.302935 -94.573347) (xy 80.28691 -94.647445) (xy 80.2631 -94.71942)
			(xy 80.231774 -94.788456) (xy 80.193287 -94.853771) (xy 80.148076 -94.914626) (xy 80.096652 -94.97033)
			(xy 80.039599 -95.020252) (xy 79.977563 -95.063827) (xy 79.911246 -95.100562) (xy 79.8414 -95.130039)
			(xy 79.768817 -95.151925) (xy 79.694319 -95.165972) (xy 79.618749 -95.172021) (xy 79.542965 -95.170002)
			(xy 79.467825 -95.15994) (xy 79.39418 -95.141948) (xy 79.322864 -95.11623) (xy 79.254687 -95.083078)
			(xy 79.190419 -95.042866) (xy 79.13079 -94.996051) (xy 79.076474 -94.943163) (xy 79.028088 -94.884801)
			(xy 78.98618 -94.821626) (xy 78.951224 -94.754355) (xy 78.923617 -94.68375) (xy 78.903671 -94.610609)
			(xy 78.891612 -94.535764) (xy 78.887577 -94.46006) (xy 77.771498 -94.46006) (xy 77.770994 -94.497966)
			(xy 77.762935 -94.573347) (xy 77.74691 -94.647445) (xy 77.7231 -94.71942) (xy 77.691774 -94.788456)
			(xy 77.653287 -94.853771) (xy 77.608076 -94.914626) (xy 77.556652 -94.97033) (xy 77.499599 -95.020252)
			(xy 77.437563 -95.063827) (xy 77.371246 -95.100562) (xy 77.3014 -95.130039) (xy 77.228817 -95.151925)
			(xy 77.154319 -95.165972) (xy 77.078749 -95.172021) (xy 77.002965 -95.170002) (xy 76.927825 -95.15994)
			(xy 76.85418 -95.141948) (xy 76.782864 -95.11623) (xy 76.714687 -95.083078) (xy 76.650419 -95.042866)
			(xy 76.59079 -94.996051) (xy 76.536474 -94.943163) (xy 76.488088 -94.884801) (xy 76.44618 -94.821626)
			(xy 76.411224 -94.754355) (xy 76.383617 -94.68375) (xy 76.363671 -94.610609) (xy 76.351612 -94.535764)
			(xy 76.347577 -94.46006) (xy 75.231498 -94.46006) (xy 75.230994 -94.497966) (xy 75.222935 -94.573347)
			(xy 75.20691 -94.647445) (xy 75.1831 -94.71942) (xy 75.151774 -94.788456) (xy 75.113287 -94.853771)
			(xy 75.068076 -94.914626) (xy 75.016652 -94.97033) (xy 74.959599 -95.020252) (xy 74.897563 -95.063827)
			(xy 74.831246 -95.100562) (xy 74.7614 -95.130039) (xy 74.688817 -95.151925) (xy 74.614319 -95.165972)
			(xy 74.538749 -95.172021) (xy 74.462965 -95.170002) (xy 74.387825 -95.15994) (xy 74.31418 -95.141948)
			(xy 74.242864 -95.11623) (xy 74.174687 -95.083078) (xy 74.110419 -95.042866) (xy 74.05079 -94.996051)
			(xy 73.996474 -94.943163) (xy 73.948088 -94.884801) (xy 73.90618 -94.821626) (xy 73.871224 -94.754355)
			(xy 73.843617 -94.68375) (xy 73.823671 -94.610609) (xy 73.811612 -94.535764) (xy 73.807577 -94.46006)
			(xy 72.691498 -94.46006) (xy 72.690994 -94.497966) (xy 72.682935 -94.573347) (xy 72.66691 -94.647445)
			(xy 72.6431 -94.71942) (xy 72.611774 -94.788456) (xy 72.573287 -94.853771) (xy 72.528076 -94.914626)
			(xy 72.476652 -94.97033) (xy 72.419599 -95.020252) (xy 72.357563 -95.063827) (xy 72.291246 -95.100562)
			(xy 72.2214 -95.130039) (xy 72.148817 -95.151925) (xy 72.074319 -95.165972) (xy 71.998749 -95.172021)
			(xy 71.922965 -95.170002) (xy 71.847825 -95.15994) (xy 71.77418 -95.141948) (xy 71.702864 -95.11623)
			(xy 71.634687 -95.083078) (xy 71.570419 -95.042866) (xy 71.51079 -94.996051) (xy 71.456474 -94.943163)
			(xy 71.408088 -94.884801) (xy 71.36618 -94.821626) (xy 71.331224 -94.754355) (xy 71.303617 -94.68375)
			(xy 71.283671 -94.610609) (xy 71.271612 -94.535764) (xy 71.267577 -94.46006) (xy 70.151498 -94.46006)
			(xy 70.150994 -94.497966) (xy 70.142935 -94.573347) (xy 70.12691 -94.647445) (xy 70.1031 -94.71942)
			(xy 70.071774 -94.788456) (xy 70.033287 -94.853771) (xy 69.988076 -94.914626) (xy 69.936652 -94.97033)
			(xy 69.879599 -95.020252) (xy 69.817563 -95.063827) (xy 69.751246 -95.100562) (xy 69.6814 -95.130039)
			(xy 69.608817 -95.151925) (xy 69.534319 -95.165972) (xy 69.458749 -95.172021) (xy 69.382965 -95.170002)
			(xy 69.307825 -95.15994) (xy 69.23418 -95.141948) (xy 69.162864 -95.11623) (xy 69.094687 -95.083078)
			(xy 69.030419 -95.042866) (xy 68.97079 -94.996051) (xy 68.916474 -94.943163) (xy 68.868088 -94.884801)
			(xy 68.82618 -94.821626) (xy 68.791224 -94.754355) (xy 68.763617 -94.68375) (xy 68.743671 -94.610609)
			(xy 68.731612 -94.535764) (xy 68.727577 -94.46006) (xy 67.611498 -94.46006) (xy 67.610994 -94.497966)
			(xy 67.602935 -94.573347) (xy 67.58691 -94.647445) (xy 67.5631 -94.71942) (xy 67.531774 -94.788456)
			(xy 67.493287 -94.853771) (xy 67.448076 -94.914626) (xy 67.396652 -94.97033) (xy 67.339599 -95.020252)
			(xy 67.277563 -95.063827) (xy 67.211246 -95.100562) (xy 67.1414 -95.130039) (xy 67.068817 -95.151925)
			(xy 66.994319 -95.165972) (xy 66.918749 -95.172021) (xy 66.842965 -95.170002) (xy 66.767825 -95.15994)
			(xy 66.69418 -95.141948) (xy 66.622864 -95.11623) (xy 66.554687 -95.083078) (xy 66.490419 -95.042866)
			(xy 66.43079 -94.996051) (xy 66.376474 -94.943163) (xy 66.328088 -94.884801) (xy 66.28618 -94.821626)
			(xy 66.251224 -94.754355) (xy 66.223617 -94.68375) (xy 66.203671 -94.610609) (xy 66.191612 -94.535764)
			(xy 66.187577 -94.46006) (xy 65.071498 -94.46006) (xy 65.070994 -94.497966) (xy 65.062935 -94.573347)
			(xy 65.04691 -94.647445) (xy 65.0231 -94.71942) (xy 64.991774 -94.788456) (xy 64.953287 -94.853771)
			(xy 64.908076 -94.914626) (xy 64.856652 -94.97033) (xy 64.799599 -95.020252) (xy 64.737563 -95.063827)
			(xy 64.671246 -95.100562) (xy 64.6014 -95.130039) (xy 64.528817 -95.151925) (xy 64.454319 -95.165972)
			(xy 64.378749 -95.172021) (xy 64.302965 -95.170002) (xy 64.227825 -95.15994) (xy 64.15418 -95.141948)
			(xy 64.082864 -95.11623) (xy 64.014687 -95.083078) (xy 63.950419 -95.042866) (xy 63.89079 -94.996051)
			(xy 63.836474 -94.943163) (xy 63.788088 -94.884801) (xy 63.74618 -94.821626) (xy 63.711224 -94.754355)
			(xy 63.683617 -94.68375) (xy 63.663671 -94.610609) (xy 63.651612 -94.535764) (xy 63.647577 -94.46006)
			(xy 42.50107 -94.46006) (xy 42.515537 -94.470272) (xy 42.604599 -94.54273) (xy 42.68851 -94.621096)
			(xy 42.766876 -94.705007) (xy 42.839334 -94.794069) (xy 42.905545 -94.887869) (xy 42.9652 -94.985968)
			(xy 43.018022 -95.08791) (xy 43.063764 -95.193218) (xy 43.102213 -95.301403) (xy 43.13319 -95.41196)
			(xy 43.156549 -95.524372) (xy 43.172183 -95.638117) (xy 43.180018 -95.752663) (xy 43.180508 -95.81007)
			(xy 43.180381 -95.843251) (xy 43.177842 -95.909565) (xy 43.175428 -95.942658) (xy 43.170272 -96.000942)
			(xy 43.152948 -96.116671) (xy 43.127616 -96.230914) (xy 43.094401 -96.343119) (xy 43.053462 -96.452742)
			(xy 43.004999 -96.559253) (xy 42.949245 -96.662135) (xy 42.886471 -96.760891) (xy 42.816981 -96.855042)
			(xy 42.741111 -96.944132) (xy 42.659229 -97.027729) (xy 42.571732 -97.10543) (xy 42.500813 -97.16008)
			(xy 63.647577 -97.16008) (xy 63.651612 -97.084376) (xy 63.663671 -97.009531) (xy 63.683617 -96.93639)
			(xy 63.711224 -96.865785) (xy 63.74618 -96.798514) (xy 63.788088 -96.735339) (xy 63.836474 -96.676977)
			(xy 63.89079 -96.624089) (xy 63.950419 -96.577274) (xy 64.014687 -96.537062) (xy 64.082864 -96.50391)
			(xy 64.15418 -96.478192) (xy 64.227825 -96.4602) (xy 64.302965 -96.450138) (xy 64.378749 -96.448119)
			(xy 64.454319 -96.454168) (xy 64.528817 -96.468215) (xy 64.6014 -96.490101) (xy 64.671246 -96.519578)
			(xy 64.737563 -96.556313) (xy 64.799599 -96.599888) (xy 64.856652 -96.64981) (xy 64.908076 -96.705514)
			(xy 64.953287 -96.766369) (xy 64.991774 -96.831684) (xy 65.0231 -96.90072) (xy 65.04691 -96.972695)
			(xy 65.062935 -97.046793) (xy 65.070994 -97.122174) (xy 65.071498 -97.16008) (xy 66.187577 -97.16008)
			(xy 66.191612 -97.084376) (xy 66.203671 -97.009531) (xy 66.223617 -96.93639) (xy 66.251224 -96.865785)
			(xy 66.28618 -96.798514) (xy 66.328088 -96.735339) (xy 66.376474 -96.676977) (xy 66.43079 -96.624089)
			(xy 66.490419 -96.577274) (xy 66.554687 -96.537062) (xy 66.622864 -96.50391) (xy 66.69418 -96.478192)
			(xy 66.767825 -96.4602) (xy 66.842965 -96.450138) (xy 66.918749 -96.448119) (xy 66.994319 -96.454168)
			(xy 67.068817 -96.468215) (xy 67.1414 -96.490101) (xy 67.211246 -96.519578) (xy 67.277563 -96.556313)
			(xy 67.339599 -96.599888) (xy 67.396652 -96.64981) (xy 67.448076 -96.705514) (xy 67.493287 -96.766369)
			(xy 67.531774 -96.831684) (xy 67.5631 -96.90072) (xy 67.58691 -96.972695) (xy 67.602935 -97.046793)
			(xy 67.610994 -97.122174) (xy 67.611498 -97.16008) (xy 68.727577 -97.16008) (xy 68.731612 -97.084376)
			(xy 68.743671 -97.009531) (xy 68.763617 -96.93639) (xy 68.791224 -96.865785) (xy 68.82618 -96.798514)
			(xy 68.868088 -96.735339) (xy 68.916474 -96.676977) (xy 68.97079 -96.624089) (xy 69.030419 -96.577274)
			(xy 69.094687 -96.537062) (xy 69.162864 -96.50391) (xy 69.23418 -96.478192) (xy 69.307825 -96.4602)
			(xy 69.382965 -96.450138) (xy 69.458749 -96.448119) (xy 69.534319 -96.454168) (xy 69.608817 -96.468215)
			(xy 69.6814 -96.490101) (xy 69.751246 -96.519578) (xy 69.817563 -96.556313) (xy 69.879599 -96.599888)
			(xy 69.936652 -96.64981) (xy 69.988076 -96.705514) (xy 70.033287 -96.766369) (xy 70.071774 -96.831684)
			(xy 70.1031 -96.90072) (xy 70.12691 -96.972695) (xy 70.142935 -97.046793) (xy 70.150994 -97.122174)
			(xy 70.151498 -97.16008) (xy 71.267577 -97.16008) (xy 71.271612 -97.084376) (xy 71.283671 -97.009531)
			(xy 71.303617 -96.93639) (xy 71.331224 -96.865785) (xy 71.36618 -96.798514) (xy 71.408088 -96.735339)
			(xy 71.456474 -96.676977) (xy 71.51079 -96.624089) (xy 71.570419 -96.577274) (xy 71.634687 -96.537062)
			(xy 71.702864 -96.50391) (xy 71.77418 -96.478192) (xy 71.847825 -96.4602) (xy 71.922965 -96.450138)
			(xy 71.998749 -96.448119) (xy 72.074319 -96.454168) (xy 72.148817 -96.468215) (xy 72.2214 -96.490101)
			(xy 72.291246 -96.519578) (xy 72.357563 -96.556313) (xy 72.419599 -96.599888) (xy 72.476652 -96.64981)
			(xy 72.528076 -96.705514) (xy 72.573287 -96.766369) (xy 72.611774 -96.831684) (xy 72.6431 -96.90072)
			(xy 72.66691 -96.972695) (xy 72.682935 -97.046793) (xy 72.690994 -97.122174) (xy 72.691498 -97.16008)
			(xy 73.807577 -97.16008) (xy 73.811612 -97.084376) (xy 73.823671 -97.009531) (xy 73.843617 -96.93639)
			(xy 73.871224 -96.865785) (xy 73.90618 -96.798514) (xy 73.948088 -96.735339) (xy 73.996474 -96.676977)
			(xy 74.05079 -96.624089) (xy 74.110419 -96.577274) (xy 74.174687 -96.537062) (xy 74.242864 -96.50391)
			(xy 74.31418 -96.478192) (xy 74.387825 -96.4602) (xy 74.462965 -96.450138) (xy 74.538749 -96.448119)
			(xy 74.614319 -96.454168) (xy 74.688817 -96.468215) (xy 74.7614 -96.490101) (xy 74.831246 -96.519578)
			(xy 74.897563 -96.556313) (xy 74.959599 -96.599888) (xy 75.016652 -96.64981) (xy 75.068076 -96.705514)
			(xy 75.113287 -96.766369) (xy 75.151774 -96.831684) (xy 75.1831 -96.90072) (xy 75.20691 -96.972695)
			(xy 75.222935 -97.046793) (xy 75.230994 -97.122174) (xy 75.231498 -97.16008) (xy 76.347577 -97.16008)
			(xy 76.351612 -97.084376) (xy 76.363671 -97.009531) (xy 76.383617 -96.93639) (xy 76.411224 -96.865785)
			(xy 76.44618 -96.798514) (xy 76.488088 -96.735339) (xy 76.536474 -96.676977) (xy 76.59079 -96.624089)
			(xy 76.650419 -96.577274) (xy 76.714687 -96.537062) (xy 76.782864 -96.50391) (xy 76.85418 -96.478192)
			(xy 76.927825 -96.4602) (xy 77.002965 -96.450138) (xy 77.078749 -96.448119) (xy 77.154319 -96.454168)
			(xy 77.228817 -96.468215) (xy 77.3014 -96.490101) (xy 77.371246 -96.519578) (xy 77.437563 -96.556313)
			(xy 77.499599 -96.599888) (xy 77.556652 -96.64981) (xy 77.608076 -96.705514) (xy 77.653287 -96.766369)
			(xy 77.691774 -96.831684) (xy 77.7231 -96.90072) (xy 77.74691 -96.972695) (xy 77.762935 -97.046793)
			(xy 77.770994 -97.122174) (xy 77.771498 -97.16008) (xy 78.887577 -97.16008) (xy 78.891612 -97.084376)
			(xy 78.903671 -97.009531) (xy 78.923617 -96.93639) (xy 78.951224 -96.865785) (xy 78.98618 -96.798514)
			(xy 79.028088 -96.735339) (xy 79.076474 -96.676977) (xy 79.13079 -96.624089) (xy 79.190419 -96.577274)
			(xy 79.254687 -96.537062) (xy 79.322864 -96.50391) (xy 79.39418 -96.478192) (xy 79.467825 -96.4602)
			(xy 79.542965 -96.450138) (xy 79.618749 -96.448119) (xy 79.694319 -96.454168) (xy 79.768817 -96.468215)
			(xy 79.8414 -96.490101) (xy 79.911246 -96.519578) (xy 79.977563 -96.556313) (xy 80.039599 -96.599888)
			(xy 80.096652 -96.64981) (xy 80.148076 -96.705514) (xy 80.193287 -96.766369) (xy 80.231774 -96.831684)
			(xy 80.2631 -96.90072) (xy 80.28691 -96.972695) (xy 80.302935 -97.046793) (xy 80.310994 -97.122174)
			(xy 80.311498 -97.16008) (xy 81.427577 -97.16008) (xy 81.431612 -97.084376) (xy 81.443671 -97.009531)
			(xy 81.463617 -96.93639) (xy 81.491224 -96.865785) (xy 81.52618 -96.798514) (xy 81.568088 -96.735339)
			(xy 81.616474 -96.676977) (xy 81.67079 -96.624089) (xy 81.730419 -96.577274) (xy 81.794687 -96.537062)
			(xy 81.862864 -96.50391) (xy 81.93418 -96.478192) (xy 82.007825 -96.4602) (xy 82.082965 -96.450138)
			(xy 82.158749 -96.448119) (xy 82.234319 -96.454168) (xy 82.308817 -96.468215) (xy 82.3814 -96.490101)
			(xy 82.451246 -96.519578) (xy 82.517563 -96.556313) (xy 82.579599 -96.599888) (xy 82.636652 -96.64981)
			(xy 82.688076 -96.705514) (xy 82.733287 -96.766369) (xy 82.771774 -96.831684) (xy 82.8031 -96.90072)
			(xy 82.82691 -96.972695) (xy 82.842935 -97.046793) (xy 82.850994 -97.122174) (xy 82.851498 -97.16008)
			(xy 82.850994 -97.197986) (xy 82.842935 -97.273367) (xy 82.82691 -97.347465) (xy 82.8031 -97.41944)
			(xy 82.771774 -97.488476) (xy 82.733287 -97.553791) (xy 82.688076 -97.614646) (xy 82.636652 -97.67035)
			(xy 82.579599 -97.720272) (xy 82.517563 -97.763847) (xy 82.451246 -97.800582) (xy 82.3814 -97.830059)
			(xy 82.308817 -97.851945) (xy 82.234319 -97.865992) (xy 82.158749 -97.872041) (xy 82.082965 -97.870022)
			(xy 82.007825 -97.85996) (xy 81.93418 -97.841968) (xy 81.862864 -97.81625) (xy 81.794687 -97.783098)
			(xy 81.730419 -97.742886) (xy 81.67079 -97.696071) (xy 81.616474 -97.643183) (xy 81.568088 -97.584821)
			(xy 81.52618 -97.521646) (xy 81.491224 -97.454375) (xy 81.463617 -97.38377) (xy 81.443671 -97.310629)
			(xy 81.431612 -97.235784) (xy 81.427577 -97.16008) (xy 80.311498 -97.16008) (xy 80.310994 -97.197986)
			(xy 80.302935 -97.273367) (xy 80.28691 -97.347465) (xy 80.2631 -97.41944) (xy 80.231774 -97.488476)
			(xy 80.193287 -97.553791) (xy 80.148076 -97.614646) (xy 80.096652 -97.67035) (xy 80.039599 -97.720272)
			(xy 79.977563 -97.763847) (xy 79.911246 -97.800582) (xy 79.8414 -97.830059) (xy 79.768817 -97.851945)
			(xy 79.694319 -97.865992) (xy 79.618749 -97.872041) (xy 79.542965 -97.870022) (xy 79.467825 -97.85996)
			(xy 79.39418 -97.841968) (xy 79.322864 -97.81625) (xy 79.254687 -97.783098) (xy 79.190419 -97.742886)
			(xy 79.13079 -97.696071) (xy 79.076474 -97.643183) (xy 79.028088 -97.584821) (xy 78.98618 -97.521646)
			(xy 78.951224 -97.454375) (xy 78.923617 -97.38377) (xy 78.903671 -97.310629) (xy 78.891612 -97.235784)
			(xy 78.887577 -97.16008) (xy 77.771498 -97.16008) (xy 77.770994 -97.197986) (xy 77.762935 -97.273367)
			(xy 77.74691 -97.347465) (xy 77.7231 -97.41944) (xy 77.691774 -97.488476) (xy 77.653287 -97.553791)
			(xy 77.608076 -97.614646) (xy 77.556652 -97.67035) (xy 77.499599 -97.720272) (xy 77.437563 -97.763847)
			(xy 77.371246 -97.800582) (xy 77.3014 -97.830059) (xy 77.228817 -97.851945) (xy 77.154319 -97.865992)
			(xy 77.078749 -97.872041) (xy 77.002965 -97.870022) (xy 76.927825 -97.85996) (xy 76.85418 -97.841968)
			(xy 76.782864 -97.81625) (xy 76.714687 -97.783098) (xy 76.650419 -97.742886) (xy 76.59079 -97.696071)
			(xy 76.536474 -97.643183) (xy 76.488088 -97.584821) (xy 76.44618 -97.521646) (xy 76.411224 -97.454375)
			(xy 76.383617 -97.38377) (xy 76.363671 -97.310629) (xy 76.351612 -97.235784) (xy 76.347577 -97.16008)
			(xy 75.231498 -97.16008) (xy 75.230994 -97.197986) (xy 75.222935 -97.273367) (xy 75.20691 -97.347465)
			(xy 75.1831 -97.41944) (xy 75.151774 -97.488476) (xy 75.113287 -97.553791) (xy 75.068076 -97.614646)
			(xy 75.016652 -97.67035) (xy 74.959599 -97.720272) (xy 74.897563 -97.763847) (xy 74.831246 -97.800582)
			(xy 74.7614 -97.830059) (xy 74.688817 -97.851945) (xy 74.614319 -97.865992) (xy 74.538749 -97.872041)
			(xy 74.462965 -97.870022) (xy 74.387825 -97.85996) (xy 74.31418 -97.841968) (xy 74.242864 -97.81625)
			(xy 74.174687 -97.783098) (xy 74.110419 -97.742886) (xy 74.05079 -97.696071) (xy 73.996474 -97.643183)
			(xy 73.948088 -97.584821) (xy 73.90618 -97.521646) (xy 73.871224 -97.454375) (xy 73.843617 -97.38377)
			(xy 73.823671 -97.310629) (xy 73.811612 -97.235784) (xy 73.807577 -97.16008) (xy 72.691498 -97.16008)
			(xy 72.690994 -97.197986) (xy 72.682935 -97.273367) (xy 72.66691 -97.347465) (xy 72.6431 -97.41944)
			(xy 72.611774 -97.488476) (xy 72.573287 -97.553791) (xy 72.528076 -97.614646) (xy 72.476652 -97.67035)
			(xy 72.419599 -97.720272) (xy 72.357563 -97.763847) (xy 72.291246 -97.800582) (xy 72.2214 -97.830059)
			(xy 72.148817 -97.851945) (xy 72.074319 -97.865992) (xy 71.998749 -97.872041) (xy 71.922965 -97.870022)
			(xy 71.847825 -97.85996) (xy 71.77418 -97.841968) (xy 71.702864 -97.81625) (xy 71.634687 -97.783098)
			(xy 71.570419 -97.742886) (xy 71.51079 -97.696071) (xy 71.456474 -97.643183) (xy 71.408088 -97.584821)
			(xy 71.36618 -97.521646) (xy 71.331224 -97.454375) (xy 71.303617 -97.38377) (xy 71.283671 -97.310629)
			(xy 71.271612 -97.235784) (xy 71.267577 -97.16008) (xy 70.151498 -97.16008) (xy 70.150994 -97.197986)
			(xy 70.142935 -97.273367) (xy 70.12691 -97.347465) (xy 70.1031 -97.41944) (xy 70.071774 -97.488476)
			(xy 70.033287 -97.553791) (xy 69.988076 -97.614646) (xy 69.936652 -97.67035) (xy 69.879599 -97.720272)
			(xy 69.817563 -97.763847) (xy 69.751246 -97.800582) (xy 69.6814 -97.830059) (xy 69.608817 -97.851945)
			(xy 69.534319 -97.865992) (xy 69.458749 -97.872041) (xy 69.382965 -97.870022) (xy 69.307825 -97.85996)
			(xy 69.23418 -97.841968) (xy 69.162864 -97.81625) (xy 69.094687 -97.783098) (xy 69.030419 -97.742886)
			(xy 68.97079 -97.696071) (xy 68.916474 -97.643183) (xy 68.868088 -97.584821) (xy 68.82618 -97.521646)
			(xy 68.791224 -97.454375) (xy 68.763617 -97.38377) (xy 68.743671 -97.310629) (xy 68.731612 -97.235784)
			(xy 68.727577 -97.16008) (xy 67.611498 -97.16008) (xy 67.610994 -97.197986) (xy 67.602935 -97.273367)
			(xy 67.58691 -97.347465) (xy 67.5631 -97.41944) (xy 67.531774 -97.488476) (xy 67.493287 -97.553791)
			(xy 67.448076 -97.614646) (xy 67.396652 -97.67035) (xy 67.339599 -97.720272) (xy 67.277563 -97.763847)
			(xy 67.211246 -97.800582) (xy 67.1414 -97.830059) (xy 67.068817 -97.851945) (xy 66.994319 -97.865992)
			(xy 66.918749 -97.872041) (xy 66.842965 -97.870022) (xy 66.767825 -97.85996) (xy 66.69418 -97.841968)
			(xy 66.622864 -97.81625) (xy 66.554687 -97.783098) (xy 66.490419 -97.742886) (xy 66.43079 -97.696071)
			(xy 66.376474 -97.643183) (xy 66.328088 -97.584821) (xy 66.28618 -97.521646) (xy 66.251224 -97.454375)
			(xy 66.223617 -97.38377) (xy 66.203671 -97.310629) (xy 66.191612 -97.235784) (xy 66.187577 -97.16008)
			(xy 65.071498 -97.16008) (xy 65.070994 -97.197986) (xy 65.062935 -97.273367) (xy 65.04691 -97.347465)
			(xy 65.0231 -97.41944) (xy 64.991774 -97.488476) (xy 64.953287 -97.553791) (xy 64.908076 -97.614646)
			(xy 64.856652 -97.67035) (xy 64.799599 -97.720272) (xy 64.737563 -97.763847) (xy 64.671246 -97.800582)
			(xy 64.6014 -97.830059) (xy 64.528817 -97.851945) (xy 64.454319 -97.865992) (xy 64.378749 -97.872041)
			(xy 64.302965 -97.870022) (xy 64.227825 -97.85996) (xy 64.15418 -97.841968) (xy 64.082864 -97.81625)
			(xy 64.014687 -97.783098) (xy 63.950419 -97.742886) (xy 63.89079 -97.696071) (xy 63.836474 -97.643183)
			(xy 63.788088 -97.584821) (xy 63.74618 -97.521646) (xy 63.711224 -97.454375) (xy 63.683617 -97.38377)
			(xy 63.663671 -97.310629) (xy 63.651612 -97.235784) (xy 63.647577 -97.16008) (xy 42.500813 -97.16008)
			(xy 42.479042 -97.176857) (xy 42.381609 -97.241665) (xy 42.279905 -97.29954) (xy 42.174422 -97.350202)
			(xy 42.065671 -97.393404) (xy 41.954179 -97.428939) (xy 41.840485 -97.456634) (xy 41.725141 -97.476354)
			(xy 41.608704 -97.488005) (xy 41.491739 -97.49153) (xy 41.374812 -97.486912) (xy 41.258489 -97.474173)
			(xy 41.143334 -97.453375) (xy 41.029905 -97.424618) (xy 40.91875 -97.388042) (xy 40.810407 -97.343825)
			(xy 40.705403 -97.292179) (xy 40.604244 -97.233356) (xy 40.507421 -97.16764) (xy 40.415403 -97.095349)
			(xy 40.328636 -97.016834) (xy 40.247539 -96.932474) (xy 40.172506 -96.842679) (xy 40.103899 -96.747883)
			(xy 40.042051 -96.648544) (xy 39.987262 -96.545145) (xy 39.939796 -96.438186) (xy 39.899884 -96.328185)
			(xy 39.86772 -96.215674) (xy 39.843457 -96.101199) (xy 39.827215 -95.985313) (xy 39.819072 -95.868579)
			(xy 39.818564 -95.81007) (xy 36.437073 -95.81007) (xy 36.431719 -95.828889) (xy 36.400327 -95.909921)
			(xy 36.361593 -95.98771) (xy 36.315846 -96.061594) (xy 36.263477 -96.130941) (xy 36.204933 -96.195161)
			(xy 36.140713 -96.253705) (xy 36.071366 -96.306074) (xy 35.997482 -96.351821) (xy 35.919693 -96.390555)
			(xy 35.838661 -96.421947) (xy 35.755079 -96.445728) (xy 35.669659 -96.461696) (xy 35.58313 -96.469714)
			(xy 35.49623 -96.469714) (xy 35.409701 -96.461696) (xy 35.324281 -96.445728) (xy 35.240699 -96.421947)
			(xy 35.159667 -96.390555) (xy 35.081878 -96.351821) (xy 35.007994 -96.306074) (xy 34.938647 -96.253705)
			(xy 34.874427 -96.195161) (xy 34.815883 -96.130941) (xy 34.763514 -96.061594) (xy 34.717767 -95.98771)
			(xy 34.679033 -95.909921) (xy 34.647641 -95.828889) (xy 34.62386 -95.745307) (xy 34.607892 -95.659887)
			(xy 34.599874 -95.573358) (xy 31.399486 -95.573358) (xy 31.391468 -95.659887) (xy 31.3755 -95.745307)
			(xy 31.351719 -95.828889) (xy 31.320327 -95.909921) (xy 31.281593 -95.98771) (xy 31.235846 -96.061594)
			(xy 31.183477 -96.130941) (xy 31.124933 -96.195161) (xy 31.060713 -96.253705) (xy 30.991366 -96.306074)
			(xy 30.917482 -96.351821) (xy 30.839693 -96.390555) (xy 30.758661 -96.421947) (xy 30.675079 -96.445728)
			(xy 30.589659 -96.461696) (xy 30.50313 -96.469714) (xy 30.41623 -96.469714) (xy 30.329701 -96.461696)
			(xy 30.244281 -96.445728) (xy 30.160699 -96.421947) (xy 30.079667 -96.390555) (xy 30.001878 -96.351821)
			(xy 29.927994 -96.306074) (xy 29.858647 -96.253705) (xy 29.794427 -96.195161) (xy 29.735883 -96.130941)
			(xy 29.683514 -96.061594) (xy 29.637767 -95.98771) (xy 29.599033 -95.909921) (xy 29.567641 -95.828889)
			(xy 29.54386 -95.745307) (xy 29.527892 -95.659887) (xy 29.519874 -95.573358) (xy 27.514422 -95.573358)
			(xy 27.517343 -95.593208) (xy 27.517852 -95.621094) (xy 27.517343 -95.64898) (xy 27.509223 -95.704156)
			(xy 27.493155 -95.757563) (xy 27.469483 -95.80806) (xy 27.43871 -95.854573) (xy 27.401493 -95.89611)
			(xy 27.358625 -95.931785) (xy 27.311019 -95.960839) (xy 27.25969 -95.982651) (xy 27.205733 -95.996757)
			(xy 27.150296 -96.002857) (xy 27.094562 -96.00082) (xy 27.039719 -95.99069) (xy 26.986935 -95.972683)
			(xy 26.937335 -95.947182) (xy 26.891977 -95.914731) (xy 26.851828 -95.876022) (xy 26.817742 -95.831879)
			(xy 26.790446 -95.783244) (xy 26.770523 -95.731153) (xy 26.758397 -95.676716) (xy 26.754326 -95.621094)
			(xy 23.551896 -95.621094) (xy 23.551896 -98.113358) (xy 29.519874 -98.113358) (xy 29.519874 -98.026458)
			(xy 29.527892 -97.939929) (xy 29.54386 -97.854509) (xy 29.567641 -97.770927) (xy 29.599033 -97.689895)
			(xy 29.637767 -97.612106) (xy 29.683514 -97.538222) (xy 29.735883 -97.468875) (xy 29.794427 -97.404655)
			(xy 29.858647 -97.346111) (xy 29.927994 -97.293742) (xy 30.001878 -97.247995) (xy 30.079667 -97.209261)
			(xy 30.160699 -97.177869) (xy 30.244281 -97.154088) (xy 30.329701 -97.13812) (xy 30.41623 -97.130102)
			(xy 30.50313 -97.130102) (xy 30.589659 -97.13812) (xy 30.675079 -97.154088) (xy 30.758661 -97.177869)
			(xy 30.839693 -97.209261) (xy 30.917482 -97.247995) (xy 30.991366 -97.293742) (xy 31.060713 -97.346111)
			(xy 31.124933 -97.404655) (xy 31.183477 -97.468875) (xy 31.235846 -97.538222) (xy 31.281593 -97.612106)
			(xy 31.320327 -97.689895) (xy 31.351719 -97.770927) (xy 31.3755 -97.854509) (xy 31.391468 -97.939929)
			(xy 31.399486 -98.026458) (xy 31.399988 -98.069908) (xy 31.399486 -98.113358) (xy 34.599874 -98.113358)
			(xy 34.599874 -98.026458) (xy 34.607892 -97.939929) (xy 34.62386 -97.854509) (xy 34.647641 -97.770927)
			(xy 34.679033 -97.689895) (xy 34.717767 -97.612106) (xy 34.763514 -97.538222) (xy 34.815883 -97.468875)
			(xy 34.874427 -97.404655) (xy 34.938647 -97.346111) (xy 35.007994 -97.293742) (xy 35.081878 -97.247995)
			(xy 35.159667 -97.209261) (xy 35.240699 -97.177869) (xy 35.324281 -97.154088) (xy 35.409701 -97.13812)
			(xy 35.49623 -97.130102) (xy 35.58313 -97.130102) (xy 35.669659 -97.13812) (xy 35.755079 -97.154088)
			(xy 35.838661 -97.177869) (xy 35.919693 -97.209261) (xy 35.997482 -97.247995) (xy 36.071366 -97.293742)
			(xy 36.140713 -97.346111) (xy 36.204933 -97.404655) (xy 36.263477 -97.468875) (xy 36.315846 -97.538222)
			(xy 36.361593 -97.612106) (xy 36.400327 -97.689895) (xy 36.431719 -97.770927) (xy 36.4555 -97.854509)
			(xy 36.471468 -97.939929) (xy 36.479486 -98.026458) (xy 36.479988 -98.069908) (xy 36.479486 -98.113358)
			(xy 36.471468 -98.199887) (xy 36.4555 -98.285307) (xy 36.431719 -98.368889) (xy 36.400327 -98.449921)
			(xy 36.361593 -98.52771) (xy 36.315846 -98.601594) (xy 36.263477 -98.670941) (xy 36.204933 -98.735161)
			(xy 36.140713 -98.793705) (xy 36.071366 -98.846074) (xy 35.997482 -98.891821) (xy 35.919693 -98.930555)
			(xy 35.838661 -98.961947) (xy 35.755079 -98.985728) (xy 35.669659 -99.001696) (xy 35.58313 -99.009714)
			(xy 35.49623 -99.009714) (xy 35.409701 -99.001696) (xy 35.324281 -98.985728) (xy 35.240699 -98.961947)
			(xy 35.159667 -98.930555) (xy 35.081878 -98.891821) (xy 35.007994 -98.846074) (xy 34.938647 -98.793705)
			(xy 34.874427 -98.735161) (xy 34.815883 -98.670941) (xy 34.763514 -98.601594) (xy 34.717767 -98.52771)
			(xy 34.679033 -98.449921) (xy 34.647641 -98.368889) (xy 34.62386 -98.285307) (xy 34.607892 -98.199887)
			(xy 34.599874 -98.113358) (xy 31.399486 -98.113358) (xy 31.391468 -98.199887) (xy 31.3755 -98.285307)
			(xy 31.351719 -98.368889) (xy 31.320327 -98.449921) (xy 31.281593 -98.52771) (xy 31.235846 -98.601594)
			(xy 31.183477 -98.670941) (xy 31.124933 -98.735161) (xy 31.060713 -98.793705) (xy 30.991366 -98.846074)
			(xy 30.917482 -98.891821) (xy 30.839693 -98.930555) (xy 30.758661 -98.961947) (xy 30.675079 -98.985728)
			(xy 30.589659 -99.001696) (xy 30.50313 -99.009714) (xy 30.41623 -99.009714) (xy 30.329701 -99.001696)
			(xy 30.244281 -98.985728) (xy 30.160699 -98.961947) (xy 30.079667 -98.930555) (xy 30.001878 -98.891821)
			(xy 29.927994 -98.846074) (xy 29.858647 -98.793705) (xy 29.794427 -98.735161) (xy 29.735883 -98.670941)
			(xy 29.683514 -98.601594) (xy 29.637767 -98.52771) (xy 29.599033 -98.449921) (xy 29.567641 -98.368889)
			(xy 29.54386 -98.285307) (xy 29.527892 -98.199887) (xy 29.519874 -98.113358) (xy 23.551896 -98.113358)
			(xy 23.551896 -99.369626) (xy 26.722068 -99.369626) (xy 26.726139 -99.314004) (xy 26.738265 -99.259567)
			(xy 26.758188 -99.207476) (xy 26.785484 -99.158841) (xy 26.81957 -99.114698) (xy 26.859719 -99.075989)
			(xy 26.905077 -99.043538) (xy 26.954677 -99.018037) (xy 27.007461 -99.00003) (xy 27.062304 -98.9899)
			(xy 27.118038 -98.987863) (xy 27.173475 -98.993963) (xy 27.227432 -99.008069) (xy 27.278761 -99.029881)
			(xy 27.326367 -99.058935) (xy 27.369235 -99.09461) (xy 27.406452 -99.136147) (xy 27.437225 -99.18266)
			(xy 27.460897 -99.233157) (xy 27.476965 -99.286564) (xy 27.485085 -99.34174) (xy 27.485594 -99.369626)
			(xy 27.485085 -99.397512) (xy 27.476965 -99.452688) (xy 27.460897 -99.506095) (xy 27.437225 -99.556592)
			(xy 27.406452 -99.603105) (xy 27.369235 -99.644642) (xy 27.326367 -99.680317) (xy 27.278761 -99.709371)
			(xy 27.227432 -99.731183) (xy 27.173475 -99.745289) (xy 27.118038 -99.751389) (xy 27.062304 -99.749352)
			(xy 27.007461 -99.739222) (xy 26.954677 -99.721215) (xy 26.905077 -99.695714) (xy 26.859719 -99.663263)
			(xy 26.81957 -99.624554) (xy 26.785484 -99.580411) (xy 26.758188 -99.531776) (xy 26.738265 -99.479685)
			(xy 26.726139 -99.425248) (xy 26.722068 -99.369626) (xy 23.551896 -99.369626) (xy 23.551896 -100.644071)
			(xy 28.700637 -100.644071) (xy 28.703538 -100.589034) (xy 28.714329 -100.534987) (xy 28.732787 -100.483056)
			(xy 28.758526 -100.434323) (xy 28.791012 -100.389801) (xy 28.829567 -100.350418) (xy 28.873389 -100.316995)
			(xy 28.921565 -100.290226) (xy 28.973093 -100.27067) (xy 29.026898 -100.258733) (xy 29.081861 -100.254665)
			(xy 29.136838 -100.258549) (xy 29.190683 -100.270306) (xy 29.242275 -100.289689) (xy 29.266642 -100.302568)
			(xy 29.286857 -100.313124) (xy 29.330086 -100.327636) (xy 29.37521 -100.334207) (xy 29.420783 -100.332626)
			(xy 29.465343 -100.322943) (xy 29.507462 -100.30547) (xy 29.545791 -100.280766) (xy 29.5791 -100.249623)
			(xy 29.606321 -100.213039) (xy 29.616908 -100.19284) (xy 29.636481 -100.154349) (xy 29.681725 -100.080791)
			(xy 29.733522 -100.011691) (xy 29.791437 -99.947632) (xy 29.854981 -99.889152) (xy 29.923619 -99.836744)
			(xy 29.996773 -99.79085) (xy 30.073827 -99.751857) (xy 30.154131 -99.720093) (xy 30.23701 -99.695825)
			(xy 30.321764 -99.679258) (xy 30.40768 -99.670532) (xy 30.494035 -99.669719) (xy 30.5801 -99.676828)
			(xy 30.665151 -99.691797) (xy 30.748471 -99.714501) (xy 30.829359 -99.744749) (xy 30.907133 -99.782286)
			(xy 30.981137 -99.826795) (xy 31.050749 -99.877902) (xy 31.115383 -99.935176) (xy 31.174492 -99.998135)
			(xy 31.227581 -100.066248) (xy 31.2742 -100.138941) (xy 31.313959 -100.215603) (xy 31.346521 -100.295587)
			(xy 31.371613 -100.37822) (xy 31.389023 -100.462805) (xy 31.398604 -100.54863) (xy 31.400276 -100.634972)
			(xy 31.398942 -100.653358) (xy 34.599874 -100.653358) (xy 34.599874 -100.566458) (xy 34.607892 -100.479929)
			(xy 34.62386 -100.394509) (xy 34.647641 -100.310927) (xy 34.679033 -100.229895) (xy 34.717767 -100.152106)
			(xy 34.763514 -100.078222) (xy 34.815883 -100.008875) (xy 34.874427 -99.944655) (xy 34.938647 -99.886111)
			(xy 35.007994 -99.833742) (xy 35.081878 -99.787995) (xy 35.159667 -99.749261) (xy 35.240699 -99.717869)
			(xy 35.324281 -99.694088) (xy 35.409701 -99.67812) (xy 35.49623 -99.670102) (xy 35.58313 -99.670102)
			(xy 35.669659 -99.67812) (xy 35.755079 -99.694088) (xy 35.838661 -99.717869) (xy 35.919693 -99.749261)
			(xy 35.997482 -99.787995) (xy 36.071366 -99.833742) (xy 36.140713 -99.886111) (xy 36.204933 -99.944655)
			(xy 36.263477 -100.008875) (xy 36.315846 -100.078222) (xy 36.361593 -100.152106) (xy 36.400327 -100.229895)
			(xy 36.431719 -100.310927) (xy 36.4555 -100.394509) (xy 36.471468 -100.479929) (xy 36.479486 -100.566458)
			(xy 36.479988 -100.609908) (xy 36.479486 -100.653358) (xy 36.471468 -100.739887) (xy 36.4555 -100.825307)
			(xy 36.431719 -100.908889) (xy 36.400327 -100.989921) (xy 36.361593 -101.06771) (xy 36.315846 -101.141594)
			(xy 36.263477 -101.210941) (xy 36.204933 -101.275161) (xy 36.140713 -101.333705) (xy 36.071366 -101.386074)
			(xy 35.997482 -101.431821) (xy 35.919693 -101.470555) (xy 35.838661 -101.501947) (xy 35.755079 -101.525728)
			(xy 35.669659 -101.541696) (xy 35.58313 -101.549714) (xy 35.49623 -101.549714) (xy 35.409701 -101.541696)
			(xy 35.324281 -101.525728) (xy 35.240699 -101.501947) (xy 35.159667 -101.470555) (xy 35.081878 -101.431821)
			(xy 35.007994 -101.386074) (xy 34.938647 -101.333705) (xy 34.874427 -101.275161) (xy 34.815883 -101.210941)
			(xy 34.763514 -101.141594) (xy 34.717767 -101.06771) (xy 34.679033 -100.989921) (xy 34.647641 -100.908889)
			(xy 34.62386 -100.825307) (xy 34.607892 -100.739887) (xy 34.599874 -100.653358) (xy 31.398942 -100.653358)
			(xy 31.394025 -100.721104) (xy 31.379903 -100.8063) (xy 31.358029 -100.889842) (xy 31.328588 -100.971027)
			(xy 31.291828 -101.04917) (xy 31.248057 -101.123614) (xy 31.197646 -101.193732) (xy 31.141018 -101.258932)
			(xy 31.078651 -101.318665) (xy 31.01107 -101.372429) (xy 30.938844 -101.41977) (xy 30.862582 -101.46029)
			(xy 30.782926 -101.493647) (xy 30.700547 -101.51956) (xy 30.616139 -101.537811) (xy 30.530414 -101.548247)
			(xy 30.444093 -101.550778) (xy 30.357903 -101.545385) (xy 30.272571 -101.532112) (xy 30.188815 -101.511071)
			(xy 30.107341 -101.482439) (xy 30.028835 -101.446459) (xy 29.953959 -101.403431) (xy 29.883344 -101.353721)
			(xy 29.817583 -101.297745) (xy 29.757232 -101.235975) (xy 29.702798 -101.168933) (xy 29.65474 -101.097182)
			(xy 29.633672 -101.059488) (xy 29.622346 -101.039693) (xy 29.593782 -101.004146) (xy 29.559329 -100.974272)
			(xy 29.520095 -100.95103) (xy 29.477342 -100.935168) (xy 29.432443 -100.927195) (xy 29.386842 -100.927367)
			(xy 29.342005 -100.935679) (xy 29.299372 -100.951865) (xy 29.279596 -100.963222) (xy 29.255722 -100.976995)
			(xy 29.204927 -100.998382) (xy 29.151583 -101.012236) (xy 29.096801 -101.018268) (xy 29.041721 -101.016353)
			(xy 28.98749 -101.00653) (xy 28.935237 -100.989004) (xy 28.886051 -100.96414) (xy 28.840955 -100.932456)
			(xy 28.800889 -100.894612) (xy 28.766686 -100.851395) (xy 28.73906 -100.803705) (xy 28.718585 -100.752536)
			(xy 28.705688 -100.698953) (xy 28.700637 -100.644071) (xy 23.551896 -100.644071) (xy 23.551896 -101.906578)
			(xy 39.461692 -101.906578) (xy 39.465763 -101.850956) (xy 39.477889 -101.796519) (xy 39.497812 -101.744428)
			(xy 39.525108 -101.695793) (xy 39.559194 -101.65165) (xy 39.599343 -101.612941) (xy 39.644701 -101.58049)
			(xy 39.694301 -101.554989) (xy 39.747085 -101.536982) (xy 39.801928 -101.526852) (xy 39.857662 -101.524815)
			(xy 39.913099 -101.530915) (xy 39.967056 -101.545021) (xy 40.018385 -101.566833) (xy 40.021909 -101.568984)
			(xy 60.513567 -101.568984) (xy 60.517459 -101.514629) (xy 60.529047 -101.461382) (xy 60.548095 -101.410326)
			(xy 60.574216 -101.3625) (xy 60.590176 -101.340412) (xy 60.603762 -101.321393) (xy 60.624497 -101.279512)
			(xy 60.637225 -101.234545) (xy 60.641518 -101.18801) (xy 60.637229 -101.141474) (xy 60.624504 -101.096506)
			(xy 60.603772 -101.054624) (xy 60.590176 -101.035612) (xy 60.574216 -101.013524) (xy 60.548095 -100.965698)
			(xy 60.529047 -100.914642) (xy 60.517459 -100.861395) (xy 60.513567 -100.80704) (xy 60.517451 -100.752685)
			(xy 60.529031 -100.699436) (xy 60.548072 -100.648377) (xy 60.574186 -100.600547) (xy 60.606841 -100.556921)
			(xy 60.645372 -100.518387) (xy 60.688996 -100.485729) (xy 60.736823 -100.459612) (xy 60.787881 -100.440567)
			(xy 60.841129 -100.428983) (xy 60.895484 -100.425095) (xy 60.949839 -100.428983) (xy 61.003087 -100.440567)
			(xy 61.054145 -100.459612) (xy 61.101972 -100.485729) (xy 61.145596 -100.518387) (xy 61.184127 -100.556921)
			(xy 61.216782 -100.600547) (xy 61.242896 -100.648377) (xy 61.261937 -100.699436) (xy 61.273517 -100.752685)
			(xy 61.277401 -100.80704) (xy 61.273509 -100.861395) (xy 61.261921 -100.914642) (xy 61.242873 -100.965698)
			(xy 61.216752 -101.013524) (xy 61.200792 -101.035612) (xy 61.187186 -101.054617) (xy 61.166455 -101.096502)
			(xy 61.153731 -101.141472) (xy 61.149442 -101.18801) (xy 61.153734 -101.234547) (xy 61.166462 -101.279516)
			(xy 61.187196 -101.3214) (xy 61.200792 -101.340412) (xy 61.216752 -101.3625) (xy 61.242873 -101.410326)
			(xy 61.261921 -101.461382) (xy 61.273509 -101.514629) (xy 61.277401 -101.568984) (xy 61.274806 -101.605306)
			(xy 62.791439 -101.605306) (xy 62.795331 -101.550951) (xy 62.806919 -101.497704) (xy 62.825967 -101.446648)
			(xy 62.852088 -101.398822) (xy 62.868048 -101.376734) (xy 62.88161 -101.3577) (xy 62.902341 -101.315821)
			(xy 62.915068 -101.270859) (xy 62.919362 -101.224327) (xy 62.915078 -101.177795) (xy 62.902361 -101.13283)
			(xy 62.881638 -101.090947) (xy 62.868048 -101.071934) (xy 62.852088 -101.049846) (xy 62.825967 -101.00202)
			(xy 62.806919 -100.950964) (xy 62.795331 -100.897717) (xy 62.791439 -100.843362) (xy 62.795323 -100.789007)
			(xy 62.806903 -100.735758) (xy 62.825944 -100.684699) (xy 62.852058 -100.636869) (xy 62.884713 -100.593243)
			(xy 62.923244 -100.554709) (xy 62.966868 -100.522051) (xy 63.014695 -100.495934) (xy 63.065753 -100.476889)
			(xy 63.119001 -100.465305) (xy 63.173356 -100.461417) (xy 63.227711 -100.465305) (xy 63.280959 -100.476889)
			(xy 63.332017 -100.495934) (xy 63.379844 -100.522051) (xy 63.423468 -100.554709) (xy 63.461999 -100.593243)
			(xy 63.494654 -100.636869) (xy 63.520768 -100.684699) (xy 63.539809 -100.735758) (xy 63.551389 -100.789007)
			(xy 63.555273 -100.843362) (xy 63.551381 -100.897717) (xy 63.539793 -100.950964) (xy 63.520745 -101.00202)
			(xy 63.494624 -101.049846) (xy 63.478664 -101.071934) (xy 63.465039 -101.090925) (xy 63.444312 -101.132815)
			(xy 63.431592 -101.177787) (xy 63.427307 -101.224327) (xy 63.431602 -101.270866) (xy 63.444331 -101.315836)
			(xy 63.465067 -101.357721) (xy 63.478664 -101.376734) (xy 63.494624 -101.398822) (xy 63.520745 -101.446648)
			(xy 63.539793 -101.497704) (xy 63.541597 -101.505992) (xy 65.041371 -101.505992) (xy 65.045263 -101.451637)
			(xy 65.056851 -101.39839) (xy 65.075899 -101.347334) (xy 65.10202 -101.299508) (xy 65.11798 -101.27742)
			(xy 65.131558 -101.258396) (xy 65.152294 -101.216516) (xy 65.165023 -101.171551) (xy 65.169316 -101.125016)
			(xy 65.165029 -101.078481) (xy 65.152305 -101.033514) (xy 65.131575 -100.991632) (xy 65.11798 -100.97262)
			(xy 65.10202 -100.950532) (xy 65.075899 -100.902706) (xy 65.056851 -100.85165) (xy 65.045263 -100.798403)
			(xy 65.041371 -100.744048) (xy 65.045255 -100.689693) (xy 65.056835 -100.636444) (xy 65.075876 -100.585385)
			(xy 65.10199 -100.537555) (xy 65.134645 -100.493929) (xy 65.173176 -100.455395) (xy 65.2168 -100.422737)
			(xy 65.264627 -100.39662) (xy 65.315685 -100.377575) (xy 65.368933 -100.365991) (xy 65.423288 -100.362103)
			(xy 65.477643 -100.365991) (xy 65.530891 -100.377575) (xy 65.581949 -100.39662) (xy 65.629776 -100.422737)
			(xy 65.6734 -100.455395) (xy 65.711931 -100.493929) (xy 65.744586 -100.537555) (xy 65.7707 -100.585385)
			(xy 65.789741 -100.636444) (xy 65.801321 -100.689693) (xy 65.805205 -100.744048) (xy 65.801313 -100.798403)
			(xy 65.789725 -100.85165) (xy 65.770677 -100.902706) (xy 65.744556 -100.950532) (xy 65.728596 -100.97262)
			(xy 65.714982 -100.99162) (xy 65.694252 -101.033506) (xy 65.681528 -101.078477) (xy 65.677241 -101.125016)
			(xy 65.681534 -101.171554) (xy 65.694263 -101.216524) (xy 65.714999 -101.258408) (xy 65.728596 -101.27742)
			(xy 65.744556 -101.299508) (xy 65.770677 -101.347334) (xy 65.789725 -101.39839) (xy 65.801313 -101.451637)
			(xy 65.805205 -101.505992) (xy 65.805187 -101.506246) (xy 67.192243 -101.506246) (xy 67.196135 -101.451891)
			(xy 67.207723 -101.398644) (xy 67.226771 -101.347588) (xy 67.252892 -101.299762) (xy 67.268852 -101.277674)
			(xy 67.282474 -101.258679) (xy 67.303208 -101.216792) (xy 67.315934 -101.17182) (xy 67.320221 -101.125279)
			(xy 67.315926 -101.078739) (xy 67.303193 -101.033769) (xy 67.282452 -100.991885) (xy 67.268852 -100.972874)
			(xy 67.252892 -100.950786) (xy 67.226771 -100.90296) (xy 67.207723 -100.851904) (xy 67.196135 -100.798657)
			(xy 67.192243 -100.744302) (xy 67.196127 -100.689947) (xy 67.207707 -100.636698) (xy 67.226748 -100.585639)
			(xy 67.252862 -100.537809) (xy 67.285517 -100.494183) (xy 67.324048 -100.455649) (xy 67.367672 -100.422991)
			(xy 67.415499 -100.396874) (xy 67.466557 -100.377829) (xy 67.519805 -100.366245) (xy 67.57416 -100.362357)
			(xy 67.628515 -100.366245) (xy 67.681763 -100.377829) (xy 67.732821 -100.396874) (xy 67.780648 -100.422991)
			(xy 67.824272 -100.455649) (xy 67.862803 -100.494183) (xy 67.895458 -100.537809) (xy 67.921572 -100.585639)
			(xy 67.940613 -100.636698) (xy 67.952193 -100.689947) (xy 67.956077 -100.744302) (xy 67.952185 -100.798657)
			(xy 67.940597 -100.851904) (xy 67.921549 -100.90296) (xy 67.895428 -100.950786) (xy 67.879468 -100.972874)
			(xy 67.865898 -100.991903) (xy 67.845166 -101.033783) (xy 67.832439 -101.078746) (xy 67.828146 -101.125279)
			(xy 67.832431 -101.171813) (xy 67.845151 -101.216778) (xy 67.865876 -101.258661) (xy 67.879468 -101.277674)
			(xy 67.895428 -101.299762) (xy 67.921549 -101.347588) (xy 67.940597 -101.398644) (xy 67.952185 -101.451891)
			(xy 67.956077 -101.506246) (xy 67.953482 -101.542568) (xy 69.348957 -101.542568) (xy 69.352849 -101.488213)
			(xy 69.364437 -101.434966) (xy 69.383485 -101.38391) (xy 69.409606 -101.336084) (xy 69.425566 -101.313996)
			(xy 69.439167 -101.294987) (xy 69.459902 -101.253104) (xy 69.472629 -101.208135) (xy 69.476919 -101.161597)
			(xy 69.472628 -101.115059) (xy 69.4599 -101.070091) (xy 69.439164 -101.028207) (xy 69.425566 -101.009196)
			(xy 69.409606 -100.987108) (xy 69.383485 -100.939282) (xy 69.364437 -100.888226) (xy 69.352849 -100.834979)
			(xy 69.348957 -100.780624) (xy 69.352841 -100.726269) (xy 69.364421 -100.67302) (xy 69.383462 -100.621961)
			(xy 69.409576 -100.574131) (xy 69.442231 -100.530505) (xy 69.480762 -100.491971) (xy 69.524386 -100.459313)
			(xy 69.572213 -100.433196) (xy 69.623271 -100.414151) (xy 69.676519 -100.402567) (xy 69.730874 -100.398679)
			(xy 69.785229 -100.402567) (xy 69.838477 -100.414151) (xy 69.889535 -100.433196) (xy 69.937362 -100.459313)
			(xy 69.980986 -100.491971) (xy 70.019517 -100.530505) (xy 70.052172 -100.574131) (xy 70.078286 -100.621961)
			(xy 70.097327 -100.67302) (xy 70.108907 -100.726269) (xy 70.112791 -100.780624) (xy 70.108899 -100.834979)
			(xy 70.097311 -100.888226) (xy 70.078263 -100.939282) (xy 70.052142 -100.987108) (xy 70.036182 -101.009196)
			(xy 70.022591 -101.028211) (xy 70.00186 -101.070094) (xy 69.989134 -101.115061) (xy 69.984844 -101.161597)
			(xy 69.989133 -101.208133) (xy 70.001857 -101.2531) (xy 70.022588 -101.294984) (xy 70.036182 -101.313996)
			(xy 70.052142 -101.336084) (xy 70.078263 -101.38391) (xy 70.097311 -101.434966) (xy 70.108899 -101.488213)
			(xy 70.112791 -101.542568) (xy 70.108907 -101.596923) (xy 70.097327 -101.650172) (xy 70.078286 -101.701231)
			(xy 70.052172 -101.749061) (xy 70.019517 -101.792687) (xy 69.980986 -101.831221) (xy 69.937362 -101.863879)
			(xy 69.889535 -101.889996) (xy 69.838477 -101.909041) (xy 69.785229 -101.920625) (xy 69.730874 -101.924513)
			(xy 69.676519 -101.920625) (xy 69.623271 -101.909041) (xy 69.572213 -101.889996) (xy 69.524386 -101.863879)
			(xy 69.480762 -101.831221) (xy 69.442231 -101.792687) (xy 69.409576 -101.749061) (xy 69.383462 -101.701231)
			(xy 69.364421 -101.650172) (xy 69.352841 -101.596923) (xy 69.348957 -101.542568) (xy 67.953482 -101.542568)
			(xy 67.952193 -101.560601) (xy 67.940613 -101.61385) (xy 67.921572 -101.664909) (xy 67.895458 -101.712739)
			(xy 67.862803 -101.756365) (xy 67.824272 -101.794899) (xy 67.780648 -101.827557) (xy 67.732821 -101.853674)
			(xy 67.681763 -101.872719) (xy 67.628515 -101.884303) (xy 67.57416 -101.888191) (xy 67.519805 -101.884303)
			(xy 67.466557 -101.872719) (xy 67.415499 -101.853674) (xy 67.367672 -101.827557) (xy 67.324048 -101.794899)
			(xy 67.285517 -101.756365) (xy 67.252862 -101.712739) (xy 67.226748 -101.664909) (xy 67.207707 -101.61385)
			(xy 67.196127 -101.560601) (xy 67.192243 -101.506246) (xy 65.805187 -101.506246) (xy 65.801321 -101.560347)
			(xy 65.789741 -101.613596) (xy 65.7707 -101.664655) (xy 65.744586 -101.712485) (xy 65.711931 -101.756111)
			(xy 65.6734 -101.794645) (xy 65.629776 -101.827303) (xy 65.581949 -101.85342) (xy 65.530891 -101.872465)
			(xy 65.477643 -101.884049) (xy 65.423288 -101.887937) (xy 65.368933 -101.884049) (xy 65.315685 -101.872465)
			(xy 65.264627 -101.85342) (xy 65.2168 -101.827303) (xy 65.173176 -101.794645) (xy 65.134645 -101.756111)
			(xy 65.10199 -101.712485) (xy 65.075876 -101.664655) (xy 65.056835 -101.613596) (xy 65.045255 -101.560347)
			(xy 65.041371 -101.505992) (xy 63.541597 -101.505992) (xy 63.551381 -101.550951) (xy 63.555273 -101.605306)
			(xy 63.551389 -101.659661) (xy 63.539809 -101.71291) (xy 63.520768 -101.763969) (xy 63.494654 -101.811799)
			(xy 63.461999 -101.855425) (xy 63.423468 -101.893959) (xy 63.379844 -101.926617) (xy 63.332017 -101.952734)
			(xy 63.280959 -101.971779) (xy 63.227711 -101.983363) (xy 63.173356 -101.987251) (xy 63.119001 -101.983363)
			(xy 63.065753 -101.971779) (xy 63.014695 -101.952734) (xy 62.966868 -101.926617) (xy 62.923244 -101.893959)
			(xy 62.884713 -101.855425) (xy 62.852058 -101.811799) (xy 62.825944 -101.763969) (xy 62.806903 -101.71291)
			(xy 62.795323 -101.659661) (xy 62.791439 -101.605306) (xy 61.274806 -101.605306) (xy 61.273517 -101.623339)
			(xy 61.261937 -101.676588) (xy 61.242896 -101.727647) (xy 61.216782 -101.775477) (xy 61.184127 -101.819103)
			(xy 61.145596 -101.857637) (xy 61.101972 -101.890295) (xy 61.054145 -101.916412) (xy 61.003087 -101.935457)
			(xy 60.949839 -101.947041) (xy 60.895484 -101.950929) (xy 60.841129 -101.947041) (xy 60.787881 -101.935457)
			(xy 60.736823 -101.916412) (xy 60.688996 -101.890295) (xy 60.645372 -101.857637) (xy 60.606841 -101.819103)
			(xy 60.574186 -101.775477) (xy 60.548072 -101.727647) (xy 60.529031 -101.676588) (xy 60.517451 -101.623339)
			(xy 60.513567 -101.568984) (xy 40.021909 -101.568984) (xy 40.065991 -101.595887) (xy 40.108859 -101.631562)
			(xy 40.146076 -101.673099) (xy 40.176849 -101.719612) (xy 40.200521 -101.770109) (xy 40.216589 -101.823516)
			(xy 40.224709 -101.878692) (xy 40.225218 -101.906578) (xy 40.224709 -101.934464) (xy 40.216589 -101.98964)
			(xy 40.205127 -102.027736) (xy 86.51062 -102.027736) (xy 86.514691 -101.972114) (xy 86.526817 -101.917677)
			(xy 86.54674 -101.865586) (xy 86.574036 -101.816951) (xy 86.608122 -101.772808) (xy 86.648271 -101.734099)
			(xy 86.693629 -101.701648) (xy 86.743229 -101.676147) (xy 86.796013 -101.65814) (xy 86.850856 -101.64801)
			(xy 86.90659 -101.645973) (xy 86.962027 -101.652073) (xy 87.015984 -101.666179) (xy 87.067313 -101.687991)
			(xy 87.114919 -101.717045) (xy 87.157787 -101.75272) (xy 87.195004 -101.794257) (xy 87.225777 -101.84077)
			(xy 87.249449 -101.891267) (xy 87.265517 -101.944674) (xy 87.273637 -101.99985) (xy 87.274146 -102.027736)
			(xy 87.273637 -102.055622) (xy 87.265517 -102.110798) (xy 87.249449 -102.164205) (xy 87.225777 -102.214702)
			(xy 87.195004 -102.261215) (xy 87.157787 -102.302752) (xy 87.114919 -102.338427) (xy 87.067313 -102.367481)
			(xy 87.015984 -102.389293) (xy 86.962027 -102.403399) (xy 86.90659 -102.409499) (xy 86.850856 -102.407462)
			(xy 86.796013 -102.397332) (xy 86.743229 -102.379325) (xy 86.693629 -102.353824) (xy 86.648271 -102.321373)
			(xy 86.608122 -102.282664) (xy 86.574036 -102.238521) (xy 86.54674 -102.189886) (xy 86.526817 -102.137795)
			(xy 86.514691 -102.083358) (xy 86.51062 -102.027736) (xy 40.205127 -102.027736) (xy 40.200521 -102.043047)
			(xy 40.176849 -102.093544) (xy 40.146076 -102.140057) (xy 40.108859 -102.181594) (xy 40.065991 -102.217269)
			(xy 40.018385 -102.246323) (xy 39.967056 -102.268135) (xy 39.913099 -102.282241) (xy 39.857662 -102.288341)
			(xy 39.801928 -102.286304) (xy 39.747085 -102.276174) (xy 39.694301 -102.258167) (xy 39.644701 -102.232666)
			(xy 39.599343 -102.200215) (xy 39.559194 -102.161506) (xy 39.525108 -102.117363) (xy 39.497812 -102.068728)
			(xy 39.477889 -102.016637) (xy 39.465763 -101.9622) (xy 39.461692 -101.906578) (xy 23.551896 -101.906578)
			(xy 23.551896 -105.602024) (xy 23.553127 -105.618169) (xy 23.562702 -105.649089) (xy 23.579734 -105.676614)
			(xy 23.60313 -105.698983) (xy 23.631393 -105.71476) (xy 23.662712 -105.722937) (xy 23.678896 -105.723436)
			(xy 23.680674 -105.723436) (xy 23.708767 -105.724088) (xy 23.764305 -105.732629) (xy 23.817992 -105.74922)
			(xy 23.868665 -105.773504) (xy 23.91523 -105.804956) (xy 23.95668 -105.842895) (xy 23.99212 -105.886501)
			(xy 24.020783 -105.934833) (xy 24.04205 -105.986844) (xy 24.049228 -106.014012) (xy 24.056022 -106.034762)
			(xy 24.075695 -106.073736) (xy 24.10174 -106.108775) (xy 24.133391 -106.138846) (xy 24.169717 -106.163064)
			(xy 24.209647 -106.180717) (xy 24.252006 -106.191285) (xy 24.295549 -106.194457) (xy 24.338994 -106.19014)
			(xy 24.381061 -106.178461) (xy 24.420512 -106.159763) (xy 24.456187 -106.134597) (xy 24.471884 -106.119422)
			(xy 26.64841 -103.942896) (xy 26.700734 -103.942896) (xy 26.774902 -103.868728) (xy 26.774902 -103.815642)
			(xy 26.774386 -103.799168) (xy 26.76595 -103.767318) (xy 26.749631 -103.738694) (xy 26.72652 -103.715211)
			(xy 26.698161 -103.698437) (xy 26.682446 -103.693468) (xy 26.682192 -103.693468) (xy 26.675588 -103.691436)
			(xy 26.6638 -103.687837) (xy 26.640668 -103.679321) (xy 26.62936 -103.674418) (xy 26.604358 -103.662744)
			(xy 26.557716 -103.633263) (xy 26.515806 -103.597371) (xy 26.479501 -103.555819) (xy 26.449559 -103.509472)
			(xy 26.426603 -103.459296) (xy 26.411111 -103.406337) (xy 26.403407 -103.351699) (xy 26.403652 -103.296522)
			(xy 26.41184 -103.241955) (xy 26.4278 -103.189135) (xy 26.4512 -103.139165) (xy 26.481552 -103.093085)
			(xy 26.499566 -103.072184) (xy 26.518937 -103.051192) (xy 26.562856 -103.014673) (xy 26.611729 -102.98511)
			(xy 26.664462 -102.963162) (xy 26.719878 -102.949321) (xy 26.776739 -102.943895) (xy 26.833772 -102.947007)
			(xy 26.889705 -102.958586) (xy 26.943287 -102.978373) (xy 26.993319 -103.005928) (xy 27.038686 -103.040632)
			(xy 27.078371 -103.081713) (xy 27.11149 -103.12825) (xy 27.124914 -103.153464) (xy 27.136722 -103.177812)
			(xy 27.154114 -103.229052) (xy 27.164091 -103.282235) (xy 27.166453 -103.336295) (xy 27.164284 -103.363268)
			(xy 27.161524 -103.387444) (xy 27.150646 -103.434872) (xy 27.133822 -103.480531) (xy 27.111327 -103.523678)
			(xy 27.097736 -103.543862) (xy 27.084981 -103.563085) (xy 27.065911 -103.605087) (xy 27.054733 -103.649841)
			(xy 27.051814 -103.695877) (xy 27.057251 -103.741685) (xy 27.070864 -103.785759) (xy 27.092207 -103.826653)
			(xy 27.120579 -103.863025) (xy 27.155049 -103.893679) (xy 27.194484 -103.917611) (xy 27.23759 -103.934034)
			(xy 27.282952 -103.942408) (xy 27.306016 -103.942896) (xy 29.393896 -103.942896) (xy 29.416925 -103.942416)
			(xy 29.462237 -103.934155) (xy 29.505319 -103.917868) (xy 29.544762 -103.894087) (xy 29.579277 -103.86359)
			(xy 29.607733 -103.827374) (xy 29.6292 -103.786625) (xy 29.642976 -103.742675) (xy 29.64861 -103.696963)
			(xy 29.645917 -103.650984) (xy 29.634986 -103.606242) (xy 29.626052 -103.58501) (xy 29.606532 -103.546556)
			(xy 29.573799 -103.466765) (xy 29.548508 -103.384313) (xy 29.530873 -103.299891) (xy 29.521042 -103.214209)
			(xy 29.519097 -103.127987) (xy 29.525055 -103.041949) (xy 29.538865 -102.956818) (xy 29.560412 -102.873309)
			(xy 29.589514 -102.792123) (xy 29.625927 -102.713944) (xy 29.669346 -102.639426) (xy 29.719404 -102.569197)
			(xy 29.775683 -102.503846) (xy 29.837709 -102.443922) (xy 29.904961 -102.38993) (xy 29.976873 -102.342321)
			(xy 30.052843 -102.301497) (xy 30.132232 -102.2678) (xy 30.214372 -102.241513) (xy 30.298574 -102.222857)
			(xy 30.384131 -102.21199) (xy 30.470323 -102.209001) (xy 30.556427 -102.213916) (xy 30.641719 -102.226695)
			(xy 30.683708 -102.236524) (xy 30.72575 -102.247351) (xy 30.807807 -102.275718) (xy 30.886899 -102.311529)
			(xy 30.962354 -102.354479) (xy 31.033528 -102.404201) (xy 31.099816 -102.460272) (xy 31.160652 -102.522215)
			(xy 31.21552 -102.589502) (xy 31.263951 -102.661561) (xy 31.305533 -102.737777) (xy 31.339913 -102.817502)
			(xy 31.366797 -102.900057) (xy 31.385957 -102.984738) (xy 31.397229 -103.070825) (xy 31.400517 -103.157585)
			(xy 31.398718 -103.200962) (xy 31.397974 -103.222835) (xy 31.403095 -103.266296) (xy 31.415587 -103.308236)
			(xy 31.435081 -103.347416) (xy 31.461 -103.382676) (xy 31.492577 -103.412974) (xy 31.528879 -103.437413)
			(xy 31.568831 -103.45527) (xy 31.611252 -103.466017) (xy 31.654888 -103.469337) (xy 31.698447 -103.46513)
			(xy 31.74064 -103.453522) (xy 31.780221 -103.434856) (xy 31.816018 -103.409684) (xy 31.831788 -103.39451)
			(xy 32.394398 -102.8319) (xy 34.5694 -102.8319) (xy 34.583912 -102.831536) (xy 34.612195 -102.825026)
			(xy 34.638266 -102.812276) (xy 34.66077 -102.793949) (xy 34.678536 -102.770999) (xy 34.68497 -102.757986)
			(xy 34.68497 -102.757732) (xy 34.703442 -102.718649) (xy 34.746553 -102.643715) (xy 34.796361 -102.573054)
			(xy 34.852443 -102.507263) (xy 34.914327 -102.446897) (xy 34.981491 -102.392466) (xy 35.053367 -102.344429)
			(xy 35.129348 -102.303191) (xy 35.208794 -102.269102) (xy 35.291033 -102.242448) (xy 35.375371 -102.223455)
			(xy 35.461097 -102.212283) (xy 35.547486 -102.209026) (xy 35.63381 -102.213712) (xy 35.719339 -102.226301)
			(xy 35.803352 -102.246688) (xy 35.885138 -102.274699) (xy 35.964009 -102.310099) (xy 36.039298 -102.352588)
			(xy 36.110369 -102.401808) (xy 36.176622 -102.457343) (xy 36.237499 -102.518725) (xy 36.292485 -102.585436)
			(xy 36.318983 -102.624382) (xy 84.84057 -102.624382) (xy 84.844641 -102.56876) (xy 84.856767 -102.514323)
			(xy 84.87669 -102.462232) (xy 84.903986 -102.413597) (xy 84.938072 -102.369454) (xy 84.978221 -102.330745)
			(xy 85.023579 -102.298294) (xy 85.073179 -102.272793) (xy 85.125963 -102.254786) (xy 85.180806 -102.244656)
			(xy 85.23654 -102.242619) (xy 85.291977 -102.248719) (xy 85.345934 -102.262825) (xy 85.397263 -102.284637)
			(xy 85.444869 -102.313691) (xy 85.487737 -102.349366) (xy 85.524954 -102.390903) (xy 85.555727 -102.437416)
			(xy 85.579399 -102.487913) (xy 85.595467 -102.54132) (xy 85.603587 -102.596496) (xy 85.604096 -102.624382)
			(xy 85.603587 -102.652268) (xy 85.595467 -102.707444) (xy 85.579399 -102.760851) (xy 85.555727 -102.811348)
			(xy 85.524954 -102.857861) (xy 85.487737 -102.899398) (xy 85.444869 -102.935073) (xy 85.397263 -102.964127)
			(xy 85.345934 -102.985939) (xy 85.291977 -103.000045) (xy 85.23654 -103.006145) (xy 85.180806 -103.004108)
			(xy 85.125963 -102.993978) (xy 85.073179 -102.975971) (xy 85.023579 -102.95047) (xy 84.978221 -102.918019)
			(xy 84.938072 -102.87931) (xy 84.903986 -102.835167) (xy 84.87669 -102.786532) (xy 84.856767 -102.734441)
			(xy 84.844641 -102.680004) (xy 84.84057 -102.624382) (xy 36.318983 -102.624382) (xy 36.341115 -102.656911)
			(xy 36.382981 -102.732549) (xy 36.417727 -102.811709) (xy 36.445061 -102.893725) (xy 36.464752 -102.977903)
			(xy 36.476634 -103.063533) (xy 36.480606 -103.149893) (xy 36.476635 -103.236252) (xy 36.464755 -103.321883)
			(xy 36.445065 -103.406061) (xy 36.417732 -103.488077) (xy 36.382987 -103.567238) (xy 36.341123 -103.642876)
			(xy 36.292493 -103.714353) (xy 36.237509 -103.781064) (xy 36.176633 -103.842447) (xy 36.11038 -103.897983)
			(xy 36.03931 -103.947204) (xy 35.964022 -103.989695) (xy 35.885152 -104.025096) (xy 35.803366 -104.053108)
			(xy 35.719353 -104.073496) (xy 35.633824 -104.086086) (xy 35.547501 -104.090774) (xy 35.461112 -104.087518)
			(xy 35.375386 -104.076348) (xy 35.291047 -104.057356) (xy 35.208807 -104.030703) (xy 35.129361 -103.996615)
			(xy 35.053379 -103.955379) (xy 34.981502 -103.907343) (xy 34.914338 -103.852913) (xy 34.852453 -103.792547)
			(xy 34.796369 -103.726757) (xy 34.746561 -103.656097) (xy 34.703449 -103.581164) (xy 34.68497 -103.542084)
			(xy 34.68497 -103.54183) (xy 34.678542 -103.528815) (xy 34.660759 -103.50588) (xy 34.638252 -103.487558)
			(xy 34.612186 -103.474799) (xy 34.583911 -103.468261) (xy 34.5694 -103.467916) (xy 32.657542 -103.467916)
			(xy 31.885664 -104.239794) (xy 60.513567 -104.239794) (xy 60.517459 -104.185439) (xy 60.529047 -104.132192)
			(xy 60.548095 -104.081136) (xy 60.574216 -104.03331) (xy 60.590176 -104.011222) (xy 60.603752 -103.992197)
			(xy 60.624489 -103.950317) (xy 60.637218 -103.905352) (xy 60.641512 -103.858818) (xy 60.637224 -103.812283)
			(xy 60.624501 -103.767316) (xy 60.603771 -103.725434) (xy 60.590176 -103.706422) (xy 60.574216 -103.684334)
			(xy 60.548095 -103.636508) (xy 60.529047 -103.585452) (xy 60.517459 -103.532205) (xy 60.513567 -103.47785)
			(xy 60.517451 -103.423495) (xy 60.529031 -103.370246) (xy 60.548072 -103.319187) (xy 60.574186 -103.271357)
			(xy 60.606841 -103.227731) (xy 60.645372 -103.189197) (xy 60.688996 -103.156539) (xy 60.736823 -103.130422)
			(xy 60.787881 -103.111377) (xy 60.841129 -103.099793) (xy 60.895484 -103.095905) (xy 60.949839 -103.099793)
			(xy 61.003087 -103.111377) (xy 61.054145 -103.130422) (xy 61.101972 -103.156539) (xy 61.145596 -103.189197)
			(xy 61.184127 -103.227731) (xy 61.216782 -103.271357) (xy 61.242896 -103.319187) (xy 61.261937 -103.370246)
			(xy 61.273517 -103.423495) (xy 61.277401 -103.47785) (xy 61.273509 -103.532205) (xy 61.261921 -103.585452)
			(xy 61.242873 -103.636508) (xy 61.216752 -103.684334) (xy 61.200792 -103.706422) (xy 61.187176 -103.72542)
			(xy 61.166446 -103.767307) (xy 61.153723 -103.812279) (xy 61.149436 -103.858818) (xy 61.15373 -103.905356)
			(xy 61.166459 -103.950325) (xy 61.187195 -103.99221) (xy 61.200792 -104.011222) (xy 61.216752 -104.03331)
			(xy 61.242873 -104.081136) (xy 61.261921 -104.132192) (xy 61.273509 -104.185439) (xy 61.277401 -104.239794)
			(xy 61.274806 -104.276116) (xy 62.791439 -104.276116) (xy 62.795331 -104.221761) (xy 62.806919 -104.168514)
			(xy 62.825967 -104.117458) (xy 62.852088 -104.069632) (xy 62.868048 -104.047544) (xy 62.8816 -104.028503)
			(xy 62.902332 -103.986626) (xy 62.915061 -103.941665) (xy 62.919356 -103.895135) (xy 62.915074 -103.848604)
			(xy 62.902358 -103.803639) (xy 62.881637 -103.761757) (xy 62.868048 -103.742744) (xy 62.852088 -103.720656)
			(xy 62.825967 -103.67283) (xy 62.806919 -103.621774) (xy 62.795331 -103.568527) (xy 62.791439 -103.514172)
			(xy 62.795323 -103.459817) (xy 62.806903 -103.406568) (xy 62.825944 -103.355509) (xy 62.852058 -103.307679)
			(xy 62.884713 -103.264053) (xy 62.923244 -103.225519) (xy 62.966868 -103.192861) (xy 63.014695 -103.166744)
			(xy 63.065753 -103.147699) (xy 63.119001 -103.136115) (xy 63.173356 -103.132227) (xy 63.227711 -103.136115)
			(xy 63.280959 -103.147699) (xy 63.332017 -103.166744) (xy 63.379844 -103.192861) (xy 63.423468 -103.225519)
			(xy 63.461999 -103.264053) (xy 63.494654 -103.307679) (xy 63.520768 -103.355509) (xy 63.539809 -103.406568)
			(xy 63.551389 -103.459817) (xy 63.555273 -103.514172) (xy 63.551381 -103.568527) (xy 63.539793 -103.621774)
			(xy 63.520745 -103.67283) (xy 63.494624 -103.720656) (xy 63.478664 -103.742744) (xy 63.465029 -103.761729)
			(xy 63.444303 -103.80362) (xy 63.431584 -103.848594) (xy 63.427301 -103.895135) (xy 63.431597 -103.941675)
			(xy 63.444329 -103.986646) (xy 63.465066 -104.028531) (xy 63.478664 -104.047544) (xy 63.494624 -104.069632)
			(xy 63.520745 -104.117458) (xy 63.539793 -104.168514) (xy 63.541597 -104.176802) (xy 65.041371 -104.176802)
			(xy 65.045263 -104.122447) (xy 65.056851 -104.0692) (xy 65.075899 -104.018144) (xy 65.10202 -103.970318)
			(xy 65.11798 -103.94823) (xy 65.131549 -103.929199) (xy 65.152285 -103.887321) (xy 65.165015 -103.842357)
			(xy 65.16931 -103.795824) (xy 65.165024 -103.74929) (xy 65.152302 -103.704324) (xy 65.131574 -103.662442)
			(xy 65.11798 -103.64343) (xy 65.10202 -103.621342) (xy 65.075899 -103.573516) (xy 65.056851 -103.52246)
			(xy 65.045263 -103.469213) (xy 65.041371 -103.414858) (xy 65.045255 -103.360503) (xy 65.056835 -103.307254)
			(xy 65.075876 -103.256195) (xy 65.10199 -103.208365) (xy 65.134645 -103.164739) (xy 65.173176 -103.126205)
			(xy 65.2168 -103.093547) (xy 65.264627 -103.06743) (xy 65.315685 -103.048385) (xy 65.368933 -103.036801)
			(xy 65.423288 -103.032913) (xy 65.477643 -103.036801) (xy 65.530891 -103.048385) (xy 65.581949 -103.06743)
			(xy 65.629776 -103.093547) (xy 65.6734 -103.126205) (xy 65.711931 -103.164739) (xy 65.744586 -103.208365)
			(xy 65.7707 -103.256195) (xy 65.789741 -103.307254) (xy 65.801321 -103.360503) (xy 65.805205 -103.414858)
			(xy 65.801313 -103.469213) (xy 65.789725 -103.52246) (xy 65.770677 -103.573516) (xy 65.744556 -103.621342)
			(xy 65.728596 -103.64343) (xy 65.714973 -103.662423) (xy 65.694243 -103.704312) (xy 65.681521 -103.749284)
			(xy 65.677235 -103.795824) (xy 65.68153 -103.842363) (xy 65.69426 -103.887333) (xy 65.714998 -103.929218)
			(xy 65.728596 -103.94823) (xy 65.744556 -103.970318) (xy 65.770677 -104.018144) (xy 65.789725 -104.0692)
			(xy 65.801313 -104.122447) (xy 65.805205 -104.176802) (xy 65.805187 -104.177056) (xy 67.192243 -104.177056)
			(xy 67.196135 -104.122701) (xy 67.207723 -104.069454) (xy 67.226771 -104.018398) (xy 67.252892 -103.970572)
			(xy 67.268852 -103.948484) (xy 67.282465 -103.929483) (xy 67.3032 -103.887598) (xy 67.315926 -103.842627)
			(xy 67.320215 -103.796087) (xy 67.315922 -103.749548) (xy 67.303191 -103.704578) (xy 67.282451 -103.662695)
			(xy 67.268852 -103.643684) (xy 67.252892 -103.621596) (xy 67.226771 -103.57377) (xy 67.207723 -103.522714)
			(xy 67.196135 -103.469467) (xy 67.192243 -103.415112) (xy 67.196127 -103.360757) (xy 67.207707 -103.307508)
			(xy 67.226748 -103.256449) (xy 67.252862 -103.208619) (xy 67.285517 -103.164993) (xy 67.324048 -103.126459)
			(xy 67.367672 -103.093801) (xy 67.415499 -103.067684) (xy 67.466557 -103.048639) (xy 67.519805 -103.037055)
			(xy 67.57416 -103.033167) (xy 67.628515 -103.037055) (xy 67.681763 -103.048639) (xy 67.732821 -103.067684)
			(xy 67.780648 -103.093801) (xy 67.824272 -103.126459) (xy 67.862803 -103.164993) (xy 67.895458 -103.208619)
			(xy 67.921572 -103.256449) (xy 67.940613 -103.307508) (xy 67.952193 -103.360757) (xy 67.956077 -103.415112)
			(xy 67.952185 -103.469467) (xy 67.940597 -103.522714) (xy 67.921549 -103.57377) (xy 67.895428 -103.621596)
			(xy 67.879468 -103.643684) (xy 67.865889 -103.662707) (xy 67.845158 -103.704588) (xy 67.832432 -103.749553)
			(xy 67.82814 -103.796087) (xy 67.832427 -103.842622) (xy 67.845148 -103.887588) (xy 67.865875 -103.929471)
			(xy 67.879468 -103.948484) (xy 67.895428 -103.970572) (xy 67.921549 -104.018398) (xy 67.940597 -104.069454)
			(xy 67.952185 -104.122701) (xy 67.956077 -104.177056) (xy 67.953482 -104.213378) (xy 69.348957 -104.213378)
			(xy 69.352849 -104.159023) (xy 69.364437 -104.105776) (xy 69.383485 -104.05472) (xy 69.409606 -104.006894)
			(xy 69.425566 -103.984806) (xy 69.439158 -103.965791) (xy 69.459893 -103.923909) (xy 69.472622 -103.878941)
			(xy 69.476913 -103.832405) (xy 69.472623 -103.785868) (xy 69.459897 -103.7409) (xy 69.439163 -103.699017)
			(xy 69.425566 -103.680006) (xy 69.409606 -103.657918) (xy 69.383485 -103.610092) (xy 69.364437 -103.559036)
			(xy 69.352849 -103.505789) (xy 69.348957 -103.451434) (xy 69.352841 -103.397079) (xy 69.364421 -103.34383)
			(xy 69.383462 -103.292771) (xy 69.409576 -103.244941) (xy 69.442231 -103.201315) (xy 69.480762 -103.162781)
			(xy 69.524386 -103.130123) (xy 69.572213 -103.104006) (xy 69.623271 -103.084961) (xy 69.676519 -103.073377)
			(xy 69.730874 -103.069489) (xy 69.785229 -103.073377) (xy 69.838477 -103.084961) (xy 69.889535 -103.104006)
			(xy 69.937362 -103.130123) (xy 69.980986 -103.162781) (xy 70.019517 -103.201315) (xy 70.052172 -103.244941)
			(xy 70.078286 -103.292771) (xy 70.097327 -103.34383) (xy 70.108907 -103.397079) (xy 70.112791 -103.451434)
			(xy 70.108899 -103.505789) (xy 70.097311 -103.559036) (xy 70.078263 -103.610092) (xy 70.052142 -103.657918)
			(xy 70.036182 -103.680006) (xy 70.022582 -103.699015) (xy 70.001851 -103.740899) (xy 69.989127 -103.785868)
			(xy 69.984838 -103.832405) (xy 69.989129 -103.878942) (xy 70.001855 -103.92391) (xy 70.010247 -103.940864)
			(xy 83.171282 -103.940864) (xy 83.175353 -103.885242) (xy 83.187479 -103.830805) (xy 83.207402 -103.778714)
			(xy 83.234698 -103.730079) (xy 83.268784 -103.685936) (xy 83.308933 -103.647227) (xy 83.354291 -103.614776)
			(xy 83.403891 -103.589275) (xy 83.456675 -103.571268) (xy 83.511518 -103.561138) (xy 83.567252 -103.559101)
			(xy 83.622689 -103.565201) (xy 83.676646 -103.579307) (xy 83.727975 -103.601119) (xy 83.775581 -103.630173)
			(xy 83.818449 -103.665848) (xy 83.855666 -103.707385) (xy 83.886439 -103.753898) (xy 83.910111 -103.804395)
			(xy 83.926179 -103.857802) (xy 83.934299 -103.912978) (xy 83.934808 -103.940864) (xy 83.934299 -103.96875)
			(xy 83.926179 -104.023926) (xy 83.910111 -104.077333) (xy 83.886439 -104.12783) (xy 83.855666 -104.174343)
			(xy 83.818449 -104.21588) (xy 83.775581 -104.251555) (xy 83.727975 -104.280609) (xy 83.676646 -104.302421)
			(xy 83.622689 -104.316527) (xy 83.567252 -104.322627) (xy 83.511518 -104.32059) (xy 83.456675 -104.31046)
			(xy 83.403891 -104.292453) (xy 83.354291 -104.266952) (xy 83.308933 -104.234501) (xy 83.268784 -104.195792)
			(xy 83.234698 -104.151649) (xy 83.207402 -104.103014) (xy 83.187479 -104.050923) (xy 83.175353 -103.996486)
			(xy 83.171282 -103.940864) (xy 70.010247 -103.940864) (xy 70.022587 -103.965794) (xy 70.036182 -103.984806)
			(xy 70.052142 -104.006894) (xy 70.078263 -104.05472) (xy 70.097311 -104.105776) (xy 70.108899 -104.159023)
			(xy 70.112791 -104.213378) (xy 70.108907 -104.267733) (xy 70.097327 -104.320982) (xy 70.078286 -104.372041)
			(xy 70.052172 -104.419871) (xy 70.019517 -104.463497) (xy 69.980986 -104.502031) (xy 69.937362 -104.534689)
			(xy 69.889535 -104.560806) (xy 69.838477 -104.579851) (xy 69.785229 -104.591435) (xy 69.730874 -104.595323)
			(xy 69.676519 -104.591435) (xy 69.623271 -104.579851) (xy 69.572213 -104.560806) (xy 69.524386 -104.534689)
			(xy 69.480762 -104.502031) (xy 69.442231 -104.463497) (xy 69.409576 -104.419871) (xy 69.383462 -104.372041)
			(xy 69.364421 -104.320982) (xy 69.352841 -104.267733) (xy 69.348957 -104.213378) (xy 67.953482 -104.213378)
			(xy 67.952193 -104.231411) (xy 67.940613 -104.28466) (xy 67.921572 -104.335719) (xy 67.895458 -104.383549)
			(xy 67.862803 -104.427175) (xy 67.824272 -104.465709) (xy 67.780648 -104.498367) (xy 67.732821 -104.524484)
			(xy 67.681763 -104.543529) (xy 67.628515 -104.555113) (xy 67.57416 -104.559001) (xy 67.519805 -104.555113)
			(xy 67.466557 -104.543529) (xy 67.415499 -104.524484) (xy 67.367672 -104.498367) (xy 67.324048 -104.465709)
			(xy 67.285517 -104.427175) (xy 67.252862 -104.383549) (xy 67.226748 -104.335719) (xy 67.207707 -104.28466)
			(xy 67.196127 -104.231411) (xy 67.192243 -104.177056) (xy 65.805187 -104.177056) (xy 65.801321 -104.231157)
			(xy 65.789741 -104.284406) (xy 65.7707 -104.335465) (xy 65.744586 -104.383295) (xy 65.711931 -104.426921)
			(xy 65.6734 -104.465455) (xy 65.629776 -104.498113) (xy 65.581949 -104.52423) (xy 65.530891 -104.543275)
			(xy 65.477643 -104.554859) (xy 65.423288 -104.558747) (xy 65.368933 -104.554859) (xy 65.315685 -104.543275)
			(xy 65.264627 -104.52423) (xy 65.2168 -104.498113) (xy 65.173176 -104.465455) (xy 65.134645 -104.426921)
			(xy 65.10199 -104.383295) (xy 65.075876 -104.335465) (xy 65.056835 -104.284406) (xy 65.045255 -104.231157)
			(xy 65.041371 -104.176802) (xy 63.541597 -104.176802) (xy 63.551381 -104.221761) (xy 63.555273 -104.276116)
			(xy 63.551389 -104.330471) (xy 63.539809 -104.38372) (xy 63.520768 -104.434779) (xy 63.494654 -104.482609)
			(xy 63.461999 -104.526235) (xy 63.423468 -104.564769) (xy 63.379844 -104.597427) (xy 63.332017 -104.623544)
			(xy 63.280959 -104.642589) (xy 63.227711 -104.654173) (xy 63.173356 -104.658061) (xy 63.119001 -104.654173)
			(xy 63.065753 -104.642589) (xy 63.014695 -104.623544) (xy 62.966868 -104.597427) (xy 62.923244 -104.564769)
			(xy 62.884713 -104.526235) (xy 62.852058 -104.482609) (xy 62.825944 -104.434779) (xy 62.806903 -104.38372)
			(xy 62.795323 -104.330471) (xy 62.791439 -104.276116) (xy 61.274806 -104.276116) (xy 61.273517 -104.294149)
			(xy 61.261937 -104.347398) (xy 61.242896 -104.398457) (xy 61.216782 -104.446287) (xy 61.184127 -104.489913)
			(xy 61.145596 -104.528447) (xy 61.101972 -104.561105) (xy 61.054145 -104.587222) (xy 61.003087 -104.606267)
			(xy 60.949839 -104.617851) (xy 60.895484 -104.621739) (xy 60.841129 -104.617851) (xy 60.787881 -104.606267)
			(xy 60.736823 -104.587222) (xy 60.688996 -104.561105) (xy 60.645372 -104.528447) (xy 60.606841 -104.489913)
			(xy 60.574186 -104.446287) (xy 60.548072 -104.398457) (xy 60.529031 -104.347398) (xy 60.517451 -104.294149)
			(xy 60.513567 -104.239794) (xy 31.885664 -104.239794) (xy 31.546546 -104.578912) (xy 31.291276 -104.578912)
			(xy 31.268111 -104.579445) (xy 31.222555 -104.587883) (xy 31.179284 -104.60444) (xy 31.139731 -104.628565)
			(xy 31.105206 -104.659461) (xy 31.076853 -104.696103) (xy 31.055612 -104.737278) (xy 31.042187 -104.781621)
			(xy 31.037022 -104.827663) (xy 31.040288 -104.873878) (xy 31.051878 -104.918736) (xy 31.071407 -104.960749)
			(xy 31.098227 -104.998527) (xy 31.114492 -105.01503) (xy 31.145529 -105.04584) (xy 31.202373 -105.112309)
			(xy 31.252798 -105.183769) (xy 31.29637 -105.259603) (xy 31.332712 -105.339155) (xy 31.36151 -105.421738)
			(xy 31.382515 -105.506639) (xy 31.395546 -105.593123) (xy 31.40049 -105.680443) (xy 31.398561 -105.733358)
			(xy 34.599874 -105.733358) (xy 34.599874 -105.646458) (xy 34.607892 -105.559929) (xy 34.62386 -105.474509)
			(xy 34.647641 -105.390927) (xy 34.679033 -105.309895) (xy 34.717767 -105.232106) (xy 34.763514 -105.158222)
			(xy 34.815883 -105.088875) (xy 34.874427 -105.024655) (xy 34.938647 -104.966111) (xy 35.007994 -104.913742)
			(xy 35.081878 -104.867995) (xy 35.159667 -104.829261) (xy 35.240699 -104.797869) (xy 35.324281 -104.774088)
			(xy 35.409701 -104.75812) (xy 35.49623 -104.750102) (xy 35.58313 -104.750102) (xy 35.669659 -104.75812)
			(xy 35.755079 -104.774088) (xy 35.838661 -104.797869) (xy 35.919693 -104.829261) (xy 35.997482 -104.867995)
			(xy 36.071366 -104.913742) (xy 36.140713 -104.966111) (xy 36.204933 -105.024655) (xy 36.263477 -105.088875)
			(xy 36.310715 -105.151428) (xy 82.471766 -105.151428) (xy 82.475837 -105.095806) (xy 82.487963 -105.041369)
			(xy 82.507886 -104.989278) (xy 82.535182 -104.940643) (xy 82.569268 -104.8965) (xy 82.609417 -104.857791)
			(xy 82.654775 -104.82534) (xy 82.704375 -104.799839) (xy 82.757159 -104.781832) (xy 82.812002 -104.771702)
			(xy 82.867736 -104.769665) (xy 82.923173 -104.775765) (xy 82.97713 -104.789871) (xy 83.028459 -104.811683)
			(xy 83.076065 -104.840737) (xy 83.118933 -104.876412) (xy 83.15615 -104.917949) (xy 83.186923 -104.964462)
			(xy 83.210595 -105.014959) (xy 83.226663 -105.068366) (xy 83.234783 -105.123542) (xy 83.235292 -105.151428)
			(xy 83.234783 -105.179314) (xy 83.226663 -105.23449) (xy 83.210595 -105.287897) (xy 83.186923 -105.338394)
			(xy 83.15615 -105.384907) (xy 83.118933 -105.426444) (xy 83.076065 -105.462119) (xy 83.028459 -105.491173)
			(xy 82.97713 -105.512985) (xy 82.923173 -105.527091) (xy 82.867736 -105.533191) (xy 82.812002 -105.531154)
			(xy 82.757159 -105.521024) (xy 82.704375 -105.503017) (xy 82.654775 -105.477516) (xy 82.609417 -105.445065)
			(xy 82.569268 -105.406356) (xy 82.535182 -105.362213) (xy 82.507886 -105.313578) (xy 82.487963 -105.261487)
			(xy 82.475837 -105.20705) (xy 82.471766 -105.151428) (xy 36.310715 -105.151428) (xy 36.315846 -105.158222)
			(xy 36.361593 -105.232106) (xy 36.400327 -105.309895) (xy 36.431719 -105.390927) (xy 36.4555 -105.474509)
			(xy 36.471468 -105.559929) (xy 36.479486 -105.646458) (xy 36.479988 -105.689908) (xy 36.479486 -105.733358)
			(xy 36.471468 -105.819887) (xy 36.4555 -105.905307) (xy 36.431719 -105.988889) (xy 36.400327 -106.069921)
			(xy 36.361593 -106.14771) (xy 36.315846 -106.221594) (xy 36.263477 -106.290941) (xy 36.204933 -106.355161)
			(xy 36.140713 -106.413705) (xy 36.071366 -106.466074) (xy 35.997482 -106.511821) (xy 35.919693 -106.550555)
			(xy 35.838661 -106.581947) (xy 35.755079 -106.605728) (xy 35.669659 -106.621696) (xy 35.58313 -106.629714)
			(xy 35.49623 -106.629714) (xy 35.409701 -106.621696) (xy 35.324281 -106.605728) (xy 35.240699 -106.581947)
			(xy 35.159667 -106.550555) (xy 35.081878 -106.511821) (xy 35.007994 -106.466074) (xy 34.938647 -106.413705)
			(xy 34.874427 -106.355161) (xy 34.815883 -106.290941) (xy 34.763514 -106.221594) (xy 34.717767 -106.14771)
			(xy 34.679033 -106.069921) (xy 34.647641 -105.988889) (xy 34.62386 -105.905307) (xy 34.607892 -105.819887)
			(xy 34.599874 -105.733358) (xy 31.398561 -105.733358) (xy 31.397304 -105.767846) (xy 31.386016 -105.854574)
			(xy 31.366723 -105.93988) (xy 31.339592 -106.023026) (xy 31.304858 -106.103293) (xy 31.26282 -106.179988)
			(xy 31.213842 -106.252448) (xy 31.158348 -106.320048) (xy 31.096816 -106.382202) (xy 31.029778 -106.438373)
			(xy 30.957815 -106.488077) (xy 30.881546 -106.530884) (xy 30.801633 -106.566424) (xy 30.718764 -106.59439)
			(xy 30.633657 -106.61454) (xy 30.547046 -106.6267) (xy 30.45968 -106.630765) (xy 30.372314 -106.6267)
			(xy 30.285703 -106.61454) (xy 30.200596 -106.59439) (xy 30.117727 -106.566424) (xy 30.037814 -106.530884)
			(xy 29.961545 -106.488077) (xy 29.889582 -106.438373) (xy 29.822544 -106.382202) (xy 29.761012 -106.320048)
			(xy 29.705518 -106.252448) (xy 29.65654 -106.179988) (xy 29.614502 -106.103293) (xy 29.579768 -106.023026)
			(xy 29.552637 -105.93988) (xy 29.533344 -105.854574) (xy 29.522056 -105.767846) (xy 29.51887 -105.680443)
			(xy 29.523814 -105.593123) (xy 29.536845 -105.506639) (xy 29.55785 -105.421738) (xy 29.586648 -105.339155)
			(xy 29.62299 -105.259603) (xy 29.666562 -105.183769) (xy 29.716987 -105.112309) (xy 29.773831 -105.04584)
			(xy 29.804868 -105.01503) (xy 29.82112 -104.998516) (xy 29.847934 -104.960737) (xy 29.867457 -104.918723)
			(xy 29.879042 -104.873867) (xy 29.882307 -104.827655) (xy 29.877141 -104.781616) (xy 29.863717 -104.737275)
			(xy 29.84248 -104.696102) (xy 29.814132 -104.65946) (xy 29.779612 -104.628562) (xy 29.740065 -104.604432)
			(xy 29.696799 -104.587869) (xy 29.651247 -104.579422) (xy 29.628084 -104.578912) (xy 26.911554 -104.578912)
			(xy 24.339804 -107.150662) (xy 24.330914 -107.182158) (xy 24.323088 -107.207762) (xy 24.301256 -107.256647)
			(xy 24.272804 -107.302001) (xy 24.238291 -107.342931) (xy 24.198395 -107.378635) (xy 24.1539 -107.408411)
			(xy 24.105679 -107.431674) (xy 24.05468 -107.447967) (xy 24.001903 -107.456971) (xy 23.948386 -107.458509)
			(xy 23.89518 -107.45255) (xy 23.869142 -107.446318) (xy 23.847347 -107.441188) (xy 23.802705 -107.437778)
			(xy 23.758155 -107.442237) (xy 23.715075 -107.454426) (xy 23.674794 -107.47397) (xy 23.638556 -107.500263)
			(xy 23.607482 -107.532495) (xy 23.58253 -107.56967) (xy 23.564472 -107.610638) (xy 23.553866 -107.654136)
			(xy 23.551896 -107.676442) (xy 23.551896 -108.081826) (xy 27.690064 -108.081826) (xy 27.690064 -106.569764)
			(xy 27.690565 -106.537819) (xy 27.698573 -106.474433) (xy 27.714462 -106.41255) (xy 27.737981 -106.353146)
			(xy 27.768761 -106.297159) (xy 27.806314 -106.24547) (xy 27.85005 -106.198896) (xy 27.899278 -106.158171)
			(xy 27.953223 -106.123937) (xy 28.011032 -106.096734) (xy 28.071795 -106.076991) (xy 28.134554 -106.065019)
			(xy 28.198318 -106.061008) (xy 28.262082 -106.065019) (xy 28.324841 -106.076991) (xy 28.385604 -106.096734)
			(xy 28.443413 -106.123937) (xy 28.497358 -106.158171) (xy 28.546586 -106.198896) (xy 28.590322 -106.24547)
			(xy 28.627875 -106.297159) (xy 28.658655 -106.353146) (xy 28.682174 -106.41255) (xy 28.698063 -106.474433)
			(xy 28.706071 -106.537819) (xy 28.706572 -106.569764) (xy 28.706572 -107.160483) (xy 47.373784 -107.160483)
			(xy 47.373784 -107.079373) (xy 47.381734 -106.998654) (xy 47.397557 -106.919103) (xy 47.421102 -106.841487)
			(xy 47.452141 -106.766551) (xy 47.490376 -106.695019) (xy 47.535438 -106.627579) (xy 47.586893 -106.56488)
			(xy 47.644246 -106.507527) (xy 47.706945 -106.456072) (xy 47.774385 -106.41101) (xy 47.845917 -106.372775)
			(xy 47.920853 -106.341736) (xy 47.998469 -106.318191) (xy 48.07802 -106.302368) (xy 48.158739 -106.294418)
			(xy 48.239849 -106.294418) (xy 48.320568 -106.302368) (xy 48.400119 -106.318191) (xy 48.477735 -106.341736)
			(xy 48.552671 -106.372775) (xy 48.624203 -106.41101) (xy 48.691643 -106.456072) (xy 48.754342 -106.507527)
			(xy 48.811695 -106.56488) (xy 48.86315 -106.627579) (xy 48.908212 -106.695019) (xy 48.946447 -106.766551)
			(xy 48.977486 -106.841487) (xy 49.001031 -106.919103) (xy 49.016854 -106.998654) (xy 49.024804 -107.079373)
			(xy 49.025302 -107.119928) (xy 49.024804 -107.160483) (xy 50.873904 -107.160483) (xy 50.873904 -107.079373)
			(xy 50.881854 -106.998654) (xy 50.897677 -106.919103) (xy 50.921222 -106.841487) (xy 50.952261 -106.766551)
			(xy 50.990496 -106.695019) (xy 51.035558 -106.627579) (xy 51.087013 -106.56488) (xy 51.144366 -106.507527)
			(xy 51.207065 -106.456072) (xy 51.274505 -106.41101) (xy 51.346037 -106.372775) (xy 51.420973 -106.341736)
			(xy 51.498589 -106.318191) (xy 51.57814 -106.302368) (xy 51.658859 -106.294418) (xy 51.739969 -106.294418)
			(xy 51.820688 -106.302368) (xy 51.900239 -106.318191) (xy 51.977855 -106.341736) (xy 52.052791 -106.372775)
			(xy 52.124323 -106.41101) (xy 52.191763 -106.456072) (xy 52.254462 -106.507527) (xy 52.311815 -106.56488)
			(xy 52.36327 -106.627579) (xy 52.408332 -106.695019) (xy 52.446567 -106.766551) (xy 52.477606 -106.841487)
			(xy 52.497802 -106.908064) (xy 60.513567 -106.908064) (xy 60.517459 -106.853709) (xy 60.529047 -106.800462)
			(xy 60.548095 -106.749406) (xy 60.574216 -106.70158) (xy 60.590176 -106.679492) (xy 60.60378 -106.660485)
			(xy 60.624514 -106.618601) (xy 60.63724 -106.573632) (xy 60.64153 -106.527094) (xy 60.637238 -106.480556)
			(xy 60.624509 -106.435587) (xy 60.603773 -106.393704) (xy 60.590176 -106.374692) (xy 60.574216 -106.352604)
			(xy 60.548095 -106.304778) (xy 60.529047 -106.253722) (xy 60.517459 -106.200475) (xy 60.513567 -106.14612)
			(xy 60.517451 -106.091765) (xy 60.529031 -106.038516) (xy 60.548072 -105.987457) (xy 60.574186 -105.939627)
			(xy 60.606841 -105.896001) (xy 60.645372 -105.857467) (xy 60.688996 -105.824809) (xy 60.736823 -105.798692)
			(xy 60.787881 -105.779647) (xy 60.841129 -105.768063) (xy 60.895484 -105.764175) (xy 60.949839 -105.768063)
			(xy 61.003087 -105.779647) (xy 61.054145 -105.798692) (xy 61.101972 -105.824809) (xy 61.145596 -105.857467)
			(xy 61.184127 -105.896001) (xy 61.216782 -105.939627) (xy 61.242896 -105.987457) (xy 61.261937 -106.038516)
			(xy 61.273517 -106.091765) (xy 61.277401 -106.14612) (xy 61.273509 -106.200475) (xy 61.261921 -106.253722)
			(xy 61.242873 -106.304778) (xy 61.216752 -106.352604) (xy 61.200792 -106.374692) (xy 61.187204 -106.393709)
			(xy 61.166472 -106.435591) (xy 61.153745 -106.480558) (xy 61.149454 -106.527094) (xy 61.153743 -106.573629)
			(xy 61.166467 -106.618597) (xy 61.187198 -106.66048) (xy 61.200792 -106.679492) (xy 61.216752 -106.70158)
			(xy 61.242873 -106.749406) (xy 61.261921 -106.800462) (xy 61.273509 -106.853709) (xy 61.277401 -106.908064)
			(xy 61.274806 -106.944386) (xy 62.791439 -106.944386) (xy 62.795331 -106.890031) (xy 62.806919 -106.836784)
			(xy 62.825967 -106.785728) (xy 62.852088 -106.737902) (xy 62.868048 -106.715814) (xy 62.881628 -106.696792)
			(xy 62.902358 -106.65491) (xy 62.915083 -106.609945) (xy 62.919374 -106.563411) (xy 62.915087 -106.516877)
			(xy 62.902366 -106.471911) (xy 62.88164 -106.430027) (xy 62.868048 -106.411014) (xy 62.852088 -106.388926)
			(xy 62.825967 -106.3411) (xy 62.806919 -106.290044) (xy 62.795331 -106.236797) (xy 62.791439 -106.182442)
			(xy 62.795323 -106.128087) (xy 62.806903 -106.074838) (xy 62.825944 -106.023779) (xy 62.852058 -105.975949)
			(xy 62.884713 -105.932323) (xy 62.923244 -105.893789) (xy 62.966868 -105.861131) (xy 63.014695 -105.835014)
			(xy 63.065753 -105.815969) (xy 63.119001 -105.804385) (xy 63.173356 -105.800497) (xy 63.227711 -105.804385)
			(xy 63.280959 -105.815969) (xy 63.332017 -105.835014) (xy 63.379844 -105.861131) (xy 63.423468 -105.893789)
			(xy 63.461999 -105.932323) (xy 63.494654 -105.975949) (xy 63.520768 -106.023779) (xy 63.539809 -106.074838)
			(xy 63.551389 -106.128087) (xy 63.555273 -106.182442) (xy 63.551381 -106.236797) (xy 63.539793 -106.290044)
			(xy 63.520745 -106.3411) (xy 63.494624 -106.388926) (xy 63.478664 -106.411014) (xy 63.465057 -106.430018)
			(xy 63.444329 -106.471904) (xy 63.431606 -106.516874) (xy 63.427319 -106.563411) (xy 63.43161 -106.609948)
			(xy 63.444337 -106.654917) (xy 63.465069 -106.696801) (xy 63.478664 -106.715814) (xy 63.494624 -106.737902)
			(xy 63.520745 -106.785728) (xy 63.539793 -106.836784) (xy 63.541597 -106.845072) (xy 65.041371 -106.845072)
			(xy 65.045263 -106.790717) (xy 65.056851 -106.73747) (xy 65.075899 -106.686414) (xy 65.10202 -106.638588)
			(xy 65.11798 -106.6165) (xy 65.131577 -106.597488) (xy 65.152311 -106.555605) (xy 65.165038 -106.510637)
			(xy 65.169328 -106.4641) (xy 65.165038 -106.417563) (xy 65.152311 -106.372595) (xy 65.131577 -106.330712)
			(xy 65.11798 -106.3117) (xy 65.10202 -106.289612) (xy 65.075899 -106.241786) (xy 65.056851 -106.19073)
			(xy 65.045263 -106.137483) (xy 65.041371 -106.083128) (xy 65.045255 -106.028773) (xy 65.056835 -105.975524)
			(xy 65.075876 -105.924465) (xy 65.10199 -105.876635) (xy 65.134645 -105.833009) (xy 65.173176 -105.794475)
			(xy 65.2168 -105.761817) (xy 65.264627 -105.7357) (xy 65.315685 -105.716655) (xy 65.368933 -105.705071)
			(xy 65.423288 -105.701183) (xy 65.477643 -105.705071) (xy 65.530891 -105.716655) (xy 65.581949 -105.7357)
			(xy 65.629776 -105.761817) (xy 65.6734 -105.794475) (xy 65.711931 -105.833009) (xy 65.744586 -105.876635)
			(xy 65.7707 -105.924465) (xy 65.789741 -105.975524) (xy 65.801321 -106.028773) (xy 65.805205 -106.083128)
			(xy 65.801313 -106.137483) (xy 65.789725 -106.19073) (xy 65.770677 -106.241786) (xy 65.744556 -106.289612)
			(xy 65.728596 -106.3117) (xy 65.715001 -106.330712) (xy 65.694268 -106.372596) (xy 65.681543 -106.417563)
			(xy 65.677253 -106.4641) (xy 65.681543 -106.510637) (xy 65.694268 -106.555604) (xy 65.715001 -106.597488)
			(xy 65.728596 -106.6165) (xy 65.744556 -106.638588) (xy 65.770677 -106.686414) (xy 65.789725 -106.73747)
			(xy 65.801313 -106.790717) (xy 65.805205 -106.845072) (xy 65.805187 -106.845326) (xy 67.192243 -106.845326)
			(xy 67.196135 -106.790971) (xy 67.207723 -106.737724) (xy 67.226771 -106.686668) (xy 67.252892 -106.638842)
			(xy 67.268852 -106.616754) (xy 67.282493 -106.597772) (xy 67.303225 -106.555882) (xy 67.315948 -106.510906)
			(xy 67.320233 -106.464363) (xy 67.315935 -106.417821) (xy 67.303199 -106.37285) (xy 67.282454 -106.330965)
			(xy 67.268852 -106.311954) (xy 67.252892 -106.289866) (xy 67.226771 -106.24204) (xy 67.207723 -106.190984)
			(xy 67.196135 -106.137737) (xy 67.192243 -106.083382) (xy 67.196127 -106.029027) (xy 67.207707 -105.975778)
			(xy 67.226748 -105.924719) (xy 67.252862 -105.876889) (xy 67.285517 -105.833263) (xy 67.324048 -105.794729)
			(xy 67.367672 -105.762071) (xy 67.415499 -105.735954) (xy 67.466557 -105.716909) (xy 67.519805 -105.705325)
			(xy 67.57416 -105.701437) (xy 67.628515 -105.705325) (xy 67.681763 -105.716909) (xy 67.732821 -105.735954)
			(xy 67.780648 -105.762071) (xy 67.824272 -105.794729) (xy 67.862803 -105.833263) (xy 67.895458 -105.876889)
			(xy 67.921572 -105.924719) (xy 67.940613 -105.975778) (xy 67.952193 -106.029027) (xy 67.956077 -106.083382)
			(xy 67.952185 -106.137737) (xy 67.940597 -106.190984) (xy 67.921549 -106.24204) (xy 67.895428 -106.289866)
			(xy 67.879468 -106.311954) (xy 67.865917 -106.330996) (xy 67.845183 -106.372872) (xy 67.832454 -106.417833)
			(xy 67.828158 -106.464363) (xy 67.83244 -106.510895) (xy 67.845157 -106.555859) (xy 67.865878 -106.597741)
			(xy 67.879468 -106.616754) (xy 67.895428 -106.638842) (xy 67.921549 -106.686668) (xy 67.940597 -106.737724)
			(xy 67.952185 -106.790971) (xy 67.956077 -106.845326) (xy 67.953482 -106.881648) (xy 69.348957 -106.881648)
			(xy 69.352849 -106.827293) (xy 69.364437 -106.774046) (xy 69.383485 -106.72299) (xy 69.409606 -106.675164)
			(xy 69.425566 -106.653076) (xy 69.439186 -106.63408) (xy 69.459919 -106.592193) (xy 69.472644 -106.547221)
			(xy 69.476931 -106.500681) (xy 69.472637 -106.454141) (xy 69.459905 -106.409171) (xy 69.439165 -106.367287)
			(xy 69.425566 -106.348276) (xy 69.409606 -106.326188) (xy 69.383485 -106.278362) (xy 69.364437 -106.227306)
			(xy 69.352849 -106.174059) (xy 69.348957 -106.119704) (xy 69.352841 -106.065349) (xy 69.364421 -106.0121)
			(xy 69.383462 -105.961041) (xy 69.409576 -105.913211) (xy 69.442231 -105.869585) (xy 69.480762 -105.831051)
			(xy 69.524386 -105.798393) (xy 69.572213 -105.772276) (xy 69.623271 -105.753231) (xy 69.676519 -105.741647)
			(xy 69.730874 -105.737759) (xy 69.785229 -105.741647) (xy 69.838477 -105.753231) (xy 69.889535 -105.772276)
			(xy 69.937362 -105.798393) (xy 69.980986 -105.831051) (xy 70.019517 -105.869585) (xy 70.052172 -105.913211)
			(xy 70.078286 -105.961041) (xy 70.097327 -106.0121) (xy 70.108907 -106.065349) (xy 70.112791 -106.119704)
			(xy 70.108899 -106.174059) (xy 70.097311 -106.227306) (xy 70.088284 -106.251502) (xy 81.739484 -106.251502)
			(xy 81.743555 -106.19588) (xy 81.755681 -106.141443) (xy 81.775604 -106.089352) (xy 81.8029 -106.040717)
			(xy 81.836986 -105.996574) (xy 81.877135 -105.957865) (xy 81.922493 -105.925414) (xy 81.972093 -105.899913)
			(xy 82.024877 -105.881906) (xy 82.07972 -105.871776) (xy 82.135454 -105.869739) (xy 82.190891 -105.875839)
			(xy 82.244848 -105.889945) (xy 82.296177 -105.911757) (xy 82.343783 -105.940811) (xy 82.386651 -105.976486)
			(xy 82.423868 -106.018023) (xy 82.454641 -106.064536) (xy 82.478313 -106.115033) (xy 82.494381 -106.16844)
			(xy 82.502501 -106.223616) (xy 82.50301 -106.251502) (xy 82.502501 -106.279388) (xy 82.494381 -106.334564)
			(xy 82.478313 -106.387971) (xy 82.454641 -106.438468) (xy 82.423868 -106.484981) (xy 82.386651 -106.526518)
			(xy 82.343783 -106.562193) (xy 82.296177 -106.591247) (xy 82.244848 -106.613059) (xy 82.190891 -106.627165)
			(xy 82.135454 -106.633265) (xy 82.07972 -106.631228) (xy 82.024877 -106.621098) (xy 81.972093 -106.603091)
			(xy 81.922493 -106.57759) (xy 81.877135 -106.545139) (xy 81.836986 -106.50643) (xy 81.8029 -106.462287)
			(xy 81.775604 -106.413652) (xy 81.755681 -106.361561) (xy 81.743555 -106.307124) (xy 81.739484 -106.251502)
			(xy 70.088284 -106.251502) (xy 70.078263 -106.278362) (xy 70.052142 -106.326188) (xy 70.036182 -106.348276)
			(xy 70.02261 -106.367304) (xy 70.001877 -106.409183) (xy 69.989149 -106.454148) (xy 69.984856 -106.500681)
			(xy 69.989142 -106.547215) (xy 70.001863 -106.592181) (xy 70.02259 -106.634064) (xy 70.036182 -106.653076)
			(xy 70.052142 -106.675164) (xy 70.078263 -106.72299) (xy 70.097311 -106.774046) (xy 70.108899 -106.827293)
			(xy 70.112791 -106.881648) (xy 70.108907 -106.936003) (xy 70.097327 -106.989252) (xy 70.078286 -107.040311)
			(xy 70.052172 -107.088141) (xy 70.019517 -107.131767) (xy 69.980986 -107.170301) (xy 69.937362 -107.202959)
			(xy 69.889535 -107.229076) (xy 69.838477 -107.248121) (xy 69.785229 -107.259705) (xy 69.730874 -107.263593)
			(xy 69.676519 -107.259705) (xy 69.623271 -107.248121) (xy 69.572213 -107.229076) (xy 69.524386 -107.202959)
			(xy 69.480762 -107.170301) (xy 69.442231 -107.131767) (xy 69.409576 -107.088141) (xy 69.383462 -107.040311)
			(xy 69.364421 -106.989252) (xy 69.352841 -106.936003) (xy 69.348957 -106.881648) (xy 67.953482 -106.881648)
			(xy 67.952193 -106.899681) (xy 67.940613 -106.95293) (xy 67.921572 -107.003989) (xy 67.895458 -107.051819)
			(xy 67.862803 -107.095445) (xy 67.824272 -107.133979) (xy 67.780648 -107.166637) (xy 67.732821 -107.192754)
			(xy 67.681763 -107.211799) (xy 67.628515 -107.223383) (xy 67.57416 -107.227271) (xy 67.519805 -107.223383)
			(xy 67.466557 -107.211799) (xy 67.415499 -107.192754) (xy 67.367672 -107.166637) (xy 67.324048 -107.133979)
			(xy 67.285517 -107.095445) (xy 67.252862 -107.051819) (xy 67.226748 -107.003989) (xy 67.207707 -106.95293)
			(xy 67.196127 -106.899681) (xy 67.192243 -106.845326) (xy 65.805187 -106.845326) (xy 65.801321 -106.899427)
			(xy 65.789741 -106.952676) (xy 65.7707 -107.003735) (xy 65.744586 -107.051565) (xy 65.711931 -107.095191)
			(xy 65.6734 -107.133725) (xy 65.629776 -107.166383) (xy 65.581949 -107.1925) (xy 65.530891 -107.211545)
			(xy 65.477643 -107.223129) (xy 65.423288 -107.227017) (xy 65.368933 -107.223129) (xy 65.315685 -107.211545)
			(xy 65.264627 -107.1925) (xy 65.2168 -107.166383) (xy 65.173176 -107.133725) (xy 65.134645 -107.095191)
			(xy 65.10199 -107.051565) (xy 65.075876 -107.003735) (xy 65.056835 -106.952676) (xy 65.045255 -106.899427)
			(xy 65.041371 -106.845072) (xy 63.541597 -106.845072) (xy 63.551381 -106.890031) (xy 63.555273 -106.944386)
			(xy 63.551389 -106.998741) (xy 63.539809 -107.05199) (xy 63.520768 -107.103049) (xy 63.494654 -107.150879)
			(xy 63.461999 -107.194505) (xy 63.423468 -107.233039) (xy 63.379844 -107.265697) (xy 63.332017 -107.291814)
			(xy 63.280959 -107.310859) (xy 63.227711 -107.322443) (xy 63.173356 -107.326331) (xy 63.119001 -107.322443)
			(xy 63.065753 -107.310859) (xy 63.014695 -107.291814) (xy 62.966868 -107.265697) (xy 62.923244 -107.233039)
			(xy 62.884713 -107.194505) (xy 62.852058 -107.150879) (xy 62.825944 -107.103049) (xy 62.806903 -107.05199)
			(xy 62.795323 -106.998741) (xy 62.791439 -106.944386) (xy 61.274806 -106.944386) (xy 61.273517 -106.962419)
			(xy 61.261937 -107.015668) (xy 61.242896 -107.066727) (xy 61.216782 -107.114557) (xy 61.184127 -107.158183)
			(xy 61.145596 -107.196717) (xy 61.101972 -107.229375) (xy 61.054145 -107.255492) (xy 61.003087 -107.274537)
			(xy 60.949839 -107.286121) (xy 60.895484 -107.290009) (xy 60.841129 -107.286121) (xy 60.787881 -107.274537)
			(xy 60.736823 -107.255492) (xy 60.688996 -107.229375) (xy 60.645372 -107.196717) (xy 60.606841 -107.158183)
			(xy 60.574186 -107.114557) (xy 60.548072 -107.066727) (xy 60.529031 -107.015668) (xy 60.517451 -106.962419)
			(xy 60.513567 -106.908064) (xy 52.497802 -106.908064) (xy 52.501151 -106.919103) (xy 52.516974 -106.998654)
			(xy 52.524924 -107.079373) (xy 52.525422 -107.119928) (xy 52.524924 -107.160483) (xy 52.516974 -107.241202)
			(xy 52.501151 -107.320753) (xy 52.477606 -107.398369) (xy 52.446567 -107.473305) (xy 52.432752 -107.49915)
			(xy 81.146902 -107.49915) (xy 81.150973 -107.443528) (xy 81.163099 -107.389091) (xy 81.183022 -107.337)
			(xy 81.210318 -107.288365) (xy 81.244404 -107.244222) (xy 81.284553 -107.205513) (xy 81.329911 -107.173062)
			(xy 81.379511 -107.147561) (xy 81.432295 -107.129554) (xy 81.487138 -107.119424) (xy 81.542872 -107.117387)
			(xy 81.598309 -107.123487) (xy 81.652266 -107.137593) (xy 81.703595 -107.159405) (xy 81.751201 -107.188459)
			(xy 81.794069 -107.224134) (xy 81.831286 -107.265671) (xy 81.862059 -107.312184) (xy 81.885731 -107.362681)
			(xy 81.901799 -107.416088) (xy 81.909919 -107.471264) (xy 81.910428 -107.49915) (xy 81.909919 -107.527036)
			(xy 81.901799 -107.582212) (xy 81.885731 -107.635619) (xy 81.862059 -107.686116) (xy 81.831286 -107.732629)
			(xy 81.794069 -107.774166) (xy 81.751201 -107.809841) (xy 81.703595 -107.838895) (xy 81.652266 -107.860707)
			(xy 81.598309 -107.874813) (xy 81.542872 -107.880913) (xy 81.487138 -107.878876) (xy 81.432295 -107.868746)
			(xy 81.379511 -107.850739) (xy 81.329911 -107.825238) (xy 81.284553 -107.792787) (xy 81.244404 -107.754078)
			(xy 81.210318 -107.709935) (xy 81.183022 -107.6613) (xy 81.163099 -107.609209) (xy 81.150973 -107.554772)
			(xy 81.146902 -107.49915) (xy 52.432752 -107.49915) (xy 52.408332 -107.544837) (xy 52.36327 -107.612277)
			(xy 52.311815 -107.674976) (xy 52.254462 -107.732329) (xy 52.191763 -107.783784) (xy 52.124323 -107.828846)
			(xy 52.052791 -107.867081) (xy 51.977855 -107.89812) (xy 51.900239 -107.921665) (xy 51.820688 -107.937488)
			(xy 51.739969 -107.945438) (xy 51.658859 -107.945438) (xy 51.57814 -107.937488) (xy 51.498589 -107.921665)
			(xy 51.420973 -107.89812) (xy 51.346037 -107.867081) (xy 51.274505 -107.828846) (xy 51.207065 -107.783784)
			(xy 51.144366 -107.732329) (xy 51.087013 -107.674976) (xy 51.035558 -107.612277) (xy 50.990496 -107.544837)
			(xy 50.952261 -107.473305) (xy 50.921222 -107.398369) (xy 50.897677 -107.320753) (xy 50.881854 -107.241202)
			(xy 50.873904 -107.160483) (xy 49.024804 -107.160483) (xy 49.016854 -107.241202) (xy 49.001031 -107.320753)
			(xy 48.977486 -107.398369) (xy 48.946447 -107.473305) (xy 48.908212 -107.544837) (xy 48.86315 -107.612277)
			(xy 48.811695 -107.674976) (xy 48.754342 -107.732329) (xy 48.691643 -107.783784) (xy 48.624203 -107.828846)
			(xy 48.552671 -107.867081) (xy 48.477735 -107.89812) (xy 48.400119 -107.921665) (xy 48.320568 -107.937488)
			(xy 48.239849 -107.945438) (xy 48.158739 -107.945438) (xy 48.07802 -107.937488) (xy 47.998469 -107.921665)
			(xy 47.920853 -107.89812) (xy 47.845917 -107.867081) (xy 47.774385 -107.828846) (xy 47.706945 -107.783784)
			(xy 47.644246 -107.732329) (xy 47.586893 -107.674976) (xy 47.535438 -107.612277) (xy 47.490376 -107.544837)
			(xy 47.452141 -107.473305) (xy 47.421102 -107.398369) (xy 47.397557 -107.320753) (xy 47.381734 -107.241202)
			(xy 47.373784 -107.160483) (xy 28.706572 -107.160483) (xy 28.706572 -107.660694) (xy 29.130752 -108.084874)
			(xy 29.14672 -108.10005) (xy 29.182804 -108.125308) (xy 29.222702 -108.143968) (xy 29.265219 -108.155471)
			(xy 29.309082 -108.159474) (xy 29.352979 -108.155857) (xy 29.395595 -108.144727) (xy 29.435655 -108.126418)
			(xy 29.47196 -108.101478) (xy 29.503422 -108.070654) (xy 29.529101 -108.034868) (xy 29.548227 -107.995192)
			(xy 29.554678 -107.97413) (xy 29.566981 -107.932502) (xy 29.598211 -107.851504) (xy 29.636773 -107.773729)
			(xy 29.68234 -107.699839) (xy 29.734523 -107.630463) (xy 29.792878 -107.566193) (xy 29.856908 -107.507574)
			(xy 29.926068 -107.455107) (xy 29.99977 -107.409237) (xy 30.077386 -107.370355) (xy 30.158255 -107.338792)
			(xy 30.241689 -107.314817) (xy 30.326978 -107.298635) (xy 30.413395 -107.290382) (xy 30.500204 -107.290128)
			(xy 30.586668 -107.297877) (xy 30.672049 -107.313563) (xy 30.755622 -107.33705) (xy 30.836674 -107.368141)
			(xy 30.914515 -107.406569) (xy 30.988483 -107.452009) (xy 31.057948 -107.504072) (xy 31.122319 -107.562316)
			(xy 31.181048 -107.626246) (xy 31.233634 -107.695316) (xy 31.279631 -107.768938) (xy 31.318646 -107.846487)
			(xy 31.350348 -107.927302) (xy 31.374466 -108.010695) (xy 31.390796 -108.095955) (xy 31.399198 -108.182358)
			(xy 31.3996 -108.269167) (xy 31.392 -108.355644) (xy 31.376462 -108.441052) (xy 31.353118 -108.524665)
			(xy 31.322167 -108.60577) (xy 31.303468 -108.644944) (xy 31.293567 -108.666196) (xy 31.28091 -108.711334)
			(xy 31.276745 -108.758027) (xy 31.281214 -108.804692) (xy 31.294163 -108.849747) (xy 31.315155 -108.891663)
			(xy 31.343478 -108.929019) (xy 31.37817 -108.960547) (xy 31.418056 -108.985179) (xy 31.461783 -109.00208)
			(xy 31.507867 -109.010675) (xy 31.531306 -109.011212) (xy 34.468054 -109.011212) (xy 34.491492 -109.010698)
			(xy 34.537571 -109.002093) (xy 34.581292 -108.985186) (xy 34.621172 -108.96055) (xy 34.655859 -108.929019)
			(xy 34.684177 -108.891663) (xy 34.705166 -108.849749) (xy 34.718114 -108.804696) (xy 34.722582 -108.758034)
			(xy 34.71842 -108.711343) (xy 34.705767 -108.666207) (xy 34.695892 -108.644944) (xy 34.677206 -108.605828)
			(xy 34.646265 -108.524843) (xy 34.62291 -108.441355) (xy 34.607339 -108.35607) (xy 34.599684 -108.269715)
			(xy 34.60001 -108.183021) (xy 34.608315 -108.096726) (xy 34.624529 -108.011561) (xy 34.648512 -107.928251)
			(xy 34.680062 -107.847501) (xy 34.718911 -107.769999) (xy 34.76473 -107.696401) (xy 34.817128 -107.627334)
			(xy 34.875661 -107.563383) (xy 34.939832 -107.505091) (xy 35.009096 -107.452954) (xy 35.082866 -107.407413)
			(xy 35.160514 -107.368856) (xy 35.241381 -107.33761) (xy 35.324782 -107.313941) (xy 35.410007 -107.298048)
			(xy 35.496333 -107.290068) (xy 35.583027 -107.290068) (xy 35.669353 -107.298048) (xy 35.754578 -107.313941)
			(xy 35.837979 -107.33761) (xy 35.918846 -107.368856) (xy 35.996494 -107.407413) (xy 36.070264 -107.452954)
			(xy 36.139528 -107.505091) (xy 36.203699 -107.563383) (xy 36.262232 -107.627334) (xy 36.31463 -107.696401)
			(xy 36.360449 -107.769999) (xy 36.399298 -107.847501) (xy 36.430848 -107.928251) (xy 36.454831 -108.011561)
			(xy 36.471045 -108.096726) (xy 36.47935 -108.183021) (xy 36.479676 -108.269715) (xy 36.472021 -108.35607)
			(xy 36.45645 -108.441355) (xy 36.433095 -108.524843) (xy 36.402154 -108.605828) (xy 36.383468 -108.644944)
			(xy 36.373567 -108.666196) (xy 36.36091 -108.711334) (xy 36.356745 -108.758027) (xy 36.361214 -108.804692)
			(xy 36.374163 -108.849747) (xy 36.395155 -108.891663) (xy 36.423478 -108.929019) (xy 36.45817 -108.960547)
			(xy 36.498056 -108.985179) (xy 36.541783 -109.00208) (xy 36.587867 -109.010675) (xy 36.611306 -109.011212)
			(xy 37.41674 -109.011212) (xy 38.018212 -108.40974) (xy 56.473598 -108.40974) (xy 56.973724 -108.909866)
			(xy 86.877404 -108.909866) (xy 86.881424 -108.719215) (xy 86.893478 -108.528902) (xy 86.913544 -108.339267)
			(xy 86.941587 -108.150646) (xy 86.977556 -107.963376) (xy 87.021388 -107.777788) (xy 87.073005 -107.594213)
			(xy 87.132315 -107.412977) (xy 87.199213 -107.234402) (xy 87.273579 -107.058807) (xy 87.355281 -106.886502)
			(xy 87.444175 -106.717795) (xy 87.540101 -106.552985) (xy 87.64289 -106.392366) (xy 87.752359 -106.236223)
			(xy 87.868313 -106.084834) (xy 87.990547 -105.938467) (xy 88.118841 -105.797383) (xy 88.252969 -105.661834)
			(xy 88.392693 -105.532059) (xy 88.537763 -105.408289) (xy 88.687921 -105.290746) (xy 88.842902 -105.179637)
			(xy 89.002429 -105.07516) (xy 89.166218 -104.977501) (xy 89.333978 -104.886834) (xy 89.505412 -104.80332)
			(xy 89.680214 -104.727107) (xy 89.858073 -104.658331) (xy 90.038674 -104.597113) (xy 90.221694 -104.543564)
			(xy 90.40681 -104.497778) (xy 90.593691 -104.459836) (xy 90.782006 -104.429807) (xy 90.971419 -104.407742)
			(xy 91.161593 -104.393683) (xy 91.352192 -104.387653) (xy 91.542875 -104.389663) (xy 91.733304 -104.39971)
			(xy 91.92314 -104.417776) (xy 92.112046 -104.443829) (xy 92.299685 -104.477822) (xy 92.485725 -104.519695)
			(xy 92.669834 -104.569374) (xy 92.851685 -104.62677) (xy 93.030955 -104.691781) (xy 93.207325 -104.764292)
			(xy 93.380481 -104.844173) (xy 93.550116 -104.931283) (xy 93.715928 -105.025467) (xy 93.877622 -105.126558)
			(xy 94.03491 -105.234374) (xy 94.187513 -105.348726) (xy 94.335161 -105.469409) (xy 94.477589 -105.59621)
			(xy 94.614545 -105.728901) (xy 94.745786 -105.867249) (xy 94.871078 -106.011006) (xy 94.990198 -106.159917)
			(xy 95.102934 -106.313718) (xy 95.209087 -106.472134) (xy 95.308467 -106.634885) (xy 95.400897 -106.80168)
			(xy 95.486214 -106.972224) (xy 95.564266 -107.146212) (xy 95.634913 -107.323337) (xy 95.698031 -107.503282)
			(xy 95.753507 -107.685728) (xy 95.801242 -107.870351) (xy 95.841152 -108.056821) (xy 95.873165 -108.244809)
			(xy 95.897225 -108.433979) (xy 95.913288 -108.623995) (xy 95.921327 -108.814519) (xy 95.92183 -108.909866)
			(xy 95.921327 -109.005213) (xy 95.913288 -109.195737) (xy 95.897225 -109.385753) (xy 95.873165 -109.574923)
			(xy 95.841152 -109.762911) (xy 95.801242 -109.949381) (xy 95.753507 -110.134004) (xy 95.698031 -110.31645)
			(xy 95.634913 -110.496395) (xy 95.564266 -110.67352) (xy 95.486214 -110.847508) (xy 95.400897 -111.018052)
			(xy 95.308467 -111.184847) (xy 95.209087 -111.347598) (xy 95.102934 -111.506014) (xy 94.990198 -111.659815)
			(xy 94.871078 -111.808726) (xy 94.745786 -111.952483) (xy 94.614545 -112.090831) (xy 94.477589 -112.223522)
			(xy 94.335161 -112.350323) (xy 94.187513 -112.471006) (xy 94.03491 -112.585358) (xy 93.877622 -112.693174)
			(xy 93.715928 -112.794265) (xy 93.550116 -112.888449) (xy 93.380481 -112.975559) (xy 93.207325 -113.05544)
			(xy 93.030955 -113.127951) (xy 92.851685 -113.192962) (xy 92.669834 -113.250358) (xy 92.485725 -113.300037)
			(xy 92.299685 -113.34191) (xy 92.112046 -113.375903) (xy 91.92314 -113.401956) (xy 91.733304 -113.420022)
			(xy 91.542875 -113.430069) (xy 91.352192 -113.432079) (xy 91.161593 -113.426049) (xy 90.971419 -113.41199)
			(xy 90.782006 -113.389925) (xy 90.593691 -113.359896) (xy 90.40681 -113.321954) (xy 90.221694 -113.276168)
			(xy 90.038674 -113.222619) (xy 89.858073 -113.161401) (xy 89.680214 -113.092625) (xy 89.505412 -113.016412)
			(xy 89.333978 -112.932898) (xy 89.166218 -112.842231) (xy 89.002429 -112.744572) (xy 88.842902 -112.640095)
			(xy 88.687921 -112.528986) (xy 88.537763 -112.411443) (xy 88.392693 -112.287673) (xy 88.252969 -112.157898)
			(xy 88.118841 -112.022349) (xy 87.990547 -111.881265) (xy 87.868313 -111.734898) (xy 87.752359 -111.583509)
			(xy 87.64289 -111.427366) (xy 87.540101 -111.266747) (xy 87.444175 -111.101937) (xy 87.355281 -110.93323)
			(xy 87.273579 -110.760925) (xy 87.199213 -110.58533) (xy 87.132315 -110.406755) (xy 87.073005 -110.225519)
			(xy 87.021388 -110.041944) (xy 86.977556 -109.856356) (xy 86.941587 -109.669086) (xy 86.913544 -109.480465)
			(xy 86.893478 -109.29083) (xy 86.881424 -109.100517) (xy 86.877404 -108.909866) (xy 56.973724 -108.909866)
			(xy 65.98285 -117.918992) (xy 66.483484 -117.918992) (xy 67.133978 -117.268498) (xy 67.156922 -117.246263)
			(xy 67.207408 -117.207102) (xy 67.262404 -117.174577) (xy 67.321043 -117.149202) (xy 67.3824 -117.131376)
			(xy 67.445507 -117.121381) (xy 67.509369 -117.119374) (xy 67.57298 -117.125387) (xy 67.635334 -117.139325)
			(xy 67.695451 -117.160968) (xy 67.752381 -117.189975) (xy 67.805226 -117.225889) (xy 67.853153 -117.268143)
			(xy 67.895407 -117.31607) (xy 67.931321 -117.368915) (xy 67.960328 -117.425845) (xy 67.981971 -117.485962)
			(xy 67.995909 -117.548316) (xy 68.001922 -117.611927) (xy 67.999915 -117.675789) (xy 67.98992 -117.738896)
			(xy 67.972094 -117.800253) (xy 67.946719 -117.858892) (xy 67.914194 -117.913888) (xy 67.875033 -117.964374)
			(xy 67.852798 -117.987318) (xy 66.960496 -118.87962) (xy 66.949114 -118.891806) (xy 66.932508 -118.920707)
			(xy 66.923937 -118.952919) (xy 66.923986 -118.986251) (xy 66.93265 -119.018438) (xy 66.949342 -119.04729)
			(xy 66.96075 -119.059452) (xy 67.856608 -119.95531) (xy 67.878843 -119.978254) (xy 67.918004 -120.02874)
			(xy 67.950529 -120.083736) (xy 67.975904 -120.142375) (xy 67.99373 -120.203732) (xy 68.003725 -120.266839)
			(xy 68.005732 -120.330701) (xy 67.999719 -120.394312) (xy 67.985781 -120.456666) (xy 67.964138 -120.516783)
			(xy 67.935131 -120.573713) (xy 67.899217 -120.626558) (xy 67.856963 -120.674485) (xy 67.809036 -120.716739)
			(xy 67.756191 -120.752653) (xy 67.699261 -120.78166) (xy 67.639144 -120.803303) (xy 67.57679 -120.817241)
			(xy 67.513179 -120.823254) (xy 67.449317 -120.821247) (xy 67.38621 -120.811252) (xy 67.324853 -120.793426)
			(xy 67.266214 -120.768051) (xy 67.211218 -120.735526) (xy 67.160732 -120.696365) (xy 67.137788 -120.67413)
			(xy 66.431922 -119.968264) (xy 65.100708 -119.968264) (xy 55.614824 -110.48238) (xy 41.65981 -110.48238)
			(xy 41.636766 -110.482875) (xy 41.591425 -110.491133) (xy 41.548318 -110.507434) (xy 41.508858 -110.531244)
			(xy 41.47434 -110.561781) (xy 41.445897 -110.598044) (xy 41.424461 -110.638843) (xy 41.410737 -110.682838)
			(xy 41.405174 -110.728588) (xy 41.406064 -110.75162) (xy 41.407196 -110.778645) (xy 41.402742 -110.83255)
			(xy 41.390717 -110.885285) (xy 41.371362 -110.935792) (xy 41.345067 -110.983059) (xy 41.312357 -111.026136)
			(xy 41.27389 -111.064161) (xy 41.230437 -111.09637) (xy 41.182869 -111.122117) (xy 41.132142 -111.140885)
			(xy 41.079271 -111.152299) (xy 41.025318 -111.15613) (xy 40.971365 -111.152299) (xy 40.918494 -111.140885)
			(xy 40.867767 -111.122117) (xy 40.820199 -111.09637) (xy 40.776746 -111.064161) (xy 40.738279 -111.026136)
			(xy 40.705569 -110.983059) (xy 40.679274 -110.935792) (xy 40.659919 -110.885285) (xy 40.647894 -110.83255)
			(xy 40.64344 -110.778645) (xy 40.644572 -110.75162) (xy 40.645436 -110.728597) (xy 40.639816 -110.682874)
			(xy 40.626057 -110.638909) (xy 40.604609 -110.598139) (xy 40.576171 -110.561896) (xy 40.541674 -110.531364)
			(xy 40.502245 -110.507541) (xy 40.459171 -110.491205) (xy 40.41386 -110.482889) (xy 40.390826 -110.48238)
			(xy 40.336978 -110.48238) (xy 40.305735 -110.481831) (xy 40.243717 -110.474191) (xy 40.183104 -110.459005)
			(xy 40.124811 -110.436502) (xy 40.069716 -110.407022) (xy 40.018651 -110.371009) (xy 39.972387 -110.329007)
			(xy 39.931622 -110.281649) (xy 39.896971 -110.22965) (xy 39.868957 -110.173796) (xy 39.848003 -110.114928)
			(xy 39.834424 -110.053935) (xy 39.828426 -109.991737) (xy 39.830099 -109.929273) (xy 39.839418 -109.867486)
			(xy 39.856243 -109.807307) (xy 39.86784 -109.778292) (xy 39.876132 -109.757128) (xy 39.885904 -109.71274)
			(xy 39.887629 -109.667322) (xy 39.881254 -109.62232) (xy 39.866981 -109.579169) (xy 39.845265 -109.539242)
			(xy 39.816797 -109.503811) (xy 39.782484 -109.474005) (xy 39.743419 -109.450774) (xy 39.700847 -109.434856)
			(xy 39.656123 -109.426759) (xy 39.633398 -109.426248) (xy 38.439344 -109.426248) (xy 37.837872 -110.02772)
			(xy 36.629594 -110.02772) (xy 36.606581 -110.028227) (xy 36.561311 -110.036535) (xy 36.518278 -110.052859)
			(xy 36.478888 -110.076667) (xy 36.444429 -110.107179) (xy 36.416029 -110.143398) (xy 36.394615 -110.184139)
			(xy 36.380889 -110.228071) (xy 36.375299 -110.273756) (xy 36.378028 -110.319701) (xy 36.388986 -110.364403)
			(xy 36.397946 -110.385606) (xy 36.415302 -110.42557) (xy 36.443401 -110.50805) (xy 36.46375 -110.592775)
			(xy 36.476174 -110.679019) (xy 36.480566 -110.766043) (xy 36.476889 -110.8531) (xy 36.465174 -110.939443)
			(xy 36.445522 -111.024333) (xy 36.418101 -111.107041) (xy 36.383147 -111.186857) (xy 36.340958 -111.263097)
			(xy 36.291898 -111.335108) (xy 36.236386 -111.402271) (xy 36.174899 -111.464011) (xy 36.107965 -111.519798)
			(xy 36.036156 -111.569154) (xy 36.027354 -111.574072) (xy 40.008808 -111.574072) (xy 40.012879 -111.51845)
			(xy 40.025005 -111.464013) (xy 40.044928 -111.411922) (xy 40.072224 -111.363287) (xy 40.10631 -111.319144)
			(xy 40.146459 -111.280435) (xy 40.191817 -111.247984) (xy 40.241417 -111.222483) (xy 40.294201 -111.204476)
			(xy 40.349044 -111.194346) (xy 40.404778 -111.192309) (xy 40.460215 -111.198409) (xy 40.514172 -111.212515)
			(xy 40.565501 -111.234327) (xy 40.613107 -111.263381) (xy 40.655975 -111.299056) (xy 40.693192 -111.340593)
			(xy 40.723965 -111.387106) (xy 40.747637 -111.437603) (xy 40.763705 -111.49101) (xy 40.771825 -111.546186)
			(xy 40.772334 -111.574072) (xy 40.771825 -111.601958) (xy 40.763705 -111.657134) (xy 40.747637 -111.710541)
			(xy 40.723965 -111.761038) (xy 40.693192 -111.807551) (xy 40.655975 -111.849088) (xy 40.613107 -111.884763)
			(xy 40.565501 -111.913817) (xy 40.514172 -111.935629) (xy 40.460215 -111.949735) (xy 40.404778 -111.955835)
			(xy 40.349044 -111.953798) (xy 40.294201 -111.943668) (xy 40.241417 -111.925661) (xy 40.191817 -111.90016)
			(xy 40.146459 -111.867709) (xy 40.10631 -111.829) (xy 40.072224 -111.784857) (xy 40.044928 -111.736222)
			(xy 40.025005 -111.684131) (xy 40.012879 -111.629694) (xy 40.008808 -111.574072) (xy 36.027354 -111.574072)
			(xy 35.96009 -111.611655) (xy 35.880418 -111.646937) (xy 35.797824 -111.674697) (xy 35.713016 -111.694698)
			(xy 35.626721 -111.706768) (xy 35.53968 -111.710802) (xy 35.452639 -111.706768) (xy 35.366344 -111.694698)
			(xy 35.281536 -111.674697) (xy 35.198942 -111.646937) (xy 35.11927 -111.611655) (xy 35.043204 -111.569154)
			(xy 34.971395 -111.519798) (xy 34.904461 -111.464011) (xy 34.842974 -111.402271) (xy 34.787462 -111.335108)
			(xy 34.738402 -111.263097) (xy 34.696213 -111.186857) (xy 34.661259 -111.107041) (xy 34.633838 -111.024333)
			(xy 34.614186 -110.939443) (xy 34.602471 -110.8531) (xy 34.598794 -110.766043) (xy 34.603186 -110.679019)
			(xy 34.61561 -110.592775) (xy 34.635959 -110.50805) (xy 34.664058 -110.42557) (xy 34.681414 -110.385606)
			(xy 34.690266 -110.364368) (xy 34.701191 -110.319682) (xy 34.703898 -110.273759) (xy 34.698297 -110.228099)
			(xy 34.684573 -110.184191) (xy 34.663172 -110.14347) (xy 34.634794 -110.107264) (xy 34.600364 -110.076754)
			(xy 34.561006 -110.052938) (xy 34.518006 -110.036592) (xy 34.472766 -110.02825) (xy 34.449766 -110.02772)
			(xy 31.549594 -110.02772) (xy 31.526581 -110.028227) (xy 31.481311 -110.036535) (xy 31.438278 -110.052859)
			(xy 31.398888 -110.076667) (xy 31.364429 -110.107179) (xy 31.336029 -110.143398) (xy 31.314615 -110.184139)
			(xy 31.300889 -110.228071) (xy 31.295299 -110.273756) (xy 31.298028 -110.319701) (xy 31.308986 -110.364403)
			(xy 31.317946 -110.385606) (xy 31.33532 -110.425622) (xy 31.363446 -110.508209) (xy 31.383802 -110.593045)
			(xy 31.396212 -110.679403) (xy 31.400571 -110.766538) (xy 31.396841 -110.853703) (xy 31.385053 -110.940148)
			(xy 31.365309 -111.025129) (xy 31.337779 -111.107916) (xy 31.3027 -111.187797) (xy 31.260373 -111.264086)
			(xy 31.211161 -111.336127) (xy 31.155489 -111.4033) (xy 31.093834 -111.465028) (xy 31.026727 -111.520779)
			(xy 30.954745 -111.570076) (xy 30.878506 -111.612494) (xy 30.798667 -111.647668) (xy 30.715912 -111.675296)
			(xy 30.630954 -111.69514) (xy 30.544524 -111.707031) (xy 30.457364 -111.710865) (xy 30.370223 -111.706609)
			(xy 30.283851 -111.694301) (xy 30.19899 -111.674045) (xy 30.116371 -111.646017) (xy 30.036702 -111.610457)
			(xy 29.960669 -111.567671) (xy 29.888926 -111.518027) (xy 29.82209 -111.461951) (xy 29.760735 -111.399926)
			(xy 29.705388 -111.332484) (xy 29.656526 -111.260206) (xy 29.614568 -111.183713) (xy 29.579876 -111.103663)
			(xy 29.552747 -111.020744) (xy 29.533414 -110.935668) (xy 29.522045 -110.849168) (xy 29.518736 -110.761986)
			(xy 29.523517 -110.674872) (xy 29.536345 -110.588576) (xy 29.557111 -110.503839) (xy 29.585636 -110.421389)
			(xy 29.621676 -110.341936) (xy 29.664919 -110.266163) (xy 29.689552 -110.230158) (xy 29.697756 -110.21781)
			(xy 29.708737 -110.190279) (xy 29.713054 -110.160954) (xy 29.710474 -110.131427) (xy 29.701135 -110.103296)
			(xy 29.685545 -110.078087) (xy 29.675328 -110.067344) (xy 27.690064 -108.081826) (xy 23.551896 -108.081826)
			(xy 23.551896 -108.23448) (xy 25.742138 -110.424722) (xy 27.424632 -110.424722) (xy 27.428703 -110.3691)
			(xy 27.440829 -110.314663) (xy 27.460752 -110.262572) (xy 27.488048 -110.213937) (xy 27.522134 -110.169794)
			(xy 27.562283 -110.131085) (xy 27.607641 -110.098634) (xy 27.657241 -110.073133) (xy 27.710025 -110.055126)
			(xy 27.764868 -110.044996) (xy 27.820602 -110.042959) (xy 27.876039 -110.049059) (xy 27.929996 -110.063165)
			(xy 27.981325 -110.084977) (xy 28.028931 -110.114031) (xy 28.071799 -110.149706) (xy 28.109016 -110.191243)
			(xy 28.139789 -110.237756) (xy 28.163461 -110.288253) (xy 28.179529 -110.34166) (xy 28.187649 -110.396836)
			(xy 28.188158 -110.424722) (xy 28.187649 -110.452608) (xy 28.179529 -110.507784) (xy 28.163461 -110.561191)
			(xy 28.139789 -110.611688) (xy 28.109016 -110.658201) (xy 28.071799 -110.699738) (xy 28.028931 -110.735413)
			(xy 27.981325 -110.764467) (xy 27.929996 -110.786279) (xy 27.876039 -110.800385) (xy 27.820602 -110.806485)
			(xy 27.764868 -110.804448) (xy 27.710025 -110.794318) (xy 27.657241 -110.776311) (xy 27.607641 -110.75081)
			(xy 27.562283 -110.718359) (xy 27.522134 -110.67965) (xy 27.488048 -110.635507) (xy 27.460752 -110.586872)
			(xy 27.440829 -110.534781) (xy 27.428703 -110.480344) (xy 27.424632 -110.424722) (xy 25.742138 -110.424722)
			(xy 28.884372 -113.566956) (xy 28.884372 -121.199656) (xy 72.868035 -121.199656) (xy 72.872042 -120.996906)
			(xy 72.884055 -120.794472) (xy 72.904056 -120.592671) (xy 72.932015 -120.391817) (xy 72.967886 -120.192225)
			(xy 73.011615 -119.994206) (xy 73.063133 -119.798069) (xy 73.122359 -119.604121) (xy 73.189201 -119.412663)
			(xy 73.263555 -119.223996) (xy 73.345304 -119.038414) (xy 73.434322 -118.856206) (xy 73.530468 -118.677657)
			(xy 73.633593 -118.503046) (xy 73.743536 -118.332646) (xy 73.860125 -118.166722) (xy 73.983178 -118.005533)
			(xy 74.112503 -117.849332) (xy 74.247898 -117.698362) (xy 74.389151 -117.552858) (xy 74.536043 -117.413049)
			(xy 74.688343 -117.279152) (xy 74.845814 -117.151377) (xy 75.008211 -117.029922) (xy 75.175278 -116.914978)
			(xy 75.346757 -116.806724) (xy 75.522378 -116.705329) (xy 75.701868 -116.610951) (xy 75.884946 -116.523739)
			(xy 76.071327 -116.443827) (xy 76.26072 -116.37134) (xy 76.452828 -116.306393) (xy 76.647352 -116.249085)
			(xy 76.843988 -116.199508) (xy 77.04243 -116.157737) (xy 77.242367 -116.123839) (xy 77.443486 -116.097867)
			(xy 77.645475 -116.07986) (xy 77.848018 -116.069847) (xy 78.050798 -116.067843) (xy 78.253499 -116.073853)
			(xy 78.455804 -116.087865) (xy 78.657398 -116.10986) (xy 78.857965 -116.139801) (xy 79.057193 -116.177642)
			(xy 79.254771 -116.223325) (xy 79.450389 -116.276778) (xy 79.643743 -116.337917) (xy 79.834531 -116.406648)
			(xy 80.022454 -116.482862) (xy 80.20722 -116.566441) (xy 80.388539 -116.657254) (xy 80.56613 -116.755159)
			(xy 80.739713 -116.860004) (xy 80.909019 -116.971625) (xy 81.073784 -117.089847) (xy 81.233749 -117.214487)
			(xy 81.388665 -117.345348) (xy 81.53829 -117.482228) (xy 81.68239 -117.624912) (xy 81.820742 -117.773178)
			(xy 81.953127 -117.926794) (xy 82.079341 -118.085519) (xy 82.199185 -118.249108) (xy 82.312473 -118.417303)
			(xy 82.419028 -118.589842) (xy 82.518683 -118.766457) (xy 82.611283 -118.94687) (xy 82.696683 -119.130801)
			(xy 82.77475 -119.317962) (xy 82.845362 -119.508062) (xy 82.908408 -119.700802) (xy 82.963791 -119.895883)
			(xy 83.011423 -120.093) (xy 83.051231 -120.291844) (xy 83.083153 -120.492106) (xy 83.107137 -120.693472)
			(xy 83.123148 -120.895629) (xy 83.131159 -121.098261) (xy 83.13166 -121.199656) (xy 83.131159 -121.301051)
			(xy 83.123148 -121.503683) (xy 83.107137 -121.70584) (xy 83.083153 -121.907206) (xy 83.051231 -122.107468)
			(xy 83.011423 -122.306312) (xy 82.963791 -122.503429) (xy 82.908408 -122.69851) (xy 82.845362 -122.89125)
			(xy 82.77475 -123.08135) (xy 82.696683 -123.268511) (xy 82.611283 -123.452442) (xy 82.518683 -123.632855)
			(xy 82.419028 -123.80947) (xy 82.312473 -123.982009) (xy 82.199185 -124.150204) (xy 82.079341 -124.313793)
			(xy 81.953127 -124.472518) (xy 81.820742 -124.626134) (xy 81.68239 -124.7744) (xy 81.53829 -124.917084)
			(xy 81.388665 -125.053964) (xy 81.233749 -125.184825) (xy 81.073784 -125.309465) (xy 80.909019 -125.427687)
			(xy 80.739713 -125.539308) (xy 80.56613 -125.644153) (xy 80.388539 -125.742058) (xy 80.20722 -125.832871)
			(xy 80.022454 -125.91645) (xy 79.834531 -125.992664) (xy 79.643743 -126.061395) (xy 79.450389 -126.122534)
			(xy 79.254771 -126.175987) (xy 79.057193 -126.22167) (xy 78.857965 -126.259511) (xy 78.657398 -126.289452)
			(xy 78.455804 -126.311447) (xy 78.253499 -126.325459) (xy 78.050798 -126.331469) (xy 77.848018 -126.329465)
			(xy 77.645475 -126.319452) (xy 77.443486 -126.301445) (xy 77.242367 -126.275473) (xy 77.04243 -126.241575)
			(xy 76.843988 -126.199804) (xy 76.647352 -126.150227) (xy 76.452828 -126.092919) (xy 76.26072 -126.027972)
			(xy 76.071327 -125.955485) (xy 75.884946 -125.875573) (xy 75.701868 -125.788361) (xy 75.522378 -125.693983)
			(xy 75.346757 -125.592588) (xy 75.175278 -125.484334) (xy 75.008211 -125.36939) (xy 74.845814 -125.247935)
			(xy 74.688343 -125.12016) (xy 74.536043 -124.986263) (xy 74.389151 -124.846454) (xy 74.247898 -124.70095)
			(xy 74.112503 -124.54998) (xy 73.983178 -124.393779) (xy 73.860125 -124.23259) (xy 73.743536 -124.066666)
			(xy 73.633593 -123.896266) (xy 73.530468 -123.721655) (xy 73.434322 -123.543106) (xy 73.345304 -123.360898)
			(xy 73.263555 -123.175316) (xy 73.189201 -122.986649) (xy 73.122359 -122.795191) (xy 73.063133 -122.601243)
			(xy 73.011615 -122.405106) (xy 72.967886 -122.207087) (xy 72.932015 -122.007495) (xy 72.904056 -121.806641)
			(xy 72.884055 -121.60484) (xy 72.872042 -121.402406) (xy 72.868035 -121.199656) (xy 28.884372 -121.199656)
			(xy 28.884372 -128.695873) (xy 47.574952 -128.695873) (xy 47.574952 -128.614763) (xy 47.582902 -128.534044)
			(xy 47.598725 -128.454493) (xy 47.62227 -128.376877) (xy 47.653309 -128.301941) (xy 47.691544 -128.230409)
			(xy 47.736606 -128.162969) (xy 47.788061 -128.10027) (xy 47.845414 -128.042917) (xy 47.908113 -127.991462)
			(xy 47.975553 -127.9464) (xy 48.047085 -127.908165) (xy 48.122021 -127.877126) (xy 48.199637 -127.853581)
			(xy 48.279188 -127.837758) (xy 48.359907 -127.829808) (xy 48.441017 -127.829808) (xy 48.521736 -127.837758)
			(xy 48.601287 -127.853581) (xy 48.678903 -127.877126) (xy 48.753839 -127.908165) (xy 48.825371 -127.9464)
			(xy 48.892811 -127.991462) (xy 48.95551 -128.042917) (xy 49.012863 -128.10027) (xy 49.064318 -128.162969)
			(xy 49.10938 -128.230409) (xy 49.147615 -128.301941) (xy 49.178654 -128.376877) (xy 49.202199 -128.454493)
			(xy 49.218022 -128.534044) (xy 49.225972 -128.614763) (xy 49.22647 -128.655318) (xy 49.225972 -128.695873)
			(xy 51.075072 -128.695873) (xy 51.075072 -128.614763) (xy 51.083022 -128.534044) (xy 51.098845 -128.454493)
			(xy 51.12239 -128.376877) (xy 51.153429 -128.301941) (xy 51.191664 -128.230409) (xy 51.236726 -128.162969)
			(xy 51.288181 -128.10027) (xy 51.345534 -128.042917) (xy 51.408233 -127.991462) (xy 51.475673 -127.9464)
			(xy 51.547205 -127.908165) (xy 51.622141 -127.877126) (xy 51.699757 -127.853581) (xy 51.779308 -127.837758)
			(xy 51.860027 -127.829808) (xy 51.941137 -127.829808) (xy 52.021856 -127.837758) (xy 52.101407 -127.853581)
			(xy 52.179023 -127.877126) (xy 52.253959 -127.908165) (xy 52.325491 -127.9464) (xy 52.392931 -127.991462)
			(xy 52.45563 -128.042917) (xy 52.512983 -128.10027) (xy 52.564438 -128.162969) (xy 52.6095 -128.230409)
			(xy 52.647735 -128.301941) (xy 52.678774 -128.376877) (xy 52.702319 -128.454493) (xy 52.718142 -128.534044)
			(xy 52.726092 -128.614763) (xy 52.72659 -128.655318) (xy 52.726092 -128.695873) (xy 52.718142 -128.776592)
			(xy 52.702319 -128.856143) (xy 52.678774 -128.933759) (xy 52.647735 -129.008695) (xy 52.6095 -129.080227)
			(xy 52.564438 -129.147667) (xy 52.512983 -129.210366) (xy 52.45563 -129.267719) (xy 52.392931 -129.319174)
			(xy 52.325491 -129.364236) (xy 52.253959 -129.402471) (xy 52.179023 -129.43351) (xy 52.101407 -129.457055)
			(xy 52.021856 -129.472878) (xy 51.941137 -129.480828) (xy 51.860027 -129.480828) (xy 51.779308 -129.472878)
			(xy 51.699757 -129.457055) (xy 51.622141 -129.43351) (xy 51.547205 -129.402471) (xy 51.475673 -129.364236)
			(xy 51.408233 -129.319174) (xy 51.345534 -129.267719) (xy 51.288181 -129.210366) (xy 51.236726 -129.147667)
			(xy 51.191664 -129.080227) (xy 51.153429 -129.008695) (xy 51.12239 -128.933759) (xy 51.098845 -128.856143)
			(xy 51.083022 -128.776592) (xy 51.075072 -128.695873) (xy 49.225972 -128.695873) (xy 49.218022 -128.776592)
			(xy 49.202199 -128.856143) (xy 49.178654 -128.933759) (xy 49.147615 -129.008695) (xy 49.10938 -129.080227)
			(xy 49.064318 -129.147667) (xy 49.012863 -129.210366) (xy 48.95551 -129.267719) (xy 48.892811 -129.319174)
			(xy 48.825371 -129.364236) (xy 48.753839 -129.402471) (xy 48.678903 -129.43351) (xy 48.601287 -129.457055)
			(xy 48.521736 -129.472878) (xy 48.441017 -129.480828) (xy 48.359907 -129.480828) (xy 48.279188 -129.472878)
			(xy 48.199637 -129.457055) (xy 48.122021 -129.43351) (xy 48.047085 -129.402471) (xy 47.975553 -129.364236)
			(xy 47.908113 -129.319174) (xy 47.845414 -129.267719) (xy 47.788061 -129.210366) (xy 47.736606 -129.147667)
			(xy 47.691544 -129.080227) (xy 47.653309 -129.008695) (xy 47.62227 -128.933759) (xy 47.598725 -128.856143)
			(xy 47.582902 -128.776592) (xy 47.574952 -128.695873) (xy 28.884372 -128.695873) (xy 28.884372 -131.215082)
			(xy 73.168592 -131.215082) (xy 73.172482 -131.160727) (xy 73.184069 -131.107479) (xy 73.203117 -131.056423)
			(xy 73.229237 -131.008597) (xy 73.261898 -130.964975) (xy 73.300435 -130.926446) (xy 73.344063 -130.893794)
			(xy 73.391894 -130.867684) (xy 73.442955 -130.848647) (xy 73.496205 -130.837071) (xy 73.550561 -130.833192)
			(xy 73.604915 -130.837088) (xy 73.658162 -130.848681) (xy 73.709216 -130.867734) (xy 73.757039 -130.89386)
			(xy 73.779126 -130.909822) (xy 73.798138 -130.923418) (xy 73.840021 -130.94415) (xy 73.884989 -130.956876)
			(xy 73.931526 -130.961166) (xy 73.978063 -130.956876) (xy 74.023031 -130.94415) (xy 74.064914 -130.923418)
			(xy 74.083926 -130.909822) (xy 74.105985 -130.893824) (xy 74.153811 -130.867703) (xy 74.204867 -130.848655)
			(xy 74.258114 -130.837067) (xy 74.312469 -130.833175) (xy 74.366824 -130.837058) (xy 74.420073 -130.848638)
			(xy 74.471132 -130.867677) (xy 74.518962 -130.89379) (xy 74.562589 -130.926444) (xy 74.601124 -130.964974)
			(xy 74.633783 -131.008597) (xy 74.659902 -131.056423) (xy 74.678949 -131.10748) (xy 74.686571 -131.142508)
			(xy 75.192473 -131.142508) (xy 75.19636 -131.088152) (xy 75.207943 -131.034902) (xy 75.226987 -130.983843)
			(xy 75.253104 -130.936014) (xy 75.285762 -130.892388) (xy 75.324296 -130.853855) (xy 75.367922 -130.821198)
			(xy 75.415752 -130.795083) (xy 75.466812 -130.77604) (xy 75.520062 -130.764459) (xy 75.574419 -130.760573)
			(xy 75.628775 -130.764464) (xy 75.682024 -130.776051) (xy 75.733082 -130.795098) (xy 75.780909 -130.821218)
			(xy 75.802998 -130.837178) (xy 75.82201 -130.850774) (xy 75.863893 -130.871506) (xy 75.908861 -130.884232)
			(xy 75.955398 -130.888522) (xy 76.001935 -130.884232) (xy 76.046903 -130.871506) (xy 76.088786 -130.850774)
			(xy 76.107798 -130.837178) (xy 76.129899 -130.821237) (xy 76.177724 -130.795118) (xy 76.228779 -130.776071)
			(xy 76.282026 -130.764484) (xy 76.336379 -130.760593) (xy 76.390733 -130.764478) (xy 76.443981 -130.776059)
			(xy 76.495038 -130.7951) (xy 76.542866 -130.821214) (xy 76.58649 -130.853869) (xy 76.625023 -130.892401)
			(xy 76.657679 -130.936024) (xy 76.683795 -130.983851) (xy 76.702837 -131.034907) (xy 76.71442 -131.088155)
			(xy 76.718307 -131.142508) (xy 76.716312 -131.170384) (xy 77.079526 -131.170384) (xy 77.083415 -131.116038)
			(xy 77.094999 -131.062797) (xy 77.114042 -131.011748) (xy 77.140157 -130.963928) (xy 77.172811 -130.920311)
			(xy 77.211341 -130.881786) (xy 77.25496 -130.849136) (xy 77.302783 -130.823026) (xy 77.353835 -130.803988)
			(xy 77.407076 -130.79241) (xy 77.461423 -130.788526) (xy 77.51577 -130.792416) (xy 77.56901 -130.804001)
			(xy 77.620059 -130.823046) (xy 77.667879 -130.849161) (xy 77.689964 -130.865118) (xy 77.708976 -130.878714)
			(xy 77.750859 -130.899446) (xy 77.795827 -130.912172) (xy 77.842364 -130.916462) (xy 77.888901 -130.912172)
			(xy 77.933869 -130.899446) (xy 77.975752 -130.878714) (xy 77.994764 -130.865118) (xy 78.016829 -130.84912)
			(xy 78.064658 -130.82299) (xy 78.11572 -130.803934) (xy 78.168974 -130.792339) (xy 78.223336 -130.788441)
			(xy 78.277699 -130.79232) (xy 78.330957 -130.803898) (xy 78.382025 -130.822937) (xy 78.429863 -130.849051)
			(xy 78.473498 -130.881707) (xy 78.512041 -130.920242) (xy 78.544706 -130.963869) (xy 78.57083 -131.011702)
			(xy 78.58988 -131.062766) (xy 78.601468 -131.116022) (xy 78.605359 -131.170384) (xy 78.601473 -131.224747)
			(xy 78.597548 -131.24279) (xy 79.320988 -131.24279) (xy 79.324877 -131.188435) (xy 79.336463 -131.135187)
			(xy 79.355509 -131.08413) (xy 79.381627 -131.036304) (xy 79.414287 -130.992681) (xy 79.452823 -130.954151)
			(xy 79.49645 -130.921498) (xy 79.544281 -130.895386) (xy 79.59534 -130.876347) (xy 79.64859 -130.864769)
			(xy 79.702946 -130.860888) (xy 79.7573 -130.864782) (xy 79.810547 -130.876373) (xy 79.861602 -130.895424)
			(xy 79.909427 -130.921547) (xy 79.931514 -130.937508) (xy 79.950526 -130.951104) (xy 79.992409 -130.971836)
			(xy 80.037377 -130.984562) (xy 80.083914 -130.988852) (xy 80.130451 -130.984562) (xy 80.175419 -130.971836)
			(xy 80.217302 -130.951104) (xy 80.236314 -130.937508) (xy 80.258387 -130.921528) (xy 80.306212 -130.895407)
			(xy 80.357268 -130.876359) (xy 80.410516 -130.864771) (xy 80.46487 -130.860879) (xy 80.519225 -130.864763)
			(xy 80.572475 -130.876342) (xy 80.623534 -130.895382) (xy 80.671363 -130.921496) (xy 80.714989 -130.95415)
			(xy 80.753524 -130.992681) (xy 80.786183 -131.036304) (xy 80.812301 -131.084131) (xy 80.831347 -131.135188)
			(xy 80.842932 -131.188436) (xy 80.845511 -131.224483) (xy 81.441402 -131.224483) (xy 81.445292 -131.170131)
			(xy 81.456878 -131.116885) (xy 81.475924 -131.065831) (xy 81.502042 -131.018007) (xy 81.534701 -130.974387)
			(xy 81.573236 -130.935859) (xy 81.616861 -130.903207) (xy 81.66469 -130.877097) (xy 81.715748 -130.85806)
			(xy 81.768995 -130.846483) (xy 81.823348 -130.842602) (xy 81.8777 -130.846497) (xy 81.930945 -130.858087)
			(xy 81.981998 -130.877137) (xy 82.02982 -130.903259) (xy 82.051906 -130.91922) (xy 82.070918 -130.932816)
			(xy 82.112801 -130.953548) (xy 82.157769 -130.966274) (xy 82.204306 -130.970564) (xy 82.250843 -130.966274)
			(xy 82.295811 -130.953548) (xy 82.337694 -130.932816) (xy 82.356706 -130.91922) (xy 82.378768 -130.903223)
			(xy 82.426595 -130.877099) (xy 82.477652 -130.858049) (xy 82.530902 -130.846458) (xy 82.585259 -130.842565)
			(xy 82.639616 -130.846447) (xy 82.692868 -130.858025) (xy 82.74393 -130.877065) (xy 82.791763 -130.903178)
			(xy 82.835392 -130.935833) (xy 82.873929 -130.974364) (xy 82.906591 -131.017988) (xy 82.932711 -131.065817)
			(xy 82.951758 -131.116876) (xy 82.963345 -131.170126) (xy 82.967235 -131.224483) (xy 82.96335 -131.278841)
			(xy 82.951768 -131.332092) (xy 82.932725 -131.383152) (xy 82.906609 -131.430983) (xy 82.873951 -131.47461)
			(xy 82.835417 -131.513145) (xy 82.791791 -131.545804) (xy 82.743961 -131.571921) (xy 82.6929 -131.590965)
			(xy 82.63965 -131.602549) (xy 82.585292 -131.606435) (xy 82.530935 -131.602546) (xy 82.477685 -131.590961)
			(xy 82.426625 -131.571915) (xy 82.378796 -131.545795) (xy 82.356706 -131.529836) (xy 82.337694 -131.51624)
			(xy 82.295811 -131.495508) (xy 82.250843 -131.482782) (xy 82.204306 -131.478492) (xy 82.157769 -131.482782)
			(xy 82.112801 -131.495508) (xy 82.070918 -131.51624) (xy 82.051906 -131.529836) (xy 82.029791 -131.545759)
			(xy 81.981967 -131.571877) (xy 81.930913 -131.590922) (xy 81.877667 -131.602508) (xy 81.823315 -131.606398)
			(xy 81.768962 -131.602512) (xy 81.715716 -131.590931) (xy 81.664659 -131.571889) (xy 81.616833 -131.545775)
			(xy 81.57321 -131.513119) (xy 81.534679 -131.474588) (xy 81.502024 -131.430965) (xy 81.47591 -131.383139)
			(xy 81.456869 -131.332082) (xy 81.445287 -131.278836) (xy 81.441402 -131.224483) (xy 80.845511 -131.224483)
			(xy 80.846821 -131.24279) (xy 80.842935 -131.297145) (xy 80.831352 -131.350394) (xy 80.812309 -131.401452)
			(xy 80.786194 -131.44928) (xy 80.753537 -131.492905) (xy 80.715004 -131.531437) (xy 80.671379 -131.564094)
			(xy 80.623551 -131.59021) (xy 80.572493 -131.609252) (xy 80.519244 -131.620835) (xy 80.46489 -131.624721)
			(xy 80.410535 -131.620832) (xy 80.357287 -131.609246) (xy 80.30623 -131.590201) (xy 80.258403 -131.564083)
			(xy 80.236314 -131.548124) (xy 80.217302 -131.534528) (xy 80.175419 -131.513796) (xy 80.130451 -131.50107)
			(xy 80.083914 -131.49678) (xy 80.037377 -131.50107) (xy 79.992409 -131.513796) (xy 79.950526 -131.534528)
			(xy 79.931514 -131.548124) (xy 79.90941 -131.564064) (xy 79.861585 -131.590184) (xy 79.810529 -131.609233)
			(xy 79.757281 -131.620821) (xy 79.702926 -131.624712) (xy 79.648571 -131.620828) (xy 79.595322 -131.609248)
			(xy 79.544263 -131.590206) (xy 79.496434 -131.564092) (xy 79.452808 -131.531436) (xy 79.414275 -131.492904)
			(xy 79.381617 -131.44928) (xy 79.355501 -131.401452) (xy 79.336457 -131.350394) (xy 79.324874 -131.297145)
			(xy 79.320988 -131.24279) (xy 78.597548 -131.24279) (xy 78.589889 -131.278004) (xy 78.570843 -131.329069)
			(xy 78.544723 -131.376904) (xy 78.512061 -131.420535) (xy 78.473522 -131.459072) (xy 78.42989 -131.491733)
			(xy 78.382054 -131.51785) (xy 78.330987 -131.536894) (xy 78.27773 -131.548475) (xy 78.223367 -131.552359)
			(xy 78.169005 -131.548466) (xy 78.11575 -131.536875) (xy 78.064687 -131.517823) (xy 78.016855 -131.491697)
			(xy 77.994764 -131.475734) (xy 77.975752 -131.462138) (xy 77.933869 -131.441406) (xy 77.888901 -131.42868)
			(xy 77.842364 -131.42439) (xy 77.795827 -131.42868) (xy 77.750859 -131.441406) (xy 77.708976 -131.462138)
			(xy 77.689964 -131.475734) (xy 77.667852 -131.491656) (xy 77.620031 -131.517767) (xy 77.56898 -131.536807)
			(xy 77.515739 -131.548388) (xy 77.461392 -131.552274) (xy 77.407045 -131.548386) (xy 77.353805 -131.536803)
			(xy 77.302755 -131.517761) (xy 77.254934 -131.491647) (xy 77.211317 -131.458994) (xy 77.172791 -131.420465)
			(xy 77.14014 -131.376846) (xy 77.114029 -131.329024) (xy 77.09499 -131.277973) (xy 77.083411 -131.224732)
			(xy 77.079526 -131.170384) (xy 76.716312 -131.170384) (xy 76.714418 -131.196862) (xy 76.702833 -131.250109)
			(xy 76.683788 -131.301165) (xy 76.65767 -131.34899) (xy 76.625011 -131.392612) (xy 76.586477 -131.431142)
			(xy 76.542852 -131.463795) (xy 76.495023 -131.489907) (xy 76.443965 -131.508946) (xy 76.390716 -131.520524)
			(xy 76.336362 -131.524407) (xy 76.282009 -131.520514) (xy 76.228763 -131.508925) (xy 76.177709 -131.489875)
			(xy 76.129885 -131.463754) (xy 76.107798 -131.447794) (xy 76.088786 -131.434198) (xy 76.046903 -131.413466)
			(xy 76.001935 -131.40074) (xy 75.955398 -131.39645) (xy 75.908861 -131.40074) (xy 75.863893 -131.413466)
			(xy 75.82201 -131.434198) (xy 75.802998 -131.447794) (xy 75.780923 -131.463773) (xy 75.733097 -131.489895)
			(xy 75.68204 -131.508944) (xy 75.628791 -131.520534) (xy 75.574435 -131.524427) (xy 75.520079 -131.520544)
			(xy 75.466828 -131.508964) (xy 75.415767 -131.489924) (xy 75.367936 -131.463811) (xy 75.324309 -131.431156)
			(xy 75.285773 -131.392624) (xy 75.253113 -131.349) (xy 75.226994 -131.301172) (xy 75.207948 -131.250114)
			(xy 75.196362 -131.196865) (xy 75.192473 -131.142508) (xy 74.686571 -131.142508) (xy 74.690535 -131.160727)
			(xy 74.694425 -131.215082) (xy 74.69054 -131.269437) (xy 74.678959 -131.322686) (xy 74.659917 -131.373744)
			(xy 74.633803 -131.421573) (xy 74.601147 -131.465199) (xy 74.562616 -131.503733) (xy 74.518992 -131.536391)
			(xy 74.471165 -131.562508) (xy 74.420108 -131.581552) (xy 74.366859 -131.593137) (xy 74.312505 -131.597025)
			(xy 74.25815 -131.593138) (xy 74.204902 -131.581555) (xy 74.153844 -131.562512) (xy 74.106016 -131.536396)
			(xy 74.083926 -131.520438) (xy 74.064914 -131.506842) (xy 74.023031 -131.48611) (xy 73.978063 -131.473384)
			(xy 73.931526 -131.469094) (xy 73.884989 -131.473384) (xy 73.840021 -131.48611) (xy 73.798138 -131.506842)
			(xy 73.779126 -131.520438) (xy 73.757009 -131.53636) (xy 73.709184 -131.562481) (xy 73.658127 -131.581529)
			(xy 73.60488 -131.593117) (xy 73.550525 -131.597008) (xy 73.49617 -131.593124) (xy 73.44292 -131.581543)
			(xy 73.391862 -131.562501) (xy 73.344033 -131.536387) (xy 73.300407 -131.50373) (xy 73.261874 -131.465198)
			(xy 73.229217 -131.421573) (xy 73.203102 -131.373745) (xy 73.184059 -131.322686) (xy 73.172477 -131.269437)
			(xy 73.168592 -131.215082) (xy 28.884372 -131.215082) (xy 28.884372 -133.177975) (xy 73.168602 -133.177975)
			(xy 73.172493 -133.123621) (xy 73.18408 -133.070375) (xy 73.203128 -133.01932) (xy 73.229249 -132.971496)
			(xy 73.26191 -132.927876) (xy 73.300446 -132.889349) (xy 73.344074 -132.856698) (xy 73.391905 -132.83059)
			(xy 73.442965 -132.811554) (xy 73.496214 -132.79998) (xy 73.550568 -132.796102) (xy 73.604921 -132.799999)
			(xy 73.658166 -132.811592) (xy 73.709219 -132.830646) (xy 73.75704 -132.856772) (xy 73.779126 -132.872734)
			(xy 73.798138 -132.88633) (xy 73.840021 -132.907062) (xy 73.884989 -132.919788) (xy 73.931526 -132.924078)
			(xy 73.978063 -132.919788) (xy 74.023031 -132.907062) (xy 74.064914 -132.88633) (xy 74.083926 -132.872734)
			(xy 74.105974 -132.85672) (xy 74.1538 -132.830598) (xy 74.204857 -132.811548) (xy 74.258106 -132.799959)
			(xy 74.312462 -132.796065) (xy 74.366818 -132.799948) (xy 74.420069 -132.811526) (xy 74.47113 -132.830566)
			(xy 74.518961 -132.856678) (xy 74.562589 -132.889332) (xy 74.601126 -132.927862) (xy 74.633788 -132.971485)
			(xy 74.659908 -133.019312) (xy 74.678956 -133.07037) (xy 74.686579 -133.105401) (xy 75.192483 -133.105401)
			(xy 75.196371 -133.051046) (xy 75.207954 -132.997798) (xy 75.226999 -132.94674) (xy 75.253116 -132.898913)
			(xy 75.285774 -132.855289) (xy 75.324308 -132.816758) (xy 75.367934 -132.784102) (xy 75.415763 -132.757989)
			(xy 75.466822 -132.738948) (xy 75.520071 -132.727367) (xy 75.574426 -132.723483) (xy 75.62878 -132.727374)
			(xy 75.682028 -132.738962) (xy 75.733084 -132.75801) (xy 75.78091 -132.78413) (xy 75.802998 -132.80009)
			(xy 75.82201 -132.813686) (xy 75.863893 -132.834418) (xy 75.908861 -132.847144) (xy 75.955398 -132.851434)
			(xy 76.001935 -132.847144) (xy 76.046903 -132.834418) (xy 76.088786 -132.813686) (xy 76.107798 -132.80009)
			(xy 76.129888 -132.784133) (xy 76.177714 -132.758012) (xy 76.22877 -132.738964) (xy 76.282017 -132.727376)
			(xy 76.336372 -132.723484) (xy 76.390727 -132.727368) (xy 76.443976 -132.738948) (xy 76.495035 -132.757989)
			(xy 76.542865 -132.784102) (xy 76.586491 -132.816757) (xy 76.625025 -132.855289) (xy 76.657683 -132.898913)
			(xy 76.6838 -132.94674) (xy 76.702845 -132.997798) (xy 76.714429 -133.051046) (xy 76.718316 -133.105401)
			(xy 76.716322 -133.133277) (xy 77.079535 -133.133277) (xy 77.083426 -133.078932) (xy 77.09501 -133.025693)
			(xy 77.114054 -132.974645) (xy 77.140169 -132.926827) (xy 77.172823 -132.883212) (xy 77.211352 -132.844688)
			(xy 77.254972 -132.81204) (xy 77.302793 -132.785932) (xy 77.353844 -132.766896) (xy 77.407084 -132.755318)
			(xy 77.46143 -132.751435) (xy 77.515776 -132.755327) (xy 77.569014 -132.766913) (xy 77.620062 -132.785957)
			(xy 77.667879 -132.812073) (xy 77.689964 -132.82803) (xy 77.708976 -132.841626) (xy 77.750859 -132.862358)
			(xy 77.795827 -132.875084) (xy 77.842364 -132.879374) (xy 77.888901 -132.875084) (xy 77.933869 -132.862358)
			(xy 77.975752 -132.841626) (xy 77.994764 -132.82803) (xy 78.016817 -132.812016) (xy 78.064648 -132.785884)
			(xy 78.11571 -132.766826) (xy 78.168965 -132.75523) (xy 78.223329 -132.751331) (xy 78.277694 -132.75521)
			(xy 78.330953 -132.766786) (xy 78.382023 -132.785825) (xy 78.429863 -132.811939) (xy 78.473499 -132.844595)
			(xy 78.512043 -132.88313) (xy 78.54471 -132.926758) (xy 78.570836 -132.974592) (xy 78.589887 -133.025657)
			(xy 78.601477 -133.078913) (xy 78.605369 -133.133277) (xy 78.601483 -133.187642) (xy 78.597559 -133.205683)
			(xy 79.320997 -133.205683) (xy 79.324888 -133.15133) (xy 79.336474 -133.098083) (xy 79.35552 -133.047028)
			(xy 79.381639 -132.999203) (xy 79.414299 -132.955582) (xy 79.452835 -132.917053) (xy 79.496461 -132.884402)
			(xy 79.544291 -132.858291) (xy 79.59535 -132.839254) (xy 79.648599 -132.827678) (xy 79.702953 -132.823798)
			(xy 79.757306 -132.827693) (xy 79.810551 -132.839284) (xy 79.861605 -132.858335) (xy 79.909428 -132.884459)
			(xy 79.931514 -132.90042) (xy 79.950526 -132.914016) (xy 79.992409 -132.934748) (xy 80.037377 -132.947474)
			(xy 80.083914 -132.951764) (xy 80.130451 -132.947474) (xy 80.175419 -132.934748) (xy 80.217302 -132.914016)
			(xy 80.236314 -132.90042) (xy 80.258376 -132.884423) (xy 80.306202 -132.858301) (xy 80.357259 -132.839252)
			(xy 80.410507 -132.827662) (xy 80.464863 -132.823769) (xy 80.51922 -132.827652) (xy 80.57247 -132.839231)
			(xy 80.623531 -132.858271) (xy 80.671362 -132.884384) (xy 80.71499 -132.917038) (xy 80.753527 -132.955569)
			(xy 80.786187 -132.999192) (xy 80.812307 -133.04702) (xy 80.831354 -133.098078) (xy 80.84294 -133.151327)
			(xy 80.845521 -133.187376) (xy 81.441412 -133.187376) (xy 81.445303 -133.133025) (xy 81.456889 -133.079781)
			(xy 81.475936 -133.028728) (xy 81.502054 -132.980906) (xy 81.534713 -132.937288) (xy 81.573248 -132.898761)
			(xy 81.616873 -132.866111) (xy 81.664701 -132.840003) (xy 81.715757 -132.820967) (xy 81.769004 -132.809391)
			(xy 81.823355 -132.805512) (xy 81.877706 -132.809407) (xy 81.930949 -132.820998) (xy 81.982 -132.840049)
			(xy 82.029821 -132.866171) (xy 82.051906 -132.882132) (xy 82.070918 -132.895728) (xy 82.112801 -132.91646)
			(xy 82.157769 -132.929186) (xy 82.204306 -132.933476) (xy 82.250843 -132.929186) (xy 82.295811 -132.91646)
			(xy 82.337694 -132.895728) (xy 82.356706 -132.882132) (xy 82.378757 -132.866119) (xy 82.426584 -132.839994)
			(xy 82.477643 -132.820941) (xy 82.530893 -132.80935) (xy 82.585251 -132.805455) (xy 82.639611 -132.809336)
			(xy 82.692864 -132.820914) (xy 82.743928 -132.839953) (xy 82.791762 -132.866066) (xy 82.835392 -132.898721)
			(xy 82.873932 -132.937253) (xy 82.906595 -132.980877) (xy 82.932717 -133.028706) (xy 82.951765 -133.079766)
			(xy 82.963354 -133.133018) (xy 82.967245 -133.187376) (xy 82.96336 -133.241735) (xy 82.951779 -133.294988)
			(xy 82.932737 -133.34605) (xy 82.906621 -133.393882) (xy 82.873963 -133.437511) (xy 82.835429 -133.476048)
			(xy 82.791802 -133.508708) (xy 82.743971 -133.534827) (xy 82.69291 -133.553872) (xy 82.639658 -133.565457)
			(xy 82.585299 -133.569345) (xy 82.530941 -133.565457) (xy 82.477689 -133.553872) (xy 82.426628 -133.534826)
			(xy 82.378797 -133.508707) (xy 82.356706 -133.492748) (xy 82.337694 -133.479152) (xy 82.295811 -133.45842)
			(xy 82.250843 -133.445694) (xy 82.204306 -133.441404) (xy 82.157769 -133.445694) (xy 82.112801 -133.45842)
			(xy 82.070918 -133.479152) (xy 82.051906 -133.492748) (xy 82.02978 -133.508655) (xy 81.981957 -133.534771)
			(xy 81.930903 -133.553815) (xy 81.877659 -133.5654) (xy 81.823307 -133.569288) (xy 81.768956 -133.565402)
			(xy 81.715711 -133.553819) (xy 81.664657 -133.534777) (xy 81.616832 -133.508663) (xy 81.573211 -133.476007)
			(xy 81.534682 -133.437476) (xy 81.502028 -133.393854) (xy 81.475916 -133.346028) (xy 81.456876 -133.294973)
			(xy 81.445296 -133.241727) (xy 81.441412 -133.187376) (xy 80.845521 -133.187376) (xy 80.846831 -133.205683)
			(xy 80.842945 -133.26004) (xy 80.831363 -133.31329) (xy 80.812321 -133.364349) (xy 80.786206 -133.412179)
			(xy 80.753549 -133.455806) (xy 80.715016 -133.49434) (xy 80.671391 -133.526998) (xy 80.623562 -133.553115)
			(xy 80.572503 -133.57216) (xy 80.519253 -133.583743) (xy 80.464897 -133.587631) (xy 80.410541 -133.583742)
			(xy 80.357291 -133.572158) (xy 80.306232 -133.553113) (xy 80.258404 -133.526995) (xy 80.236314 -133.511036)
			(xy 80.217302 -133.49744) (xy 80.175419 -133.476708) (xy 80.130451 -133.463982) (xy 80.083914 -133.459692)
			(xy 80.037377 -133.463982) (xy 79.992409 -133.476708) (xy 79.950526 -133.49744) (xy 79.931514 -133.511036)
			(xy 79.909399 -133.526959) (xy 79.861574 -133.553079) (xy 79.810519 -133.572126) (xy 79.757273 -133.583712)
			(xy 79.702919 -133.587602) (xy 79.648565 -133.583718) (xy 79.595318 -133.572136) (xy 79.544261 -133.553095)
			(xy 79.496433 -133.52698) (xy 79.452809 -133.494325) (xy 79.414277 -133.455793) (xy 79.381621 -133.412169)
			(xy 79.355506 -133.364342) (xy 79.336464 -133.313285) (xy 79.324883 -133.260037) (xy 79.320997 -133.205683)
			(xy 78.597559 -133.205683) (xy 78.5899 -133.2409) (xy 78.570855 -133.291967) (xy 78.544735 -133.339803)
			(xy 78.512073 -133.383436) (xy 78.473533 -133.421975) (xy 78.429901 -133.454637) (xy 78.382064 -133.480756)
			(xy 78.330997 -133.499801) (xy 78.277739 -133.511384) (xy 78.223374 -133.515269) (xy 78.16901 -133.511376)
			(xy 78.115754 -133.499786) (xy 78.064689 -133.480735) (xy 78.016856 -133.454609) (xy 77.994764 -133.438646)
			(xy 77.975752 -133.42505) (xy 77.933869 -133.404318) (xy 77.888901 -133.391592) (xy 77.842364 -133.387302)
			(xy 77.795827 -133.391592) (xy 77.750859 -133.404318) (xy 77.708976 -133.42505) (xy 77.689964 -133.438646)
			(xy 77.667841 -133.454552) (xy 77.62002 -133.480662) (xy 77.56897 -133.4997) (xy 77.515731 -133.51128)
			(xy 77.461385 -133.515165) (xy 77.407039 -133.511275) (xy 77.3538 -133.499692) (xy 77.302752 -133.480649)
			(xy 77.254933 -133.454535) (xy 77.211318 -133.421882) (xy 77.172793 -133.383353) (xy 77.140144 -133.339735)
			(xy 77.114035 -133.291913) (xy 77.094998 -133.240863) (xy 77.083419 -133.187623) (xy 77.079535 -133.133277)
			(xy 76.716322 -133.133277) (xy 76.714428 -133.159756) (xy 76.702844 -133.213004) (xy 76.683799 -133.264062)
			(xy 76.657682 -133.311889) (xy 76.625023 -133.355513) (xy 76.586489 -133.394044) (xy 76.542863 -133.426699)
			(xy 76.495033 -133.452812) (xy 76.443974 -133.471853) (xy 76.390725 -133.483433) (xy 76.33637 -133.487316)
			(xy 76.282015 -133.483424) (xy 76.228768 -133.471836) (xy 76.177711 -133.452787) (xy 76.129886 -133.426666)
			(xy 76.107798 -133.410706) (xy 76.088786 -133.39711) (xy 76.046903 -133.376378) (xy 76.001935 -133.363652)
			(xy 75.955398 -133.359362) (xy 75.908861 -133.363652) (xy 75.863893 -133.376378) (xy 75.82201 -133.39711)
			(xy 75.802998 -133.410706) (xy 75.780912 -133.426668) (xy 75.733086 -133.452789) (xy 75.68203 -133.471837)
			(xy 75.628783 -133.483425) (xy 75.574428 -133.487317) (xy 75.520073 -133.483433) (xy 75.466824 -133.471853)
			(xy 75.415765 -133.452812) (xy 75.367936 -133.426699) (xy 75.32431 -133.394044) (xy 75.285775 -133.355513)
			(xy 75.253117 -133.311889) (xy 75.227 -133.264062) (xy 75.207955 -133.213004) (xy 75.196371 -133.159756)
			(xy 75.192483 -133.105401) (xy 74.686579 -133.105401) (xy 74.690543 -133.123619) (xy 74.694435 -133.177975)
			(xy 74.69055 -133.232331) (xy 74.67897 -133.285582) (xy 74.659929 -133.336642) (xy 74.633815 -133.384472)
			(xy 74.601159 -133.428099) (xy 74.562628 -133.466635) (xy 74.519004 -133.499295) (xy 74.471176 -133.525413)
			(xy 74.420117 -133.544459) (xy 74.366868 -133.556045) (xy 74.312512 -133.559935) (xy 74.258156 -133.556049)
			(xy 74.204906 -133.544466) (xy 74.153846 -133.525423) (xy 74.106017 -133.499308) (xy 74.083926 -133.48335)
			(xy 74.064914 -133.469754) (xy 74.023031 -133.449022) (xy 73.978063 -133.436296) (xy 73.931526 -133.432006)
			(xy 73.884989 -133.436296) (xy 73.840021 -133.449022) (xy 73.798138 -133.469754) (xy 73.779126 -133.48335)
			(xy 73.756998 -133.499256) (xy 73.709173 -133.525375) (xy 73.658118 -133.544422) (xy 73.604871 -133.556008)
			(xy 73.550518 -133.559898) (xy 73.496164 -133.556013) (xy 73.442916 -133.544432) (xy 73.391859 -133.52539)
			(xy 73.344032 -133.499275) (xy 73.300408 -133.466618) (xy 73.261877 -133.428086) (xy 73.229221 -133.384462)
			(xy 73.203107 -133.336634) (xy 73.184066 -133.285577) (xy 73.172486 -133.232329) (xy 73.168602 -133.177975)
			(xy 28.884372 -133.177975) (xy 28.884372 -135.321471) (xy 73.168606 -135.321471) (xy 73.172498 -135.267118)
			(xy 73.184086 -135.213873) (xy 73.203134 -135.162819) (xy 73.229255 -135.114995) (xy 73.261916 -135.071376)
			(xy 73.300452 -135.03285) (xy 73.34408 -135.0002) (xy 73.39191 -134.974092) (xy 73.442969 -134.955058)
			(xy 73.496218 -134.943484) (xy 73.550572 -134.939606) (xy 73.604924 -134.943504) (xy 73.658168 -134.955098)
			(xy 73.70922 -134.974152) (xy 73.757041 -135.000278) (xy 73.779126 -135.01624) (xy 73.798138 -135.029836)
			(xy 73.840021 -135.050568) (xy 73.884989 -135.063294) (xy 73.931526 -135.067584) (xy 73.978063 -135.063294)
			(xy 74.023031 -135.050568) (xy 74.064914 -135.029836) (xy 74.083926 -135.01624) (xy 74.105969 -135.000218)
			(xy 74.153795 -134.974095) (xy 74.204853 -134.955044) (xy 74.258102 -134.943454) (xy 74.312458 -134.939561)
			(xy 74.366815 -134.943442) (xy 74.420067 -134.955021) (xy 74.471128 -134.97406) (xy 74.518961 -135.000172)
			(xy 74.56259 -135.032826) (xy 74.601128 -135.071357) (xy 74.63379 -135.11498) (xy 74.659911 -135.162807)
			(xy 74.678959 -135.213865) (xy 74.686583 -135.248898) (xy 75.192488 -135.248898) (xy 75.196376 -135.194543)
			(xy 75.20796 -135.141296) (xy 75.227005 -135.090239) (xy 75.253122 -135.042412) (xy 75.28578 -134.99879)
			(xy 75.324314 -134.960259) (xy 75.367939 -134.927605) (xy 75.415768 -134.901491) (xy 75.466826 -134.882451)
			(xy 75.520075 -134.870871) (xy 75.574429 -134.866988) (xy 75.628783 -134.87088) (xy 75.68203 -134.882468)
			(xy 75.733085 -134.901516) (xy 75.78091 -134.927636) (xy 75.802998 -134.943596) (xy 75.82201 -134.957192)
			(xy 75.863893 -134.977924) (xy 75.908861 -134.99065) (xy 75.955398 -134.99494) (xy 76.001935 -134.99065)
			(xy 76.046903 -134.977924) (xy 76.088786 -134.957192) (xy 76.107798 -134.943596) (xy 76.129882 -134.92763)
			(xy 76.177708 -134.901509) (xy 76.228765 -134.88246) (xy 76.282013 -134.870871) (xy 76.336368 -134.866979)
			(xy 76.390724 -134.870862) (xy 76.443974 -134.882442) (xy 76.495034 -134.901483) (xy 76.542864 -134.927596)
			(xy 76.586491 -134.960251) (xy 76.625026 -134.998783) (xy 76.657685 -135.042407) (xy 76.683803 -135.090235)
			(xy 76.702848 -135.141293) (xy 76.714433 -135.194542) (xy 76.718321 -135.248898) (xy 76.716327 -135.276774)
			(xy 77.07954 -135.276774) (xy 77.083431 -135.222429) (xy 77.095016 -135.169191) (xy 77.11406 -135.118144)
			(xy 77.140175 -135.070327) (xy 77.172829 -135.026713) (xy 77.211358 -134.98819) (xy 77.254977 -134.955542)
			(xy 77.302799 -134.929435) (xy 77.353849 -134.910399) (xy 77.407089 -134.898822) (xy 77.461434 -134.89494)
			(xy 77.515779 -134.898832) (xy 77.569016 -134.910418) (xy 77.620063 -134.929463) (xy 77.66788 -134.955579)
			(xy 77.689964 -134.971536) (xy 77.708976 -134.985132) (xy 77.750859 -135.005864) (xy 77.795827 -135.01859)
			(xy 77.842364 -135.02288) (xy 77.888901 -135.01859) (xy 77.933869 -135.005864) (xy 77.975752 -134.985132)
			(xy 77.994764 -134.971536) (xy 78.016812 -134.955514) (xy 78.064642 -134.929381) (xy 78.115705 -134.910323)
			(xy 78.168961 -134.898726) (xy 78.223325 -134.894827) (xy 78.277691 -134.898705) (xy 78.330951 -134.910281)
			(xy 78.382021 -134.929319) (xy 78.429862 -134.955433) (xy 78.473499 -134.988089) (xy 78.512044 -135.026624)
			(xy 78.544713 -135.070253) (xy 78.570839 -135.118086) (xy 78.589891 -135.169152) (xy 78.601481 -135.222409)
			(xy 78.605373 -135.276774) (xy 78.601489 -135.331139) (xy 78.597565 -135.34918) (xy 79.321002 -135.34918)
			(xy 79.324893 -135.294827) (xy 79.336479 -135.241581) (xy 79.355526 -135.190526) (xy 79.381645 -135.142702)
			(xy 79.414305 -135.099082) (xy 79.45284 -135.060555) (xy 79.496467 -135.027904) (xy 79.544296 -135.001794)
			(xy 79.595355 -134.982758) (xy 79.648603 -134.971182) (xy 79.702956 -134.967302) (xy 79.757309 -134.971198)
			(xy 79.810553 -134.98279) (xy 79.861606 -135.001841) (xy 79.909428 -135.027965) (xy 79.931514 -135.043926)
			(xy 79.950526 -135.057522) (xy 79.992409 -135.078254) (xy 80.037377 -135.09098) (xy 80.083914 -135.09527)
			(xy 80.130451 -135.09098) (xy 80.175419 -135.078254) (xy 80.217302 -135.057522) (xy 80.236314 -135.043926)
			(xy 80.25837 -135.027921) (xy 80.306197 -135.001798) (xy 80.357254 -134.982748) (xy 80.410503 -134.971158)
			(xy 80.46486 -134.967265) (xy 80.519217 -134.971147) (xy 80.572468 -134.982725) (xy 80.62353 -135.001765)
			(xy 80.671362 -135.027878) (xy 80.714991 -135.060532) (xy 80.753528 -135.099063) (xy 80.786189 -135.142687)
			(xy 80.81231 -135.190515) (xy 80.831358 -135.241573) (xy 80.842945 -135.294823) (xy 80.845525 -135.330872)
			(xy 81.441417 -135.330872) (xy 81.445308 -135.276522) (xy 81.456895 -135.223279) (xy 81.475942 -135.172227)
			(xy 81.50206 -135.124405) (xy 81.534719 -135.080788) (xy 81.573253 -135.042263) (xy 81.616878 -135.009614)
			(xy 81.664706 -134.983506) (xy 81.715762 -134.964471) (xy 81.769008 -134.952896) (xy 81.823359 -134.949017)
			(xy 81.877709 -134.952913) (xy 81.930951 -134.964504) (xy 81.982002 -134.983555) (xy 82.029821 -135.009677)
			(xy 82.051906 -135.025638) (xy 82.070918 -135.039234) (xy 82.112801 -135.059966) (xy 82.157769 -135.072692)
			(xy 82.204306 -135.076982) (xy 82.250843 -135.072692) (xy 82.295811 -135.059966) (xy 82.337694 -135.039234)
			(xy 82.356706 -135.025638) (xy 82.378751 -135.009617) (xy 82.426579 -134.983491) (xy 82.477638 -134.964438)
			(xy 82.530889 -134.952846) (xy 82.585248 -134.94895) (xy 82.639608 -134.952831) (xy 82.692862 -134.964408)
			(xy 82.743926 -134.983447) (xy 82.791761 -135.00956) (xy 82.835393 -135.042215) (xy 82.873933 -135.080747)
			(xy 82.906597 -135.124372) (xy 82.932719 -135.172201) (xy 82.951769 -135.223262) (xy 82.963358 -135.276513)
			(xy 82.96725 -135.330872) (xy 82.963366 -135.385232) (xy 82.951785 -135.438485) (xy 82.932742 -135.489549)
			(xy 82.906627 -135.537382) (xy 82.873969 -135.581011) (xy 82.835435 -135.619549) (xy 82.791808 -135.65221)
			(xy 82.743976 -135.67833) (xy 82.692915 -135.697376) (xy 82.639662 -135.708961) (xy 82.585303 -135.71285)
			(xy 82.530944 -135.708962) (xy 82.477691 -135.697378) (xy 82.426629 -135.678332) (xy 82.378797 -135.652213)
			(xy 82.356706 -135.636254) (xy 82.337694 -135.622658) (xy 82.295811 -135.601926) (xy 82.250843 -135.5892)
			(xy 82.204306 -135.58491) (xy 82.157769 -135.5892) (xy 82.112801 -135.601926) (xy 82.070918 -135.622658)
			(xy 82.051906 -135.636254) (xy 82.029775 -135.652152) (xy 81.981951 -135.678268) (xy 81.930898 -135.697312)
			(xy 81.877654 -135.708895) (xy 81.823304 -135.712783) (xy 81.768953 -135.708896) (xy 81.715709 -135.697314)
			(xy 81.664656 -135.678271) (xy 81.616832 -135.652157) (xy 81.573212 -135.619501) (xy 81.534683 -135.58097)
			(xy 81.502031 -135.537348) (xy 81.475919 -135.489523) (xy 81.456879 -135.438468) (xy 81.4453 -135.385223)
			(xy 81.441417 -135.330872) (xy 80.845525 -135.330872) (xy 80.846835 -135.34918) (xy 80.84295 -135.403537)
			(xy 80.831369 -135.456788) (xy 80.812327 -135.507848) (xy 80.786212 -135.555679) (xy 80.753555 -135.599306)
			(xy 80.715022 -135.637841) (xy 80.671396 -135.6705) (xy 80.623567 -135.696618) (xy 80.572507 -135.715663)
			(xy 80.519257 -135.727247) (xy 80.4649 -135.731135) (xy 80.410543 -135.727248) (xy 80.357293 -135.715663)
			(xy 80.306234 -135.696618) (xy 80.258404 -135.670501) (xy 80.236314 -135.654542) (xy 80.217302 -135.640946)
			(xy 80.175419 -135.620214) (xy 80.130451 -135.607488) (xy 80.083914 -135.603198) (xy 80.037377 -135.607488)
			(xy 79.992409 -135.620214) (xy 79.950526 -135.640946) (xy 79.931514 -135.654542) (xy 79.909394 -135.670457)
			(xy 79.861569 -135.696576) (xy 79.810514 -135.715622) (xy 79.757268 -135.727208) (xy 79.702916 -135.731098)
			(xy 79.648562 -135.727212) (xy 79.595316 -135.715631) (xy 79.544259 -135.696589) (xy 79.496433 -135.670474)
			(xy 79.45281 -135.637819) (xy 79.414278 -135.599287) (xy 79.381623 -135.555663) (xy 79.355509 -135.507836)
			(xy 79.336468 -135.45678) (xy 79.324887 -135.403533) (xy 79.321002 -135.34918) (xy 78.597565 -135.34918)
			(xy 78.589906 -135.384397) (xy 78.570861 -135.435465) (xy 78.544741 -135.483303) (xy 78.512079 -135.526936)
			(xy 78.473539 -135.565476) (xy 78.429907 -135.598139) (xy 78.382069 -135.624259) (xy 78.331002 -135.643304)
			(xy 78.277743 -135.654888) (xy 78.223378 -135.658773) (xy 78.169013 -135.654882) (xy 78.115756 -135.643292)
			(xy 78.06469 -135.62424) (xy 78.016856 -135.598115) (xy 77.994764 -135.582152) (xy 77.975752 -135.568556)
			(xy 77.933869 -135.547824) (xy 77.888901 -135.535098) (xy 77.842364 -135.530808) (xy 77.795827 -135.535098)
			(xy 77.750859 -135.547824) (xy 77.708976 -135.568556) (xy 77.689964 -135.582152) (xy 77.667835 -135.59805)
			(xy 77.620015 -135.624159) (xy 77.568966 -135.643197) (xy 77.515726 -135.654776) (xy 77.461381 -135.65866)
			(xy 77.407036 -135.65477) (xy 77.353798 -135.643186) (xy 77.302751 -135.624143) (xy 77.254933 -135.598029)
			(xy 77.211318 -135.565376) (xy 77.172795 -135.526848) (xy 77.140146 -135.483229) (xy 77.114038 -135.435408)
			(xy 77.095001 -135.384358) (xy 77.083423 -135.331119) (xy 77.07954 -135.276774) (xy 76.716327 -135.276774)
			(xy 76.714433 -135.303253) (xy 76.70285 -135.356502) (xy 76.683805 -135.407561) (xy 76.657688 -135.455389)
			(xy 76.625029 -135.499013) (xy 76.586495 -135.537545) (xy 76.542868 -135.570201) (xy 76.495039 -135.596315)
			(xy 76.443979 -135.615356) (xy 76.390729 -135.626937) (xy 76.336373 -135.630821) (xy 76.282018 -135.626929)
			(xy 76.22877 -135.615341) (xy 76.177713 -135.596293) (xy 76.129887 -135.570172) (xy 76.107798 -135.554212)
			(xy 76.088786 -135.540616) (xy 76.046903 -135.519884) (xy 76.001935 -135.507158) (xy 75.955398 -135.502868)
			(xy 75.908861 -135.507158) (xy 75.863893 -135.519884) (xy 75.82201 -135.540616) (xy 75.802998 -135.554212)
			(xy 75.780906 -135.570166) (xy 75.733081 -135.596286) (xy 75.682025 -135.615334) (xy 75.628778 -135.626921)
			(xy 75.574425 -135.630812) (xy 75.52007 -135.626928) (xy 75.466822 -135.615348) (xy 75.415764 -135.596307)
			(xy 75.367935 -135.570193) (xy 75.32431 -135.537538) (xy 75.285777 -135.499007) (xy 75.253119 -135.455383)
			(xy 75.227003 -135.407557) (xy 75.207959 -135.356499) (xy 75.196375 -135.303252) (xy 75.192488 -135.248898)
			(xy 74.686583 -135.248898) (xy 74.690548 -135.267115) (xy 74.694439 -135.321471) (xy 74.690556 -135.375828)
			(xy 74.678976 -135.429079) (xy 74.659935 -135.48014) (xy 74.633821 -135.527972) (xy 74.601165 -135.5716)
			(xy 74.562633 -135.610136) (xy 74.519009 -135.642797) (xy 74.471181 -135.668916) (xy 74.420122 -135.687963)
			(xy 74.366872 -135.699549) (xy 74.312516 -135.703439) (xy 74.258159 -135.699554) (xy 74.204908 -135.687972)
			(xy 74.153848 -135.668929) (xy 74.106017 -135.642814) (xy 74.083926 -135.626856) (xy 74.064914 -135.61326)
			(xy 74.023031 -135.592528) (xy 73.978063 -135.579802) (xy 73.931526 -135.575512) (xy 73.884989 -135.579802)
			(xy 73.840021 -135.592528) (xy 73.798138 -135.61326) (xy 73.779126 -135.626856) (xy 73.756992 -135.642753)
			(xy 73.709168 -135.668872) (xy 73.658113 -135.687918) (xy 73.604867 -135.699504) (xy 73.550514 -135.703394)
			(xy 73.496161 -135.699508) (xy 73.442914 -135.687926) (xy 73.391858 -135.668884) (xy 73.344031 -135.642769)
			(xy 73.300409 -135.610112) (xy 73.261878 -135.57158) (xy 73.229223 -135.527956) (xy 73.20311 -135.480129)
			(xy 73.18407 -135.429072) (xy 73.17249 -135.375824) (xy 73.168606 -135.321471) (xy 28.884372 -135.321471)
			(xy 28.884372 -140.254228) (xy 39.818818 -140.254228) (xy 39.819523 -140.195605) (xy 39.828091 -140.078667)
			(xy 39.844787 -139.962611) (xy 39.86953 -139.848001) (xy 39.902199 -139.735393) (xy 39.942635 -139.625335)
			(xy 39.990642 -139.518363) (xy 40.045986 -139.414996) (xy 40.108399 -139.315737) (xy 40.177577 -139.221068)
			(xy 40.253183 -139.13145) (xy 40.334851 -139.047318) (xy 40.422182 -138.969081) (xy 40.514753 -138.89712)
			(xy 40.612113 -138.831784) (xy 40.713789 -138.773392) (xy 40.819288 -138.722226) (xy 40.928095 -138.678537)
			(xy 41.039682 -138.642535) (xy 41.153506 -138.614397) (xy 41.269014 -138.594259) (xy 41.385645 -138.582218)
			(xy 41.502832 -138.578334) (xy 41.620004 -138.582625) (xy 41.736593 -138.595071) (xy 41.85203 -138.615611)
			(xy 41.965756 -138.644144) (xy 42.077217 -138.680533) (xy 42.185872 -138.724601) (xy 42.291192 -138.776133)
			(xy 42.392665 -138.834878) (xy 42.489797 -138.900552) (xy 42.501941 -138.91006) (xy 63.647831 -138.91006)
			(xy 63.651866 -138.834356) (xy 63.663925 -138.759511) (xy 63.683871 -138.68637) (xy 63.711478 -138.615765)
			(xy 63.746434 -138.548494) (xy 63.788342 -138.485319) (xy 63.836728 -138.426957) (xy 63.891044 -138.374069)
			(xy 63.950673 -138.327254) (xy 64.014941 -138.287042) (xy 64.083118 -138.25389) (xy 64.154434 -138.228172)
			(xy 64.228079 -138.21018) (xy 64.303219 -138.200118) (xy 64.379003 -138.198099) (xy 64.454573 -138.204148)
			(xy 64.529071 -138.218195) (xy 64.601654 -138.240081) (xy 64.6715 -138.269558) (xy 64.737817 -138.306293)
			(xy 64.799853 -138.349868) (xy 64.856906 -138.39979) (xy 64.90833 -138.455494) (xy 64.953541 -138.516349)
			(xy 64.992028 -138.581664) (xy 65.023354 -138.6507) (xy 65.047164 -138.722675) (xy 65.063189 -138.796773)
			(xy 65.071248 -138.872154) (xy 65.071752 -138.91006) (xy 66.187831 -138.91006) (xy 66.191866 -138.834356)
			(xy 66.203925 -138.759511) (xy 66.223871 -138.68637) (xy 66.251478 -138.615765) (xy 66.286434 -138.548494)
			(xy 66.328342 -138.485319) (xy 66.376728 -138.426957) (xy 66.431044 -138.374069) (xy 66.490673 -138.327254)
			(xy 66.554941 -138.287042) (xy 66.623118 -138.25389) (xy 66.694434 -138.228172) (xy 66.768079 -138.21018)
			(xy 66.843219 -138.200118) (xy 66.919003 -138.198099) (xy 66.994573 -138.204148) (xy 67.069071 -138.218195)
			(xy 67.141654 -138.240081) (xy 67.2115 -138.269558) (xy 67.277817 -138.306293) (xy 67.339853 -138.349868)
			(xy 67.396906 -138.39979) (xy 67.44833 -138.455494) (xy 67.493541 -138.516349) (xy 67.532028 -138.581664)
			(xy 67.563354 -138.6507) (xy 67.587164 -138.722675) (xy 67.603189 -138.796773) (xy 67.611248 -138.872154)
			(xy 67.611752 -138.91006) (xy 68.727831 -138.91006) (xy 68.731866 -138.834356) (xy 68.743925 -138.759511)
			(xy 68.763871 -138.68637) (xy 68.791478 -138.615765) (xy 68.826434 -138.548494) (xy 68.868342 -138.485319)
			(xy 68.916728 -138.426957) (xy 68.971044 -138.374069) (xy 69.030673 -138.327254) (xy 69.094941 -138.287042)
			(xy 69.163118 -138.25389) (xy 69.234434 -138.228172) (xy 69.308079 -138.21018) (xy 69.383219 -138.200118)
			(xy 69.459003 -138.198099) (xy 69.534573 -138.204148) (xy 69.609071 -138.218195) (xy 69.681654 -138.240081)
			(xy 69.7515 -138.269558) (xy 69.817817 -138.306293) (xy 69.879853 -138.349868) (xy 69.936906 -138.39979)
			(xy 69.98833 -138.455494) (xy 70.033541 -138.516349) (xy 70.072028 -138.581664) (xy 70.103354 -138.6507)
			(xy 70.127164 -138.722675) (xy 70.143189 -138.796773) (xy 70.151248 -138.872154) (xy 70.151752 -138.91006)
			(xy 71.267831 -138.91006) (xy 71.271866 -138.834356) (xy 71.283925 -138.759511) (xy 71.303871 -138.68637)
			(xy 71.331478 -138.615765) (xy 71.366434 -138.548494) (xy 71.408342 -138.485319) (xy 71.456728 -138.426957)
			(xy 71.511044 -138.374069) (xy 71.570673 -138.327254) (xy 71.634941 -138.287042) (xy 71.703118 -138.25389)
			(xy 71.774434 -138.228172) (xy 71.848079 -138.21018) (xy 71.923219 -138.200118) (xy 71.999003 -138.198099)
			(xy 72.074573 -138.204148) (xy 72.149071 -138.218195) (xy 72.221654 -138.240081) (xy 72.2915 -138.269558)
			(xy 72.357817 -138.306293) (xy 72.419853 -138.349868) (xy 72.476906 -138.39979) (xy 72.52833 -138.455494)
			(xy 72.573541 -138.516349) (xy 72.612028 -138.581664) (xy 72.643354 -138.6507) (xy 72.667164 -138.722675)
			(xy 72.683189 -138.796773) (xy 72.691248 -138.872154) (xy 72.691752 -138.91006) (xy 73.807831 -138.91006)
			(xy 73.811866 -138.834356) (xy 73.823925 -138.759511) (xy 73.843871 -138.68637) (xy 73.871478 -138.615765)
			(xy 73.906434 -138.548494) (xy 73.948342 -138.485319) (xy 73.996728 -138.426957) (xy 74.051044 -138.374069)
			(xy 74.110673 -138.327254) (xy 74.174941 -138.287042) (xy 74.243118 -138.25389) (xy 74.314434 -138.228172)
			(xy 74.388079 -138.21018) (xy 74.463219 -138.200118) (xy 74.539003 -138.198099) (xy 74.614573 -138.204148)
			(xy 74.689071 -138.218195) (xy 74.761654 -138.240081) (xy 74.8315 -138.269558) (xy 74.897817 -138.306293)
			(xy 74.959853 -138.349868) (xy 75.016906 -138.39979) (xy 75.06833 -138.455494) (xy 75.113541 -138.516349)
			(xy 75.152028 -138.581664) (xy 75.183354 -138.6507) (xy 75.207164 -138.722675) (xy 75.223189 -138.796773)
			(xy 75.231248 -138.872154) (xy 75.231752 -138.91006) (xy 76.347831 -138.91006) (xy 76.351866 -138.834356)
			(xy 76.363925 -138.759511) (xy 76.383871 -138.68637) (xy 76.411478 -138.615765) (xy 76.446434 -138.548494)
			(xy 76.488342 -138.485319) (xy 76.536728 -138.426957) (xy 76.591044 -138.374069) (xy 76.650673 -138.327254)
			(xy 76.714941 -138.287042) (xy 76.783118 -138.25389) (xy 76.854434 -138.228172) (xy 76.928079 -138.21018)
			(xy 77.003219 -138.200118) (xy 77.079003 -138.198099) (xy 77.154573 -138.204148) (xy 77.229071 -138.218195)
			(xy 77.301654 -138.240081) (xy 77.3715 -138.269558) (xy 77.437817 -138.306293) (xy 77.499853 -138.349868)
			(xy 77.556906 -138.39979) (xy 77.60833 -138.455494) (xy 77.653541 -138.516349) (xy 77.692028 -138.581664)
			(xy 77.723354 -138.6507) (xy 77.747164 -138.722675) (xy 77.763189 -138.796773) (xy 77.771248 -138.872154)
			(xy 77.771752 -138.91006) (xy 78.887831 -138.91006) (xy 78.891866 -138.834356) (xy 78.903925 -138.759511)
			(xy 78.923871 -138.68637) (xy 78.951478 -138.615765) (xy 78.986434 -138.548494) (xy 79.028342 -138.485319)
			(xy 79.076728 -138.426957) (xy 79.131044 -138.374069) (xy 79.190673 -138.327254) (xy 79.254941 -138.287042)
			(xy 79.323118 -138.25389) (xy 79.394434 -138.228172) (xy 79.468079 -138.21018) (xy 79.543219 -138.200118)
			(xy 79.619003 -138.198099) (xy 79.694573 -138.204148) (xy 79.769071 -138.218195) (xy 79.841654 -138.240081)
			(xy 79.9115 -138.269558) (xy 79.977817 -138.306293) (xy 80.039853 -138.349868) (xy 80.096906 -138.39979)
			(xy 80.14833 -138.455494) (xy 80.193541 -138.516349) (xy 80.232028 -138.581664) (xy 80.263354 -138.6507)
			(xy 80.287164 -138.722675) (xy 80.303189 -138.796773) (xy 80.311248 -138.872154) (xy 80.311752 -138.91006)
			(xy 81.427831 -138.91006) (xy 81.431866 -138.834356) (xy 81.443925 -138.759511) (xy 81.463871 -138.68637)
			(xy 81.491478 -138.615765) (xy 81.526434 -138.548494) (xy 81.568342 -138.485319) (xy 81.616728 -138.426957)
			(xy 81.671044 -138.374069) (xy 81.730673 -138.327254) (xy 81.794941 -138.287042) (xy 81.863118 -138.25389)
			(xy 81.934434 -138.228172) (xy 82.008079 -138.21018) (xy 82.083219 -138.200118) (xy 82.159003 -138.198099)
			(xy 82.234573 -138.204148) (xy 82.309071 -138.218195) (xy 82.381654 -138.240081) (xy 82.4515 -138.269558)
			(xy 82.517817 -138.306293) (xy 82.579853 -138.349868) (xy 82.636906 -138.39979) (xy 82.68833 -138.455494)
			(xy 82.733541 -138.516349) (xy 82.772028 -138.581664) (xy 82.803354 -138.6507) (xy 82.827164 -138.722675)
			(xy 82.843189 -138.796773) (xy 82.851248 -138.872154) (xy 82.851752 -138.91006) (xy 82.851248 -138.947966)
			(xy 82.843189 -139.023347) (xy 82.827164 -139.097445) (xy 82.803354 -139.16942) (xy 82.772028 -139.238456)
			(xy 82.733541 -139.303771) (xy 82.68833 -139.364626) (xy 82.636906 -139.42033) (xy 82.579853 -139.470252)
			(xy 82.517817 -139.513827) (xy 82.4515 -139.550562) (xy 82.381654 -139.580039) (xy 82.309071 -139.601925)
			(xy 82.234573 -139.615972) (xy 82.159003 -139.622021) (xy 82.083219 -139.620002) (xy 82.008079 -139.60994)
			(xy 81.934434 -139.591948) (xy 81.863118 -139.56623) (xy 81.794941 -139.533078) (xy 81.730673 -139.492866)
			(xy 81.671044 -139.446051) (xy 81.616728 -139.393163) (xy 81.568342 -139.334801) (xy 81.526434 -139.271626)
			(xy 81.491478 -139.204355) (xy 81.463871 -139.13375) (xy 81.443925 -139.060609) (xy 81.431866 -138.985764)
			(xy 81.427831 -138.91006) (xy 80.311752 -138.91006) (xy 80.311248 -138.947966) (xy 80.303189 -139.023347)
			(xy 80.287164 -139.097445) (xy 80.263354 -139.16942) (xy 80.232028 -139.238456) (xy 80.193541 -139.303771)
			(xy 80.14833 -139.364626) (xy 80.096906 -139.42033) (xy 80.039853 -139.470252) (xy 79.977817 -139.513827)
			(xy 79.9115 -139.550562) (xy 79.841654 -139.580039) (xy 79.769071 -139.601925) (xy 79.694573 -139.615972)
			(xy 79.619003 -139.622021) (xy 79.543219 -139.620002) (xy 79.468079 -139.60994) (xy 79.394434 -139.591948)
			(xy 79.323118 -139.56623) (xy 79.254941 -139.533078) (xy 79.190673 -139.492866) (xy 79.131044 -139.446051)
			(xy 79.076728 -139.393163) (xy 79.028342 -139.334801) (xy 78.986434 -139.271626) (xy 78.951478 -139.204355)
			(xy 78.923871 -139.13375) (xy 78.903925 -139.060609) (xy 78.891866 -138.985764) (xy 78.887831 -138.91006)
			(xy 77.771752 -138.91006) (xy 77.771248 -138.947966) (xy 77.763189 -139.023347) (xy 77.747164 -139.097445)
			(xy 77.723354 -139.16942) (xy 77.692028 -139.238456) (xy 77.653541 -139.303771) (xy 77.60833 -139.364626)
			(xy 77.556906 -139.42033) (xy 77.499853 -139.470252) (xy 77.437817 -139.513827) (xy 77.3715 -139.550562)
			(xy 77.301654 -139.580039) (xy 77.229071 -139.601925) (xy 77.154573 -139.615972) (xy 77.079003 -139.622021)
			(xy 77.003219 -139.620002) (xy 76.928079 -139.60994) (xy 76.854434 -139.591948) (xy 76.783118 -139.56623)
			(xy 76.714941 -139.533078) (xy 76.650673 -139.492866) (xy 76.591044 -139.446051) (xy 76.536728 -139.393163)
			(xy 76.488342 -139.334801) (xy 76.446434 -139.271626) (xy 76.411478 -139.204355) (xy 76.383871 -139.13375)
			(xy 76.363925 -139.060609) (xy 76.351866 -138.985764) (xy 76.347831 -138.91006) (xy 75.231752 -138.91006)
			(xy 75.231248 -138.947966) (xy 75.223189 -139.023347) (xy 75.207164 -139.097445) (xy 75.183354 -139.16942)
			(xy 75.152028 -139.238456) (xy 75.113541 -139.303771) (xy 75.06833 -139.364626) (xy 75.016906 -139.42033)
			(xy 74.959853 -139.470252) (xy 74.897817 -139.513827) (xy 74.8315 -139.550562) (xy 74.761654 -139.580039)
			(xy 74.689071 -139.601925) (xy 74.614573 -139.615972) (xy 74.539003 -139.622021) (xy 74.463219 -139.620002)
			(xy 74.388079 -139.60994) (xy 74.314434 -139.591948) (xy 74.243118 -139.56623) (xy 74.174941 -139.533078)
			(xy 74.110673 -139.492866) (xy 74.051044 -139.446051) (xy 73.996728 -139.393163) (xy 73.948342 -139.334801)
			(xy 73.906434 -139.271626) (xy 73.871478 -139.204355) (xy 73.843871 -139.13375) (xy 73.823925 -139.060609)
			(xy 73.811866 -138.985764) (xy 73.807831 -138.91006) (xy 72.691752 -138.91006) (xy 72.691248 -138.947966)
			(xy 72.683189 -139.023347) (xy 72.667164 -139.097445) (xy 72.643354 -139.16942) (xy 72.612028 -139.238456)
			(xy 72.573541 -139.303771) (xy 72.52833 -139.364626) (xy 72.476906 -139.42033) (xy 72.419853 -139.470252)
			(xy 72.357817 -139.513827) (xy 72.2915 -139.550562) (xy 72.221654 -139.580039) (xy 72.149071 -139.601925)
			(xy 72.074573 -139.615972) (xy 71.999003 -139.622021) (xy 71.923219 -139.620002) (xy 71.848079 -139.60994)
			(xy 71.774434 -139.591948) (xy 71.703118 -139.56623) (xy 71.634941 -139.533078) (xy 71.570673 -139.492866)
			(xy 71.511044 -139.446051) (xy 71.456728 -139.393163) (xy 71.408342 -139.334801) (xy 71.366434 -139.271626)
			(xy 71.331478 -139.204355) (xy 71.303871 -139.13375) (xy 71.283925 -139.060609) (xy 71.271866 -138.985764)
			(xy 71.267831 -138.91006) (xy 70.151752 -138.91006) (xy 70.151248 -138.947966) (xy 70.143189 -139.023347)
			(xy 70.127164 -139.097445) (xy 70.103354 -139.16942) (xy 70.072028 -139.238456) (xy 70.033541 -139.303771)
			(xy 69.98833 -139.364626) (xy 69.936906 -139.42033) (xy 69.879853 -139.470252) (xy 69.817817 -139.513827)
			(xy 69.7515 -139.550562) (xy 69.681654 -139.580039) (xy 69.609071 -139.601925) (xy 69.534573 -139.615972)
			(xy 69.459003 -139.622021) (xy 69.383219 -139.620002) (xy 69.308079 -139.60994) (xy 69.234434 -139.591948)
			(xy 69.163118 -139.56623) (xy 69.094941 -139.533078) (xy 69.030673 -139.492866) (xy 68.971044 -139.446051)
			(xy 68.916728 -139.393163) (xy 68.868342 -139.334801) (xy 68.826434 -139.271626) (xy 68.791478 -139.204355)
			(xy 68.763871 -139.13375) (xy 68.743925 -139.060609) (xy 68.731866 -138.985764) (xy 68.727831 -138.91006)
			(xy 67.611752 -138.91006) (xy 67.611248 -138.947966) (xy 67.603189 -139.023347) (xy 67.587164 -139.097445)
			(xy 67.563354 -139.16942) (xy 67.532028 -139.238456) (xy 67.493541 -139.303771) (xy 67.44833 -139.364626)
			(xy 67.396906 -139.42033) (xy 67.339853 -139.470252) (xy 67.277817 -139.513827) (xy 67.2115 -139.550562)
			(xy 67.141654 -139.580039) (xy 67.069071 -139.601925) (xy 66.994573 -139.615972) (xy 66.919003 -139.622021)
			(xy 66.843219 -139.620002) (xy 66.768079 -139.60994) (xy 66.694434 -139.591948) (xy 66.623118 -139.56623)
			(xy 66.554941 -139.533078) (xy 66.490673 -139.492866) (xy 66.431044 -139.446051) (xy 66.376728 -139.393163)
			(xy 66.328342 -139.334801) (xy 66.286434 -139.271626) (xy 66.251478 -139.204355) (xy 66.223871 -139.13375)
			(xy 66.203925 -139.060609) (xy 66.191866 -138.985764) (xy 66.187831 -138.91006) (xy 65.071752 -138.91006)
			(xy 65.071248 -138.947966) (xy 65.063189 -139.023347) (xy 65.047164 -139.097445) (xy 65.023354 -139.16942)
			(xy 64.992028 -139.238456) (xy 64.953541 -139.303771) (xy 64.90833 -139.364626) (xy 64.856906 -139.42033)
			(xy 64.799853 -139.470252) (xy 64.737817 -139.513827) (xy 64.6715 -139.550562) (xy 64.601654 -139.580039)
			(xy 64.529071 -139.601925) (xy 64.454573 -139.615972) (xy 64.379003 -139.622021) (xy 64.303219 -139.620002)
			(xy 64.228079 -139.60994) (xy 64.154434 -139.591948) (xy 64.083118 -139.56623) (xy 64.014941 -139.533078)
			(xy 63.950673 -139.492866) (xy 63.891044 -139.446051) (xy 63.836728 -139.393163) (xy 63.788342 -139.334801)
			(xy 63.746434 -139.271626) (xy 63.711478 -139.204355) (xy 63.683871 -139.13375) (xy 63.663925 -139.060609)
			(xy 63.651866 -138.985764) (xy 63.647831 -138.91006) (xy 42.501941 -138.91006) (xy 42.582117 -138.972834)
			(xy 42.669176 -139.051374) (xy 42.750551 -139.135789) (xy 42.825845 -139.225669) (xy 42.894694 -139.320578)
			(xy 42.956761 -139.420054) (xy 43.011746 -139.523612) (xy 43.059381 -139.630751) (xy 43.099434 -139.740948)
			(xy 43.131712 -139.853669) (xy 43.156056 -139.968365) (xy 43.172348 -140.084478) (xy 43.18051 -140.201445)
			(xy 43.181016 -140.26007) (xy 43.180861 -140.290833) (xy 43.178574 -140.352316) (xy 43.176444 -140.383006)
			(xy 43.175682 -140.392404) (xy 43.170622 -140.450806) (xy 43.153396 -140.566771) (xy 43.12813 -140.681253)
			(xy 43.094949 -140.793697) (xy 43.054014 -140.903555) (xy 43.005523 -141.010294) (xy 42.949712 -141.113395)
			(xy 42.886853 -141.212356) (xy 42.817252 -141.306696) (xy 42.741246 -141.395958) (xy 42.659204 -141.479706)
			(xy 42.571527 -141.557535) (xy 42.503292 -141.61008) (xy 63.647831 -141.61008) (xy 63.651866 -141.534376)
			(xy 63.663925 -141.459531) (xy 63.683871 -141.38639) (xy 63.711478 -141.315785) (xy 63.746434 -141.248514)
			(xy 63.788342 -141.185339) (xy 63.836728 -141.126977) (xy 63.891044 -141.074089) (xy 63.950673 -141.027274)
			(xy 64.014941 -140.987062) (xy 64.083118 -140.95391) (xy 64.154434 -140.928192) (xy 64.228079 -140.9102)
			(xy 64.303219 -140.900138) (xy 64.379003 -140.898119) (xy 64.454573 -140.904168) (xy 64.529071 -140.918215)
			(xy 64.601654 -140.940101) (xy 64.6715 -140.969578) (xy 64.737817 -141.006313) (xy 64.799853 -141.049888)
			(xy 64.856906 -141.09981) (xy 64.90833 -141.155514) (xy 64.953541 -141.216369) (xy 64.992028 -141.281684)
			(xy 65.023354 -141.35072) (xy 65.047164 -141.422695) (xy 65.063189 -141.496793) (xy 65.071248 -141.572174)
			(xy 65.071752 -141.61008) (xy 66.187831 -141.61008) (xy 66.191866 -141.534376) (xy 66.203925 -141.459531)
			(xy 66.223871 -141.38639) (xy 66.251478 -141.315785) (xy 66.286434 -141.248514) (xy 66.328342 -141.185339)
			(xy 66.376728 -141.126977) (xy 66.431044 -141.074089) (xy 66.490673 -141.027274) (xy 66.554941 -140.987062)
			(xy 66.623118 -140.95391) (xy 66.694434 -140.928192) (xy 66.768079 -140.9102) (xy 66.843219 -140.900138)
			(xy 66.919003 -140.898119) (xy 66.994573 -140.904168) (xy 67.069071 -140.918215) (xy 67.141654 -140.940101)
			(xy 67.2115 -140.969578) (xy 67.277817 -141.006313) (xy 67.339853 -141.049888) (xy 67.396906 -141.09981)
			(xy 67.44833 -141.155514) (xy 67.493541 -141.216369) (xy 67.532028 -141.281684) (xy 67.563354 -141.35072)
			(xy 67.587164 -141.422695) (xy 67.603189 -141.496793) (xy 67.611248 -141.572174) (xy 67.611752 -141.61008)
			(xy 68.727831 -141.61008) (xy 68.731866 -141.534376) (xy 68.743925 -141.459531) (xy 68.763871 -141.38639)
			(xy 68.791478 -141.315785) (xy 68.826434 -141.248514) (xy 68.868342 -141.185339) (xy 68.916728 -141.126977)
			(xy 68.971044 -141.074089) (xy 69.030673 -141.027274) (xy 69.094941 -140.987062) (xy 69.163118 -140.95391)
			(xy 69.234434 -140.928192) (xy 69.308079 -140.9102) (xy 69.383219 -140.900138) (xy 69.459003 -140.898119)
			(xy 69.534573 -140.904168) (xy 69.609071 -140.918215) (xy 69.681654 -140.940101) (xy 69.7515 -140.969578)
			(xy 69.817817 -141.006313) (xy 69.879853 -141.049888) (xy 69.936906 -141.09981) (xy 69.98833 -141.155514)
			(xy 70.033541 -141.216369) (xy 70.072028 -141.281684) (xy 70.103354 -141.35072) (xy 70.127164 -141.422695)
			(xy 70.143189 -141.496793) (xy 70.151248 -141.572174) (xy 70.151752 -141.61008) (xy 71.267831 -141.61008)
			(xy 71.271866 -141.534376) (xy 71.283925 -141.459531) (xy 71.303871 -141.38639) (xy 71.331478 -141.315785)
			(xy 71.366434 -141.248514) (xy 71.408342 -141.185339) (xy 71.456728 -141.126977) (xy 71.511044 -141.074089)
			(xy 71.570673 -141.027274) (xy 71.634941 -140.987062) (xy 71.703118 -140.95391) (xy 71.774434 -140.928192)
			(xy 71.848079 -140.9102) (xy 71.923219 -140.900138) (xy 71.999003 -140.898119) (xy 72.074573 -140.904168)
			(xy 72.149071 -140.918215) (xy 72.221654 -140.940101) (xy 72.2915 -140.969578) (xy 72.357817 -141.006313)
			(xy 72.419853 -141.049888) (xy 72.476906 -141.09981) (xy 72.52833 -141.155514) (xy 72.573541 -141.216369)
			(xy 72.612028 -141.281684) (xy 72.643354 -141.35072) (xy 72.667164 -141.422695) (xy 72.683189 -141.496793)
			(xy 72.691248 -141.572174) (xy 72.691752 -141.61008) (xy 73.807831 -141.61008) (xy 73.811866 -141.534376)
			(xy 73.823925 -141.459531) (xy 73.843871 -141.38639) (xy 73.871478 -141.315785) (xy 73.906434 -141.248514)
			(xy 73.948342 -141.185339) (xy 73.996728 -141.126977) (xy 74.051044 -141.074089) (xy 74.110673 -141.027274)
			(xy 74.174941 -140.987062) (xy 74.243118 -140.95391) (xy 74.314434 -140.928192) (xy 74.388079 -140.9102)
			(xy 74.463219 -140.900138) (xy 74.539003 -140.898119) (xy 74.614573 -140.904168) (xy 74.689071 -140.918215)
			(xy 74.761654 -140.940101) (xy 74.8315 -140.969578) (xy 74.897817 -141.006313) (xy 74.959853 -141.049888)
			(xy 75.016906 -141.09981) (xy 75.06833 -141.155514) (xy 75.113541 -141.216369) (xy 75.152028 -141.281684)
			(xy 75.183354 -141.35072) (xy 75.207164 -141.422695) (xy 75.223189 -141.496793) (xy 75.231248 -141.572174)
			(xy 75.231752 -141.61008) (xy 76.347831 -141.61008) (xy 76.351866 -141.534376) (xy 76.363925 -141.459531)
			(xy 76.383871 -141.38639) (xy 76.411478 -141.315785) (xy 76.446434 -141.248514) (xy 76.488342 -141.185339)
			(xy 76.536728 -141.126977) (xy 76.591044 -141.074089) (xy 76.650673 -141.027274) (xy 76.714941 -140.987062)
			(xy 76.783118 -140.95391) (xy 76.854434 -140.928192) (xy 76.928079 -140.9102) (xy 77.003219 -140.900138)
			(xy 77.079003 -140.898119) (xy 77.154573 -140.904168) (xy 77.229071 -140.918215) (xy 77.301654 -140.940101)
			(xy 77.3715 -140.969578) (xy 77.437817 -141.006313) (xy 77.499853 -141.049888) (xy 77.556906 -141.09981)
			(xy 77.60833 -141.155514) (xy 77.653541 -141.216369) (xy 77.692028 -141.281684) (xy 77.723354 -141.35072)
			(xy 77.747164 -141.422695) (xy 77.763189 -141.496793) (xy 77.771248 -141.572174) (xy 77.771752 -141.61008)
			(xy 78.887831 -141.61008) (xy 78.891866 -141.534376) (xy 78.903925 -141.459531) (xy 78.923871 -141.38639)
			(xy 78.951478 -141.315785) (xy 78.986434 -141.248514) (xy 79.028342 -141.185339) (xy 79.076728 -141.126977)
			(xy 79.131044 -141.074089) (xy 79.190673 -141.027274) (xy 79.254941 -140.987062) (xy 79.323118 -140.95391)
			(xy 79.394434 -140.928192) (xy 79.468079 -140.9102) (xy 79.543219 -140.900138) (xy 79.619003 -140.898119)
			(xy 79.694573 -140.904168) (xy 79.769071 -140.918215) (xy 79.841654 -140.940101) (xy 79.9115 -140.969578)
			(xy 79.977817 -141.006313) (xy 80.039853 -141.049888) (xy 80.096906 -141.09981) (xy 80.14833 -141.155514)
			(xy 80.193541 -141.216369) (xy 80.232028 -141.281684) (xy 80.263354 -141.35072) (xy 80.287164 -141.422695)
			(xy 80.303189 -141.496793) (xy 80.311248 -141.572174) (xy 80.311752 -141.61008) (xy 81.427831 -141.61008)
			(xy 81.431866 -141.534376) (xy 81.443925 -141.459531) (xy 81.463871 -141.38639) (xy 81.491478 -141.315785)
			(xy 81.526434 -141.248514) (xy 81.568342 -141.185339) (xy 81.616728 -141.126977) (xy 81.671044 -141.074089)
			(xy 81.730673 -141.027274) (xy 81.794941 -140.987062) (xy 81.863118 -140.95391) (xy 81.934434 -140.928192)
			(xy 82.008079 -140.9102) (xy 82.083219 -140.900138) (xy 82.159003 -140.898119) (xy 82.234573 -140.904168)
			(xy 82.309071 -140.918215) (xy 82.381654 -140.940101) (xy 82.4515 -140.969578) (xy 82.517817 -141.006313)
			(xy 82.579853 -141.049888) (xy 82.636906 -141.09981) (xy 82.68833 -141.155514) (xy 82.733541 -141.216369)
			(xy 82.772028 -141.281684) (xy 82.803354 -141.35072) (xy 82.827164 -141.422695) (xy 82.843189 -141.496793)
			(xy 82.851248 -141.572174) (xy 82.851752 -141.61008) (xy 82.851248 -141.647986) (xy 82.843189 -141.723367)
			(xy 82.827164 -141.797465) (xy 82.803354 -141.86944) (xy 82.772028 -141.938476) (xy 82.733541 -142.003791)
			(xy 82.68833 -142.064646) (xy 82.636906 -142.12035) (xy 82.579853 -142.170272) (xy 82.517817 -142.213847)
			(xy 82.4515 -142.250582) (xy 82.381654 -142.280059) (xy 82.309071 -142.301945) (xy 82.234573 -142.315992)
			(xy 82.159003 -142.322041) (xy 82.083219 -142.320022) (xy 82.008079 -142.30996) (xy 81.934434 -142.291968)
			(xy 81.863118 -142.26625) (xy 81.794941 -142.233098) (xy 81.730673 -142.192886) (xy 81.671044 -142.146071)
			(xy 81.616728 -142.093183) (xy 81.568342 -142.034821) (xy 81.526434 -141.971646) (xy 81.491478 -141.904375)
			(xy 81.463871 -141.83377) (xy 81.443925 -141.760629) (xy 81.431866 -141.685784) (xy 81.427831 -141.61008)
			(xy 80.311752 -141.61008) (xy 80.311248 -141.647986) (xy 80.303189 -141.723367) (xy 80.287164 -141.797465)
			(xy 80.263354 -141.86944) (xy 80.232028 -141.938476) (xy 80.193541 -142.003791) (xy 80.14833 -142.064646)
			(xy 80.096906 -142.12035) (xy 80.039853 -142.170272) (xy 79.977817 -142.213847) (xy 79.9115 -142.250582)
			(xy 79.841654 -142.280059) (xy 79.769071 -142.301945) (xy 79.694573 -142.315992) (xy 79.619003 -142.322041)
			(xy 79.543219 -142.320022) (xy 79.468079 -142.30996) (xy 79.394434 -142.291968) (xy 79.323118 -142.26625)
			(xy 79.254941 -142.233098) (xy 79.190673 -142.192886) (xy 79.131044 -142.146071) (xy 79.076728 -142.093183)
			(xy 79.028342 -142.034821) (xy 78.986434 -141.971646) (xy 78.951478 -141.904375) (xy 78.923871 -141.83377)
			(xy 78.903925 -141.760629) (xy 78.891866 -141.685784) (xy 78.887831 -141.61008) (xy 77.771752 -141.61008)
			(xy 77.771248 -141.647986) (xy 77.763189 -141.723367) (xy 77.747164 -141.797465) (xy 77.723354 -141.86944)
			(xy 77.692028 -141.938476) (xy 77.653541 -142.003791) (xy 77.60833 -142.064646) (xy 77.556906 -142.12035)
			(xy 77.499853 -142.170272) (xy 77.437817 -142.213847) (xy 77.3715 -142.250582) (xy 77.301654 -142.280059)
			(xy 77.229071 -142.301945) (xy 77.154573 -142.315992) (xy 77.079003 -142.322041) (xy 77.003219 -142.320022)
			(xy 76.928079 -142.30996) (xy 76.854434 -142.291968) (xy 76.783118 -142.26625) (xy 76.714941 -142.233098)
			(xy 76.650673 -142.192886) (xy 76.591044 -142.146071) (xy 76.536728 -142.093183) (xy 76.488342 -142.034821)
			(xy 76.446434 -141.971646) (xy 76.411478 -141.904375) (xy 76.383871 -141.83377) (xy 76.363925 -141.760629)
			(xy 76.351866 -141.685784) (xy 76.347831 -141.61008) (xy 75.231752 -141.61008) (xy 75.231248 -141.647986)
			(xy 75.223189 -141.723367) (xy 75.207164 -141.797465) (xy 75.183354 -141.86944) (xy 75.152028 -141.938476)
			(xy 75.113541 -142.003791) (xy 75.06833 -142.064646) (xy 75.016906 -142.12035) (xy 74.959853 -142.170272)
			(xy 74.897817 -142.213847) (xy 74.8315 -142.250582) (xy 74.761654 -142.280059) (xy 74.689071 -142.301945)
			(xy 74.614573 -142.315992) (xy 74.539003 -142.322041) (xy 74.463219 -142.320022) (xy 74.388079 -142.30996)
			(xy 74.314434 -142.291968) (xy 74.243118 -142.26625) (xy 74.174941 -142.233098) (xy 74.110673 -142.192886)
			(xy 74.051044 -142.146071) (xy 73.996728 -142.093183) (xy 73.948342 -142.034821) (xy 73.906434 -141.971646)
			(xy 73.871478 -141.904375) (xy 73.843871 -141.83377) (xy 73.823925 -141.760629) (xy 73.811866 -141.685784)
			(xy 73.807831 -141.61008) (xy 72.691752 -141.61008) (xy 72.691248 -141.647986) (xy 72.683189 -141.723367)
			(xy 72.667164 -141.797465) (xy 72.643354 -141.86944) (xy 72.612028 -141.938476) (xy 72.573541 -142.003791)
			(xy 72.52833 -142.064646) (xy 72.476906 -142.12035) (xy 72.419853 -142.170272) (xy 72.357817 -142.213847)
			(xy 72.2915 -142.250582) (xy 72.221654 -142.280059) (xy 72.149071 -142.301945) (xy 72.074573 -142.315992)
			(xy 71.999003 -142.322041) (xy 71.923219 -142.320022) (xy 71.848079 -142.30996) (xy 71.774434 -142.291968)
			(xy 71.703118 -142.26625) (xy 71.634941 -142.233098) (xy 71.570673 -142.192886) (xy 71.511044 -142.146071)
			(xy 71.456728 -142.093183) (xy 71.408342 -142.034821) (xy 71.366434 -141.971646) (xy 71.331478 -141.904375)
			(xy 71.303871 -141.83377) (xy 71.283925 -141.760629) (xy 71.271866 -141.685784) (xy 71.267831 -141.61008)
			(xy 70.151752 -141.61008) (xy 70.151248 -141.647986) (xy 70.143189 -141.723367) (xy 70.127164 -141.797465)
			(xy 70.103354 -141.86944) (xy 70.072028 -141.938476) (xy 70.033541 -142.003791) (xy 69.98833 -142.064646)
			(xy 69.936906 -142.12035) (xy 69.879853 -142.170272) (xy 69.817817 -142.213847) (xy 69.7515 -142.250582)
			(xy 69.681654 -142.280059) (xy 69.609071 -142.301945) (xy 69.534573 -142.315992) (xy 69.459003 -142.322041)
			(xy 69.383219 -142.320022) (xy 69.308079 -142.30996) (xy 69.234434 -142.291968) (xy 69.163118 -142.26625)
			(xy 69.094941 -142.233098) (xy 69.030673 -142.192886) (xy 68.971044 -142.146071) (xy 68.916728 -142.093183)
			(xy 68.868342 -142.034821) (xy 68.826434 -141.971646) (xy 68.791478 -141.904375) (xy 68.763871 -141.83377)
			(xy 68.743925 -141.760629) (xy 68.731866 -141.685784) (xy 68.727831 -141.61008) (xy 67.611752 -141.61008)
			(xy 67.611248 -141.647986) (xy 67.603189 -141.723367) (xy 67.587164 -141.797465) (xy 67.563354 -141.86944)
			(xy 67.532028 -141.938476) (xy 67.493541 -142.003791) (xy 67.44833 -142.064646) (xy 67.396906 -142.12035)
			(xy 67.339853 -142.170272) (xy 67.277817 -142.213847) (xy 67.2115 -142.250582) (xy 67.141654 -142.280059)
			(xy 67.069071 -142.301945) (xy 66.994573 -142.315992) (xy 66.919003 -142.322041) (xy 66.843219 -142.320022)
			(xy 66.768079 -142.30996) (xy 66.694434 -142.291968) (xy 66.623118 -142.26625) (xy 66.554941 -142.233098)
			(xy 66.490673 -142.192886) (xy 66.431044 -142.146071) (xy 66.376728 -142.093183) (xy 66.328342 -142.034821)
			(xy 66.286434 -141.971646) (xy 66.251478 -141.904375) (xy 66.223871 -141.83377) (xy 66.203925 -141.760629)
			(xy 66.191866 -141.685784) (xy 66.187831 -141.61008) (xy 65.071752 -141.61008) (xy 65.071248 -141.647986)
			(xy 65.063189 -141.723367) (xy 65.047164 -141.797465) (xy 65.023354 -141.86944) (xy 64.992028 -141.938476)
			(xy 64.953541 -142.003791) (xy 64.90833 -142.064646) (xy 64.856906 -142.12035) (xy 64.799853 -142.170272)
			(xy 64.737817 -142.213847) (xy 64.6715 -142.250582) (xy 64.601654 -142.280059) (xy 64.529071 -142.301945)
			(xy 64.454573 -142.315992) (xy 64.379003 -142.322041) (xy 64.303219 -142.320022) (xy 64.228079 -142.30996)
			(xy 64.154434 -142.291968) (xy 64.083118 -142.26625) (xy 64.014941 -142.233098) (xy 63.950673 -142.192886)
			(xy 63.891044 -142.146071) (xy 63.836728 -142.093183) (xy 63.788342 -142.034821) (xy 63.746434 -141.971646)
			(xy 63.711478 -141.904375) (xy 63.683871 -141.83377) (xy 63.663925 -141.760629) (xy 63.651866 -141.685784)
			(xy 63.647831 -141.61008) (xy 42.503292 -141.61008) (xy 42.47864 -141.629064) (xy 42.380994 -141.693948)
			(xy 42.279065 -141.75187) (xy 42.173347 -141.802549) (xy 42.064355 -141.845738) (xy 41.952619 -141.881228)
			(xy 41.838681 -141.908845) (xy 41.723096 -141.928457) (xy 41.606425 -141.939967) (xy 41.489236 -141.943319)
			(xy 41.372098 -141.938497) (xy 41.25558 -141.925525) (xy 41.14025 -141.904466) (xy 41.026668 -141.875421)
			(xy 40.915385 -141.838533) (xy 40.806943 -141.79398) (xy 40.70187 -141.74198) (xy 40.600675 -141.682784)
			(xy 40.50385 -141.616681) (xy 40.411868 -141.543992) (xy 40.325173 -141.46507) (xy 40.244189 -141.380299)
			(xy 40.169308 -141.290091) (xy 40.100895 -141.194885) (xy 40.039282 -141.095143) (xy 39.984769 -140.991351)
			(xy 39.937621 -140.884012) (xy 39.898066 -140.773649) (xy 39.866298 -140.660798) (xy 39.842471 -140.546008)
			(xy 39.826699 -140.429836) (xy 39.819061 -140.312848) (xy 39.818818 -140.254228) (xy 28.884372 -140.254228)
			(xy 28.884372 -143.833358) (xy 29.519874 -143.833358) (xy 29.519874 -143.746458) (xy 29.527892 -143.659929)
			(xy 29.54386 -143.574509) (xy 29.567641 -143.490927) (xy 29.599033 -143.409895) (xy 29.637767 -143.332106)
			(xy 29.683514 -143.258222) (xy 29.735883 -143.188875) (xy 29.794427 -143.124655) (xy 29.858647 -143.066111)
			(xy 29.927994 -143.013742) (xy 30.001878 -142.967995) (xy 30.079667 -142.929261) (xy 30.160699 -142.897869)
			(xy 30.244281 -142.874088) (xy 30.329701 -142.85812) (xy 30.41623 -142.850102) (xy 30.50313 -142.850102)
			(xy 30.589659 -142.85812) (xy 30.675079 -142.874088) (xy 30.758661 -142.897869) (xy 30.839693 -142.929261)
			(xy 30.917482 -142.967995) (xy 30.991366 -143.013742) (xy 31.060713 -143.066111) (xy 31.124933 -143.124655)
			(xy 31.183477 -143.188875) (xy 31.235846 -143.258222) (xy 31.281593 -143.332106) (xy 31.320327 -143.409895)
			(xy 31.351719 -143.490927) (xy 31.3755 -143.574509) (xy 31.391468 -143.659929) (xy 31.399486 -143.746458)
			(xy 31.399988 -143.789908) (xy 31.399486 -143.833358) (xy 34.599874 -143.833358) (xy 34.599874 -143.746458)
			(xy 34.607892 -143.659929) (xy 34.62386 -143.574509) (xy 34.647641 -143.490927) (xy 34.679033 -143.409895)
			(xy 34.717767 -143.332106) (xy 34.763514 -143.258222) (xy 34.815883 -143.188875) (xy 34.874427 -143.124655)
			(xy 34.938647 -143.066111) (xy 35.007994 -143.013742) (xy 35.081878 -142.967995) (xy 35.159667 -142.929261)
			(xy 35.240699 -142.897869) (xy 35.324281 -142.874088) (xy 35.409701 -142.85812) (xy 35.49623 -142.850102)
			(xy 35.58313 -142.850102) (xy 35.669659 -142.85812) (xy 35.755079 -142.874088) (xy 35.838661 -142.897869)
			(xy 35.919693 -142.929261) (xy 35.997482 -142.967995) (xy 36.071366 -143.013742) (xy 36.140713 -143.066111)
			(xy 36.204933 -143.124655) (xy 36.263477 -143.188875) (xy 36.315846 -143.258222) (xy 36.361593 -143.332106)
			(xy 36.400327 -143.409895) (xy 36.431719 -143.490927) (xy 36.4555 -143.574509) (xy 36.471468 -143.659929)
			(xy 36.479486 -143.746458) (xy 36.479988 -143.789908) (xy 36.479486 -143.833358) (xy 36.471468 -143.919887)
			(xy 36.4555 -144.005307) (xy 36.431719 -144.088889) (xy 36.400327 -144.169921) (xy 36.361593 -144.24771)
			(xy 36.315846 -144.321594) (xy 36.263477 -144.390941) (xy 36.204933 -144.455161) (xy 36.140713 -144.513705)
			(xy 36.071366 -144.566074) (xy 35.997482 -144.611821) (xy 35.919693 -144.650555) (xy 35.838661 -144.681947)
			(xy 35.755079 -144.705728) (xy 35.669659 -144.721696) (xy 35.58313 -144.729714) (xy 35.49623 -144.729714)
			(xy 35.409701 -144.721696) (xy 35.324281 -144.705728) (xy 35.240699 -144.681947) (xy 35.159667 -144.650555)
			(xy 35.081878 -144.611821) (xy 35.007994 -144.566074) (xy 34.938647 -144.513705) (xy 34.874427 -144.455161)
			(xy 34.815883 -144.390941) (xy 34.763514 -144.321594) (xy 34.717767 -144.24771) (xy 34.679033 -144.169921)
			(xy 34.647641 -144.088889) (xy 34.62386 -144.005307) (xy 34.607892 -143.919887) (xy 34.599874 -143.833358)
			(xy 31.399486 -143.833358) (xy 31.391468 -143.919887) (xy 31.3755 -144.005307) (xy 31.351719 -144.088889)
			(xy 31.320327 -144.169921) (xy 31.281593 -144.24771) (xy 31.235846 -144.321594) (xy 31.183477 -144.390941)
			(xy 31.124933 -144.455161) (xy 31.060713 -144.513705) (xy 30.991366 -144.566074) (xy 30.917482 -144.611821)
			(xy 30.839693 -144.650555) (xy 30.758661 -144.681947) (xy 30.675079 -144.705728) (xy 30.589659 -144.721696)
			(xy 30.50313 -144.729714) (xy 30.41623 -144.729714) (xy 30.329701 -144.721696) (xy 30.244281 -144.705728)
			(xy 30.160699 -144.681947) (xy 30.079667 -144.650555) (xy 30.001878 -144.611821) (xy 29.927994 -144.566074)
			(xy 29.858647 -144.513705) (xy 29.794427 -144.455161) (xy 29.735883 -144.390941) (xy 29.683514 -144.321594)
			(xy 29.637767 -144.24771) (xy 29.599033 -144.169921) (xy 29.567641 -144.088889) (xy 29.54386 -144.005307)
			(xy 29.527892 -143.919887) (xy 29.519874 -143.833358) (xy 28.884372 -143.833358) (xy 28.884372 -146.373358)
			(xy 29.519874 -146.373358) (xy 29.519874 -146.286458) (xy 29.527892 -146.199929) (xy 29.54386 -146.114509)
			(xy 29.567641 -146.030927) (xy 29.599033 -145.949895) (xy 29.637767 -145.872106) (xy 29.683514 -145.798222)
			(xy 29.735883 -145.728875) (xy 29.794427 -145.664655) (xy 29.858647 -145.606111) (xy 29.927994 -145.553742)
			(xy 30.001878 -145.507995) (xy 30.079667 -145.469261) (xy 30.160699 -145.437869) (xy 30.244281 -145.414088)
			(xy 30.329701 -145.39812) (xy 30.41623 -145.390102) (xy 30.50313 -145.390102) (xy 30.589659 -145.39812)
			(xy 30.675079 -145.414088) (xy 30.758661 -145.437869) (xy 30.839693 -145.469261) (xy 30.917482 -145.507995)
			(xy 30.991366 -145.553742) (xy 31.060713 -145.606111) (xy 31.124933 -145.664655) (xy 31.183477 -145.728875)
			(xy 31.235846 -145.798222) (xy 31.281593 -145.872106) (xy 31.320327 -145.949895) (xy 31.351719 -146.030927)
			(xy 31.3755 -146.114509) (xy 31.391468 -146.199929) (xy 31.399486 -146.286458) (xy 31.399988 -146.329908)
			(xy 31.399486 -146.373358) (xy 34.599874 -146.373358) (xy 34.599874 -146.286458) (xy 34.607892 -146.199929)
			(xy 34.62386 -146.114509) (xy 34.647641 -146.030927) (xy 34.679033 -145.949895) (xy 34.717767 -145.872106)
			(xy 34.763514 -145.798222) (xy 34.815883 -145.728875) (xy 34.874427 -145.664655) (xy 34.938647 -145.606111)
			(xy 35.007994 -145.553742) (xy 35.081878 -145.507995) (xy 35.159667 -145.469261) (xy 35.240699 -145.437869)
			(xy 35.324281 -145.414088) (xy 35.409701 -145.39812) (xy 35.49623 -145.390102) (xy 35.58313 -145.390102)
			(xy 35.669659 -145.39812) (xy 35.755079 -145.414088) (xy 35.838661 -145.437869) (xy 35.870739 -145.450296)
			(xy 66.71631 -145.450296) (xy 66.720198 -145.395947) (xy 66.73178 -145.342704) (xy 66.750823 -145.291652)
			(xy 66.776937 -145.243829) (xy 66.809591 -145.20021) (xy 66.848121 -145.161682) (xy 66.891742 -145.129029)
			(xy 66.939565 -145.102917) (xy 66.990619 -145.083876) (xy 67.043862 -145.072295) (xy 67.098211 -145.06841)
			(xy 67.15256 -145.072299) (xy 67.205803 -145.083883) (xy 67.256855 -145.102926) (xy 67.304677 -145.129041)
			(xy 67.326764 -145.144998) (xy 67.345776 -145.158594) (xy 67.387659 -145.179326) (xy 67.432627 -145.192052)
			(xy 67.479164 -145.196342) (xy 67.525701 -145.192052) (xy 67.570669 -145.179326) (xy 67.612552 -145.158594)
			(xy 67.631564 -145.144998) (xy 67.653647 -145.129027) (xy 67.701476 -145.1029) (xy 67.752536 -145.083846)
			(xy 67.805788 -145.072253) (xy 67.860148 -145.068357) (xy 67.914509 -145.072238) (xy 67.967764 -145.083816)
			(xy 68.018829 -145.102856) (xy 68.066665 -145.128971) (xy 68.110297 -145.161627) (xy 68.148836 -145.200161)
			(xy 68.181499 -145.243788) (xy 68.20762 -145.29162) (xy 68.226668 -145.342682) (xy 68.238254 -145.395936)
			(xy 68.242143 -145.450296) (xy 69.707903 -145.450296) (xy 69.711791 -145.395945) (xy 69.723374 -145.342701)
			(xy 69.742417 -145.291647) (xy 69.768532 -145.243823) (xy 69.801188 -145.200203) (xy 69.839719 -145.161674)
			(xy 69.883341 -145.129021) (xy 69.931167 -145.102908) (xy 69.982222 -145.083868) (xy 70.035467 -145.072287)
			(xy 70.089818 -145.068403) (xy 70.144169 -145.072293) (xy 70.197413 -145.083878) (xy 70.248466 -145.102923)
			(xy 70.296289 -145.12904) (xy 70.318376 -145.144998) (xy 70.337388 -145.158594) (xy 70.379271 -145.179326)
			(xy 70.424239 -145.192052) (xy 70.470776 -145.196342) (xy 70.517313 -145.192052) (xy 70.562281 -145.179326)
			(xy 70.604164 -145.158594) (xy 70.623176 -145.144998) (xy 70.645259 -145.129028) (xy 70.693087 -145.102903)
			(xy 70.744146 -145.08385) (xy 70.797396 -145.072259) (xy 70.851755 -145.068364) (xy 70.906114 -145.072246)
			(xy 70.959368 -145.083825) (xy 71.010431 -145.102865) (xy 71.058265 -145.128979) (xy 71.101895 -145.161635)
			(xy 71.140433 -145.200168) (xy 71.173095 -145.243794) (xy 71.199215 -145.291625) (xy 71.218261 -145.342686)
			(xy 71.229847 -145.395938) (xy 71.233736 -145.450296) (xy 71.229848 -145.504655) (xy 71.218264 -145.557908)
			(xy 71.199218 -145.608969) (xy 71.173099 -145.6568) (xy 71.140438 -145.700426) (xy 71.1019 -145.73896)
			(xy 71.058271 -145.771617) (xy 71.010438 -145.797732) (xy 70.959374 -145.816773) (xy 70.906121 -145.828353)
			(xy 70.851762 -145.832236) (xy 70.797403 -145.828342) (xy 70.744152 -145.816752) (xy 70.693093 -145.7977)
			(xy 70.645265 -145.771576) (xy 70.623176 -145.755614) (xy 70.604164 -145.742018) (xy 70.562281 -145.721286)
			(xy 70.517313 -145.70856) (xy 70.470776 -145.70427) (xy 70.424239 -145.70856) (xy 70.379271 -145.721286)
			(xy 70.337388 -145.742018) (xy 70.318376 -145.755614) (xy 70.296283 -145.771564) (xy 70.248459 -145.79768)
			(xy 70.197406 -145.816724) (xy 70.144162 -145.828308) (xy 70.089811 -145.832197) (xy 70.03546 -145.828312)
			(xy 69.982215 -145.81673) (xy 69.93116 -145.797689) (xy 69.883335 -145.771575) (xy 69.839714 -145.738922)
			(xy 69.801183 -145.700392) (xy 69.768528 -145.656771) (xy 69.742414 -145.608946) (xy 69.723372 -145.557892)
			(xy 69.71179 -145.504647) (xy 69.707903 -145.450296) (xy 68.242143 -145.450296) (xy 68.238255 -145.504657)
			(xy 68.22667 -145.557911) (xy 68.207623 -145.608974) (xy 68.181503 -145.656806) (xy 68.148841 -145.700433)
			(xy 68.110302 -145.738968) (xy 68.066671 -145.771626) (xy 68.018836 -145.797741) (xy 67.967771 -145.816782)
			(xy 67.914516 -145.828361) (xy 67.860155 -145.832243) (xy 67.805795 -145.828348) (xy 67.752543 -145.816756)
			(xy 67.701482 -145.797703) (xy 67.653653 -145.771577) (xy 67.631564 -145.755614) (xy 67.612552 -145.742018)
			(xy 67.570669 -145.721286) (xy 67.525701 -145.70856) (xy 67.479164 -145.70427) (xy 67.432627 -145.70856)
			(xy 67.387659 -145.721286) (xy 67.345776 -145.742018) (xy 67.326764 -145.755614) (xy 67.304671 -145.771563)
			(xy 67.256848 -145.797677) (xy 67.205796 -145.816719) (xy 67.152553 -145.828302) (xy 67.098204 -145.83219)
			(xy 67.043855 -145.828304) (xy 66.990612 -145.816722) (xy 66.939559 -145.79768) (xy 66.891736 -145.771567)
			(xy 66.848116 -145.738914) (xy 66.809587 -145.700385) (xy 66.776933 -145.656765) (xy 66.75082 -145.608941)
			(xy 66.731778 -145.557889) (xy 66.720197 -145.504646) (xy 66.71631 -145.450296) (xy 35.870739 -145.450296)
			(xy 35.919693 -145.469261) (xy 35.997482 -145.507995) (xy 36.071366 -145.553742) (xy 36.140713 -145.606111)
			(xy 36.204933 -145.664655) (xy 36.263477 -145.728875) (xy 36.315846 -145.798222) (xy 36.361593 -145.872106)
			(xy 36.400327 -145.949895) (xy 36.431719 -146.030927) (xy 36.4555 -146.114509) (xy 36.471468 -146.199929)
			(xy 36.479486 -146.286458) (xy 36.479988 -146.329908) (xy 36.479486 -146.373358) (xy 36.474357 -146.428714)
			(xy 80.994502 -146.428714) (xy 80.998573 -146.373092) (xy 81.010699 -146.318655) (xy 81.030622 -146.266564)
			(xy 81.057918 -146.217929) (xy 81.092004 -146.173786) (xy 81.132153 -146.135077) (xy 81.177511 -146.102626)
			(xy 81.227111 -146.077125) (xy 81.279895 -146.059118) (xy 81.334738 -146.048988) (xy 81.390472 -146.046951)
			(xy 81.445909 -146.053051) (xy 81.499866 -146.067157) (xy 81.551195 -146.088969) (xy 81.598801 -146.118023)
			(xy 81.641669 -146.153698) (xy 81.678886 -146.195235) (xy 81.709659 -146.241748) (xy 81.733331 -146.292245)
			(xy 81.749399 -146.345652) (xy 81.757519 -146.400828) (xy 81.758028 -146.428714) (xy 81.757519 -146.4566)
			(xy 81.749399 -146.511776) (xy 81.733331 -146.565183) (xy 81.709659 -146.61568) (xy 81.678886 -146.662193)
			(xy 81.641669 -146.70373) (xy 81.598801 -146.739405) (xy 81.551195 -146.768459) (xy 81.499866 -146.790271)
			(xy 81.445909 -146.804377) (xy 81.390472 -146.810477) (xy 81.334738 -146.80844) (xy 81.279895 -146.79831)
			(xy 81.227111 -146.780303) (xy 81.177511 -146.754802) (xy 81.132153 -146.722351) (xy 81.092004 -146.683642)
			(xy 81.057918 -146.639499) (xy 81.030622 -146.590864) (xy 81.010699 -146.538773) (xy 80.998573 -146.484336)
			(xy 80.994502 -146.428714) (xy 36.474357 -146.428714) (xy 36.471468 -146.459887) (xy 36.4555 -146.545307)
			(xy 36.431719 -146.628889) (xy 36.400327 -146.709921) (xy 36.361593 -146.78771) (xy 36.315846 -146.861594)
			(xy 36.263477 -146.930941) (xy 36.204933 -146.995161) (xy 36.140713 -147.053705) (xy 36.071366 -147.106074)
			(xy 35.997482 -147.151821) (xy 35.919693 -147.190555) (xy 35.838661 -147.221947) (xy 35.755079 -147.245728)
			(xy 35.669659 -147.261696) (xy 35.58313 -147.269714) (xy 35.49623 -147.269714) (xy 35.409701 -147.261696)
			(xy 35.324281 -147.245728) (xy 35.240699 -147.221947) (xy 35.159667 -147.190555) (xy 35.081878 -147.151821)
			(xy 35.007994 -147.106074) (xy 34.938647 -147.053705) (xy 34.874427 -146.995161) (xy 34.815883 -146.930941)
			(xy 34.763514 -146.861594) (xy 34.717767 -146.78771) (xy 34.679033 -146.709921) (xy 34.647641 -146.628889)
			(xy 34.62386 -146.545307) (xy 34.607892 -146.459887) (xy 34.599874 -146.373358) (xy 31.399486 -146.373358)
			(xy 31.391468 -146.459887) (xy 31.3755 -146.545307) (xy 31.351719 -146.628889) (xy 31.320327 -146.709921)
			(xy 31.281593 -146.78771) (xy 31.235846 -146.861594) (xy 31.183477 -146.930941) (xy 31.124933 -146.995161)
			(xy 31.060713 -147.053705) (xy 30.991366 -147.106074) (xy 30.917482 -147.151821) (xy 30.839693 -147.190555)
			(xy 30.758661 -147.221947) (xy 30.675079 -147.245728) (xy 30.589659 -147.261696) (xy 30.50313 -147.269714)
			(xy 30.41623 -147.269714) (xy 30.329701 -147.261696) (xy 30.244281 -147.245728) (xy 30.160699 -147.221947)
			(xy 30.079667 -147.190555) (xy 30.001878 -147.151821) (xy 29.927994 -147.106074) (xy 29.858647 -147.053705)
			(xy 29.794427 -146.995161) (xy 29.735883 -146.930941) (xy 29.683514 -146.861594) (xy 29.637767 -146.78771)
			(xy 29.599033 -146.709921) (xy 29.567641 -146.628889) (xy 29.54386 -146.545307) (xy 29.527892 -146.459887)
			(xy 29.519874 -146.373358) (xy 28.884372 -146.373358) (xy 28.884372 -147.685824) (xy 66.716273 -147.685824)
			(xy 66.720157 -147.631469) (xy 66.731737 -147.57822) (xy 66.750778 -147.527162) (xy 66.776891 -147.479333)
			(xy 66.809545 -147.435707) (xy 66.848076 -147.397172) (xy 66.891699 -147.364513) (xy 66.939525 -147.338395)
			(xy 66.990582 -147.319349) (xy 67.043829 -147.307763) (xy 67.098184 -147.303873) (xy 67.152538 -147.307758)
			(xy 67.205787 -147.31934) (xy 67.256845 -147.338381) (xy 67.304674 -147.364495) (xy 67.326764 -147.380452)
			(xy 67.345776 -147.394048) (xy 67.387659 -147.41478) (xy 67.432627 -147.427506) (xy 67.479164 -147.431796)
			(xy 67.525701 -147.427506) (xy 67.570669 -147.41478) (xy 67.612552 -147.394048) (xy 67.631564 -147.380452)
			(xy 67.653691 -147.364543) (xy 67.701516 -147.338422) (xy 67.752573 -147.319373) (xy 67.80582 -147.307785)
			(xy 67.860175 -147.303894) (xy 67.914531 -147.307778) (xy 67.96778 -147.319359) (xy 68.018839 -147.338401)
			(xy 68.066668 -147.364516) (xy 68.110293 -147.397173) (xy 68.148827 -147.435706) (xy 68.181483 -147.479331)
			(xy 68.207598 -147.52716) (xy 68.22664 -147.578219) (xy 68.238222 -147.631468) (xy 68.242106 -147.685824)
			(xy 69.707866 -147.685824) (xy 69.71175 -147.631468) (xy 69.723331 -147.578217) (xy 69.742372 -147.527157)
			(xy 69.768486 -147.479327) (xy 69.801142 -147.4357) (xy 69.839674 -147.397164) (xy 69.883298 -147.364505)
			(xy 69.931127 -147.338386) (xy 69.982185 -147.31934) (xy 70.035434 -147.307755) (xy 70.08979 -147.303866)
			(xy 70.144147 -147.307752) (xy 70.197397 -147.319335) (xy 70.248456 -147.338378) (xy 70.296286 -147.364494)
			(xy 70.318376 -147.380452) (xy 70.337388 -147.394048) (xy 70.379271 -147.41478) (xy 70.424239 -147.427506)
			(xy 70.470776 -147.431796) (xy 70.517313 -147.427506) (xy 70.562281 -147.41478) (xy 70.604164 -147.394048)
			(xy 70.623176 -147.380452) (xy 70.645302 -147.364544) (xy 70.693127 -147.338425) (xy 70.744182 -147.319378)
			(xy 70.797429 -147.307791) (xy 70.851782 -147.303901) (xy 70.906136 -147.307786) (xy 70.959384 -147.319368)
			(xy 71.010441 -147.33841) (xy 71.058268 -147.364525) (xy 71.101892 -147.397181) (xy 71.140423 -147.435713)
			(xy 71.173079 -147.479337) (xy 71.199193 -147.527165) (xy 71.218234 -147.578222) (xy 71.229815 -147.63147)
			(xy 71.233699 -147.685824) (xy 71.229808 -147.740177) (xy 71.21822 -147.793424) (xy 71.199173 -147.844479)
			(xy 71.192775 -147.856194) (xy 80.721452 -147.856194) (xy 80.725523 -147.800572) (xy 80.737649 -147.746135)
			(xy 80.757572 -147.694044) (xy 80.784868 -147.645409) (xy 80.818954 -147.601266) (xy 80.859103 -147.562557)
			(xy 80.904461 -147.530106) (xy 80.954061 -147.504605) (xy 81.006845 -147.486598) (xy 81.061688 -147.476468)
			(xy 81.117422 -147.474431) (xy 81.172859 -147.480531) (xy 81.226816 -147.494637) (xy 81.278145 -147.516449)
			(xy 81.325751 -147.545503) (xy 81.368619 -147.581178) (xy 81.405836 -147.622715) (xy 81.436609 -147.669228)
			(xy 81.460281 -147.719725) (xy 81.476349 -147.773132) (xy 81.484469 -147.828308) (xy 81.484978 -147.856194)
			(xy 81.484469 -147.88408) (xy 81.476349 -147.939256) (xy 81.460281 -147.992663) (xy 81.436609 -148.04316)
			(xy 81.405836 -148.089673) (xy 81.368619 -148.13121) (xy 81.325751 -148.166885) (xy 81.278145 -148.195939)
			(xy 81.226816 -148.217751) (xy 81.172859 -148.231857) (xy 81.117422 -148.237957) (xy 81.061688 -148.23592)
			(xy 81.006845 -148.22579) (xy 80.954061 -148.207783) (xy 80.904461 -148.182282) (xy 80.859103 -148.149831)
			(xy 80.818954 -148.111122) (xy 80.784868 -148.066979) (xy 80.757572 -148.018344) (xy 80.737649 -147.966253)
			(xy 80.725523 -147.911816) (xy 80.721452 -147.856194) (xy 71.192775 -147.856194) (xy 71.173053 -147.892303)
			(xy 71.140392 -147.935923) (xy 71.101855 -147.974451) (xy 71.058228 -148.007101) (xy 71.010397 -148.03321)
			(xy 70.959338 -148.052246) (xy 70.906089 -148.063821) (xy 70.851734 -148.067699) (xy 70.797381 -148.063802)
			(xy 70.744136 -148.052209) (xy 70.693083 -148.033155) (xy 70.645262 -148.00703) (xy 70.623176 -147.991068)
			(xy 70.604164 -147.977472) (xy 70.562281 -147.95674) (xy 70.517313 -147.944014) (xy 70.470776 -147.939724)
			(xy 70.424239 -147.944014) (xy 70.379271 -147.95674) (xy 70.337388 -147.977472) (xy 70.318376 -147.991068)
			(xy 70.296326 -148.00708) (xy 70.2485 -148.033202) (xy 70.197443 -148.052252) (xy 70.144194 -148.063841)
			(xy 70.089838 -148.067734) (xy 70.035482 -148.063852) (xy 69.982231 -148.052273) (xy 69.93117 -148.033234)
			(xy 69.883339 -148.007121) (xy 69.83971 -147.974467) (xy 69.801173 -147.935937) (xy 69.768512 -147.892314)
			(xy 69.742392 -147.844487) (xy 69.723344 -147.793429) (xy 69.711757 -147.74018) (xy 69.707866 -147.685824)
			(xy 68.242106 -147.685824) (xy 68.238215 -147.740179) (xy 68.226627 -147.793427) (xy 68.207579 -147.844483)
			(xy 68.181457 -147.892309) (xy 68.148795 -147.93593) (xy 68.110257 -147.974458) (xy 68.066628 -148.00711)
			(xy 68.018796 -148.033219) (xy 67.967734 -148.052254) (xy 67.914483 -148.063829) (xy 67.860127 -148.067706)
			(xy 67.805773 -148.063808) (xy 67.752527 -148.052213) (xy 67.701472 -148.033158) (xy 67.65365 -148.007031)
			(xy 67.631564 -147.991068) (xy 67.612552 -147.977472) (xy 67.570669 -147.95674) (xy 67.525701 -147.944014)
			(xy 67.479164 -147.939724) (xy 67.432627 -147.944014) (xy 67.387659 -147.95674) (xy 67.345776 -147.977472)
			(xy 67.326764 -147.991068) (xy 67.304714 -148.007079) (xy 67.256889 -148.033199) (xy 67.205833 -148.052247)
			(xy 67.152586 -148.063835) (xy 67.098232 -148.067727) (xy 67.043877 -148.063844) (xy 66.990628 -148.052265)
			(xy 66.939569 -148.033225) (xy 66.891739 -148.007113) (xy 66.848112 -147.97446) (xy 66.809577 -147.93593)
			(xy 66.776917 -147.892308) (xy 66.750798 -147.844482) (xy 66.731751 -147.793426) (xy 66.720164 -147.740178)
			(xy 66.716273 -147.685824) (xy 28.884372 -147.685824) (xy 28.884372 -148.913358) (xy 29.519874 -148.913358)
			(xy 29.519874 -148.826458) (xy 29.527892 -148.739929) (xy 29.54386 -148.654509) (xy 29.567641 -148.570927)
			(xy 29.599033 -148.489895) (xy 29.637767 -148.412106) (xy 29.683514 -148.338222) (xy 29.735883 -148.268875)
			(xy 29.794427 -148.204655) (xy 29.858647 -148.146111) (xy 29.927994 -148.093742) (xy 30.001878 -148.047995)
			(xy 30.079667 -148.009261) (xy 30.160699 -147.977869) (xy 30.244281 -147.954088) (xy 30.329701 -147.93812)
			(xy 30.41623 -147.930102) (xy 30.50313 -147.930102) (xy 30.589659 -147.93812) (xy 30.675079 -147.954088)
			(xy 30.758661 -147.977869) (xy 30.839693 -148.009261) (xy 30.917482 -148.047995) (xy 30.991366 -148.093742)
			(xy 31.060713 -148.146111) (xy 31.124933 -148.204655) (xy 31.183477 -148.268875) (xy 31.235846 -148.338222)
			(xy 31.281593 -148.412106) (xy 31.320327 -148.489895) (xy 31.351719 -148.570927) (xy 31.3755 -148.654509)
			(xy 31.391468 -148.739929) (xy 31.399486 -148.826458) (xy 31.399988 -148.869908) (xy 31.399486 -148.913358)
			(xy 34.599874 -148.913358) (xy 34.599874 -148.826458) (xy 34.607892 -148.739929) (xy 34.62386 -148.654509)
			(xy 34.647641 -148.570927) (xy 34.679033 -148.489895) (xy 34.717767 -148.412106) (xy 34.763514 -148.338222)
			(xy 34.815883 -148.268875) (xy 34.874427 -148.204655) (xy 34.938647 -148.146111) (xy 35.007994 -148.093742)
			(xy 35.081878 -148.047995) (xy 35.159667 -148.009261) (xy 35.240699 -147.977869) (xy 35.324281 -147.954088)
			(xy 35.409701 -147.93812) (xy 35.49623 -147.930102) (xy 35.58313 -147.930102) (xy 35.669659 -147.93812)
			(xy 35.755079 -147.954088) (xy 35.838661 -147.977869) (xy 35.919693 -148.009261) (xy 35.997482 -148.047995)
			(xy 36.071366 -148.093742) (xy 36.140713 -148.146111) (xy 36.204933 -148.204655) (xy 36.263477 -148.268875)
			(xy 36.315846 -148.338222) (xy 36.361593 -148.412106) (xy 36.400327 -148.489895) (xy 36.431719 -148.570927)
			(xy 36.4555 -148.654509) (xy 36.471468 -148.739929) (xy 36.479486 -148.826458) (xy 36.479988 -148.869908)
			(xy 36.479486 -148.913358) (xy 36.471468 -148.999887) (xy 36.4555 -149.085307) (xy 36.431719 -149.168889)
			(xy 36.400327 -149.249921) (xy 36.361593 -149.32771) (xy 36.315846 -149.401594) (xy 36.305345 -149.4155)
			(xy 80.319878 -149.4155) (xy 80.323949 -149.359878) (xy 80.336075 -149.305441) (xy 80.355998 -149.25335)
			(xy 80.383294 -149.204715) (xy 80.41738 -149.160572) (xy 80.457529 -149.121863) (xy 80.502887 -149.089412)
			(xy 80.552487 -149.063911) (xy 80.605271 -149.045904) (xy 80.660114 -149.035774) (xy 80.715848 -149.033737)
			(xy 80.771285 -149.039837) (xy 80.825242 -149.053943) (xy 80.876571 -149.075755) (xy 80.924177 -149.104809)
			(xy 80.967045 -149.140484) (xy 81.004262 -149.182021) (xy 81.035035 -149.228534) (xy 81.058707 -149.279031)
			(xy 81.074775 -149.332438) (xy 81.082895 -149.387614) (xy 81.083404 -149.4155) (xy 81.082895 -149.443386)
			(xy 81.074775 -149.498562) (xy 81.058707 -149.551969) (xy 81.035035 -149.602466) (xy 81.004262 -149.648979)
			(xy 80.967045 -149.690516) (xy 80.924177 -149.726191) (xy 80.876571 -149.755245) (xy 80.825242 -149.777057)
			(xy 80.771285 -149.791163) (xy 80.715848 -149.797263) (xy 80.660114 -149.795226) (xy 80.605271 -149.785096)
			(xy 80.552487 -149.767089) (xy 80.502887 -149.741588) (xy 80.457529 -149.709137) (xy 80.41738 -149.670428)
			(xy 80.383294 -149.626285) (xy 80.355998 -149.57765) (xy 80.336075 -149.525559) (xy 80.323949 -149.471122)
			(xy 80.319878 -149.4155) (xy 36.305345 -149.4155) (xy 36.263477 -149.470941) (xy 36.204933 -149.535161)
			(xy 36.140713 -149.593705) (xy 36.071366 -149.646074) (xy 35.997482 -149.691821) (xy 35.919693 -149.730555)
			(xy 35.838661 -149.761947) (xy 35.755079 -149.785728) (xy 35.669659 -149.801696) (xy 35.58313 -149.809714)
			(xy 35.49623 -149.809714) (xy 35.409701 -149.801696) (xy 35.324281 -149.785728) (xy 35.240699 -149.761947)
			(xy 35.159667 -149.730555) (xy 35.081878 -149.691821) (xy 35.007994 -149.646074) (xy 34.938647 -149.593705)
			(xy 34.874427 -149.535161) (xy 34.815883 -149.470941) (xy 34.763514 -149.401594) (xy 34.717767 -149.32771)
			(xy 34.679033 -149.249921) (xy 34.647641 -149.168889) (xy 34.62386 -149.085307) (xy 34.607892 -148.999887)
			(xy 34.599874 -148.913358) (xy 31.399486 -148.913358) (xy 31.391468 -148.999887) (xy 31.3755 -149.085307)
			(xy 31.351719 -149.168889) (xy 31.320327 -149.249921) (xy 31.281593 -149.32771) (xy 31.235846 -149.401594)
			(xy 31.183477 -149.470941) (xy 31.124933 -149.535161) (xy 31.060713 -149.593705) (xy 30.991366 -149.646074)
			(xy 30.917482 -149.691821) (xy 30.839693 -149.730555) (xy 30.758661 -149.761947) (xy 30.675079 -149.785728)
			(xy 30.589659 -149.801696) (xy 30.50313 -149.809714) (xy 30.41623 -149.809714) (xy 30.329701 -149.801696)
			(xy 30.244281 -149.785728) (xy 30.160699 -149.761947) (xy 30.079667 -149.730555) (xy 30.001878 -149.691821)
			(xy 29.927994 -149.646074) (xy 29.858647 -149.593705) (xy 29.794427 -149.535161) (xy 29.735883 -149.470941)
			(xy 29.683514 -149.401594) (xy 29.637767 -149.32771) (xy 29.599033 -149.249921) (xy 29.567641 -149.168889)
			(xy 29.54386 -149.085307) (xy 29.527892 -148.999887) (xy 29.519874 -148.913358) (xy 28.884372 -148.913358)
			(xy 28.884372 -150.353982) (xy 66.716329 -150.353982) (xy 66.720219 -150.299636) (xy 66.731803 -150.246396)
			(xy 66.750846 -150.195347) (xy 66.776961 -150.147528) (xy 66.809615 -150.103912) (xy 66.848144 -150.065387)
			(xy 66.891764 -150.032737) (xy 66.939586 -150.006628) (xy 66.990638 -149.987591) (xy 67.043879 -149.976012)
			(xy 67.098226 -149.972129) (xy 67.152572 -149.97602) (xy 67.205811 -149.987605) (xy 67.25686 -150.006649)
			(xy 67.304679 -150.032765) (xy 67.326764 -150.048722) (xy 67.345776 -150.062318) (xy 67.387659 -150.08305)
			(xy 67.432627 -150.095776) (xy 67.479164 -150.100066) (xy 67.525701 -150.095776) (xy 67.570669 -150.08305)
			(xy 67.612552 -150.062318) (xy 67.631564 -150.048722) (xy 67.653625 -150.032719) (xy 67.701455 -150.006588)
			(xy 67.752517 -149.987531) (xy 67.805771 -149.975936) (xy 67.860133 -149.972038) (xy 67.914497 -149.975917)
			(xy 67.967756 -149.987494) (xy 68.018824 -150.006533) (xy 68.066663 -150.032647) (xy 68.110298 -150.065303)
			(xy 68.148841 -150.103838) (xy 68.181508 -150.147466) (xy 68.207632 -150.195299) (xy 68.226682 -150.246363)
			(xy 68.238271 -150.299619) (xy 68.242162 -150.353982) (xy 69.707922 -150.353982) (xy 69.711812 -150.299634)
			(xy 69.723396 -150.246393) (xy 69.742441 -150.195342) (xy 69.768556 -150.147522) (xy 69.801212 -150.103904)
			(xy 69.839743 -150.065379) (xy 69.883364 -150.032729) (xy 69.931188 -150.00662) (xy 69.982241 -149.987582)
			(xy 70.035484 -149.976004) (xy 70.089832 -149.972122) (xy 70.14418 -149.976014) (xy 70.197421 -149.9876)
			(xy 70.248471 -150.006647) (xy 70.296291 -150.032764) (xy 70.318376 -150.048722) (xy 70.337388 -150.062318)
			(xy 70.379271 -150.08305) (xy 70.424239 -150.095776) (xy 70.470776 -150.100066) (xy 70.517313 -150.095776)
			(xy 70.562281 -150.08305) (xy 70.604164 -150.062318) (xy 70.623176 -150.048722) (xy 70.645237 -150.03272)
			(xy 70.693066 -150.006591) (xy 70.744126 -149.987536) (xy 70.797379 -149.975942) (xy 70.85174 -149.972045)
			(xy 70.906103 -149.975925) (xy 70.959359 -149.987502) (xy 71.010426 -150.006542) (xy 71.058263 -150.032655)
			(xy 71.101896 -150.065311) (xy 71.140438 -150.103845) (xy 71.173103 -150.147472) (xy 71.199226 -150.195303)
			(xy 71.218276 -150.246366) (xy 71.229864 -150.299621) (xy 71.233755 -150.353982) (xy 71.229869 -150.408344)
			(xy 71.218286 -150.461599) (xy 71.199241 -150.512664) (xy 71.173122 -150.560498) (xy 71.140462 -150.604128)
			(xy 71.101924 -150.642665) (xy 71.058293 -150.675326) (xy 71.010459 -150.701444) (xy 70.959394 -150.720488)
			(xy 70.906138 -150.73207) (xy 70.851776 -150.735955) (xy 70.797415 -150.732063) (xy 70.744161 -150.720474)
			(xy 70.693098 -150.701424) (xy 70.645267 -150.6753) (xy 70.623176 -150.659338) (xy 70.604164 -150.645742)
			(xy 70.562281 -150.62501) (xy 70.517313 -150.612284) (xy 70.470776 -150.607994) (xy 70.424239 -150.612284)
			(xy 70.379271 -150.62501) (xy 70.337388 -150.645742) (xy 70.318376 -150.659338) (xy 70.29626 -150.675255)
			(xy 70.248438 -150.701368) (xy 70.197387 -150.72041) (xy 70.144145 -150.731991) (xy 70.089796 -150.735878)
			(xy 70.035448 -150.73199) (xy 69.982207 -150.720408) (xy 69.931155 -150.701365) (xy 69.883334 -150.675252)
			(xy 69.839715 -150.642598) (xy 69.801188 -150.604068) (xy 69.768537 -150.560448) (xy 69.742426 -150.512625)
			(xy 69.723386 -150.461573) (xy 69.711806 -150.40833) (xy 69.707922 -150.353982) (xy 68.242162 -150.353982)
			(xy 68.238276 -150.408345) (xy 68.226693 -150.461602) (xy 68.207647 -150.512668) (xy 68.181527 -150.560504)
			(xy 68.148865 -150.604135) (xy 68.110326 -150.642673) (xy 68.066693 -150.675334) (xy 68.018857 -150.701452)
			(xy 67.96779 -150.720496) (xy 67.914533 -150.732078) (xy 67.860169 -150.735962) (xy 67.805807 -150.732069)
			(xy 67.752551 -150.720479) (xy 67.701487 -150.701427) (xy 67.653655 -150.675301) (xy 67.631564 -150.659338)
			(xy 67.612552 -150.645742) (xy 67.570669 -150.62501) (xy 67.525701 -150.612284) (xy 67.479164 -150.607994)
			(xy 67.432627 -150.612284) (xy 67.387659 -150.62501) (xy 67.345776 -150.645742) (xy 67.326764 -150.659338)
			(xy 67.304649 -150.675254) (xy 67.256827 -150.701365) (xy 67.205777 -150.720405) (xy 67.152536 -150.731985)
			(xy 67.09819 -150.735871) (xy 67.043843 -150.731982) (xy 66.990603 -150.720399) (xy 66.939554 -150.701357)
			(xy 66.891734 -150.675243) (xy 66.848117 -150.64259) (xy 66.809592 -150.604061) (xy 66.776941 -150.560442)
			(xy 66.750831 -150.51262) (xy 66.731793 -150.46157) (xy 66.720214 -150.408329) (xy 66.716329 -150.353982)
			(xy 28.884372 -150.353982) (xy 28.884372 -151.453358) (xy 29.519874 -151.453358) (xy 29.519874 -151.366458)
			(xy 29.527892 -151.279929) (xy 29.54386 -151.194509) (xy 29.567641 -151.110927) (xy 29.599033 -151.029895)
			(xy 29.637767 -150.952106) (xy 29.683514 -150.878222) (xy 29.735883 -150.808875) (xy 29.794427 -150.744655)
			(xy 29.858647 -150.686111) (xy 29.927994 -150.633742) (xy 30.001878 -150.587995) (xy 30.079667 -150.549261)
			(xy 30.160699 -150.517869) (xy 30.244281 -150.494088) (xy 30.329701 -150.47812) (xy 30.41623 -150.470102)
			(xy 30.50313 -150.470102) (xy 30.589659 -150.47812) (xy 30.675079 -150.494088) (xy 30.758661 -150.517869)
			(xy 30.839693 -150.549261) (xy 30.917482 -150.587995) (xy 30.991366 -150.633742) (xy 31.060713 -150.686111)
			(xy 31.124933 -150.744655) (xy 31.183477 -150.808875) (xy 31.235846 -150.878222) (xy 31.281593 -150.952106)
			(xy 31.320327 -151.029895) (xy 31.351719 -151.110927) (xy 31.3755 -151.194509) (xy 31.391468 -151.279929)
			(xy 31.399486 -151.366458) (xy 31.399988 -151.409908) (xy 31.399486 -151.453358) (xy 34.599874 -151.453358)
			(xy 34.599874 -151.366458) (xy 34.607892 -151.279929) (xy 34.62386 -151.194509) (xy 34.647641 -151.110927)
			(xy 34.679033 -151.029895) (xy 34.717767 -150.952106) (xy 34.763514 -150.878222) (xy 34.815883 -150.808875)
			(xy 34.874427 -150.744655) (xy 34.938647 -150.686111) (xy 35.007994 -150.633742) (xy 35.081878 -150.587995)
			(xy 35.159667 -150.549261) (xy 35.240699 -150.517869) (xy 35.324281 -150.494088) (xy 35.409701 -150.47812)
			(xy 35.49623 -150.470102) (xy 35.58313 -150.470102) (xy 35.669659 -150.47812) (xy 35.755079 -150.494088)
			(xy 35.838661 -150.517869) (xy 35.919693 -150.549261) (xy 35.997482 -150.587995) (xy 36.071366 -150.633742)
			(xy 36.140713 -150.686111) (xy 36.204933 -150.744655) (xy 36.263477 -150.808875) (xy 36.315846 -150.878222)
			(xy 36.361593 -150.952106) (xy 36.400327 -151.029895) (xy 36.431719 -151.110927) (xy 36.4555 -151.194509)
			(xy 36.471468 -151.279929) (xy 36.479486 -151.366458) (xy 36.479988 -151.409908) (xy 36.479486 -151.453358)
			(xy 36.471468 -151.539887) (xy 36.4555 -151.625307) (xy 36.431719 -151.708889) (xy 36.400327 -151.789921)
			(xy 36.361593 -151.86771) (xy 36.315846 -151.941594) (xy 36.297736 -151.965575) (xy 48.168042 -151.965575)
			(xy 48.168042 -151.884465) (xy 48.175992 -151.803746) (xy 48.191815 -151.724195) (xy 48.21536 -151.646579)
			(xy 48.246399 -151.571643) (xy 48.284634 -151.500111) (xy 48.329696 -151.432671) (xy 48.381151 -151.369972)
			(xy 48.438504 -151.312619) (xy 48.501203 -151.261164) (xy 48.568643 -151.216102) (xy 48.640175 -151.177867)
			(xy 48.715111 -151.146828) (xy 48.792727 -151.123283) (xy 48.872278 -151.10746) (xy 48.952997 -151.09951)
			(xy 49.034107 -151.09951) (xy 49.114826 -151.10746) (xy 49.194377 -151.123283) (xy 49.271993 -151.146828)
			(xy 49.346929 -151.177867) (xy 49.418461 -151.216102) (xy 49.485901 -151.261164) (xy 49.5486 -151.312619)
			(xy 49.605953 -151.369972) (xy 49.657408 -151.432671) (xy 49.70247 -151.500111) (xy 49.740705 -151.571643)
			(xy 49.771744 -151.646579) (xy 49.795289 -151.724195) (xy 49.811112 -151.803746) (xy 49.819062 -151.884465)
			(xy 49.81956 -151.92502) (xy 49.819062 -151.965575) (xy 51.668162 -151.965575) (xy 51.668162 -151.884465)
			(xy 51.676112 -151.803746) (xy 51.691935 -151.724195) (xy 51.71548 -151.646579) (xy 51.746519 -151.571643)
			(xy 51.784754 -151.500111) (xy 51.829816 -151.432671) (xy 51.881271 -151.369972) (xy 51.938624 -151.312619)
			(xy 52.001323 -151.261164) (xy 52.068763 -151.216102) (xy 52.140295 -151.177867) (xy 52.215231 -151.146828)
			(xy 52.292847 -151.123283) (xy 52.372398 -151.10746) (xy 52.453117 -151.09951) (xy 52.534227 -151.09951)
			(xy 52.614946 -151.10746) (xy 52.694497 -151.123283) (xy 52.772113 -151.146828) (xy 52.847049 -151.177867)
			(xy 52.918581 -151.216102) (xy 52.986021 -151.261164) (xy 53.04872 -151.312619) (xy 53.106073 -151.369972)
			(xy 53.157528 -151.432671) (xy 53.20259 -151.500111) (xy 53.240825 -151.571643) (xy 53.271864 -151.646579)
			(xy 53.295409 -151.724195) (xy 53.311232 -151.803746) (xy 53.319182 -151.884465) (xy 53.31968 -151.92502)
			(xy 53.319182 -151.965575) (xy 53.311232 -152.046294) (xy 53.295409 -152.125845) (xy 53.271864 -152.203461)
			(xy 53.240825 -152.278397) (xy 53.20259 -152.349929) (xy 53.157528 -152.417369) (xy 53.106073 -152.480068)
			(xy 53.04872 -152.537421) (xy 52.986021 -152.588876) (xy 52.918581 -152.633938) (xy 52.847049 -152.672173)
			(xy 52.772113 -152.703212) (xy 52.698367 -152.725583) (xy 66.716327 -152.725583) (xy 66.720217 -152.671237)
			(xy 66.731801 -152.617997) (xy 66.750844 -152.566947) (xy 66.776959 -152.519128) (xy 66.809613 -152.475511)
			(xy 66.848142 -152.436986) (xy 66.891762 -152.404337) (xy 66.939585 -152.378227) (xy 66.990636 -152.35919)
			(xy 67.043877 -152.347611) (xy 67.098224 -152.343727) (xy 67.152571 -152.347618) (xy 67.205811 -152.359203)
			(xy 67.25686 -152.378248) (xy 67.304679 -152.404363) (xy 67.326764 -152.42032) (xy 67.345776 -152.433916)
			(xy 67.387659 -152.454648) (xy 67.432627 -152.467374) (xy 67.479164 -152.471664) (xy 67.525701 -152.467374)
			(xy 67.570669 -152.454648) (xy 67.612552 -152.433916) (xy 67.631564 -152.42032) (xy 67.653627 -152.404319)
			(xy 67.701456 -152.378189) (xy 67.752518 -152.359132) (xy 67.805772 -152.347537) (xy 67.860135 -152.343639)
			(xy 67.914498 -152.347519) (xy 67.967756 -152.359096) (xy 68.018825 -152.378135) (xy 68.066663 -152.404249)
			(xy 68.110298 -152.436905) (xy 68.148841 -152.47544) (xy 68.181507 -152.519068) (xy 68.207631 -152.566901)
			(xy 68.226681 -152.617965) (xy 68.23827 -152.67122) (xy 68.242161 -152.725583) (xy 69.70792 -152.725583)
			(xy 69.71181 -152.671235) (xy 69.723395 -152.617993) (xy 69.742439 -152.566943) (xy 69.768554 -152.519122)
			(xy 69.80121 -152.475504) (xy 69.839741 -152.436978) (xy 69.883362 -152.404328) (xy 69.931186 -152.378219)
			(xy 69.982239 -152.359181) (xy 70.035482 -152.347603) (xy 70.089831 -152.34372) (xy 70.144179 -152.347612)
			(xy 70.19742 -152.359199) (xy 70.248471 -152.378245) (xy 70.29629 -152.404362) (xy 70.318376 -152.42032)
			(xy 70.337388 -152.433916) (xy 70.379271 -152.454648) (xy 70.424239 -152.467374) (xy 70.470776 -152.471664)
			(xy 70.517313 -152.467374) (xy 70.562281 -152.454648) (xy 70.604164 -152.433916) (xy 70.623176 -152.42032)
			(xy 70.645238 -152.40432) (xy 70.693067 -152.378192) (xy 70.744128 -152.359137) (xy 70.797381 -152.347543)
			(xy 70.851741 -152.343647) (xy 70.906103 -152.347527) (xy 70.95936 -152.359104) (xy 71.010426 -152.378143)
			(xy 71.058263 -152.404257) (xy 71.101896 -152.436913) (xy 71.140438 -152.475447) (xy 71.173102 -152.519074)
			(xy 71.199225 -152.566905) (xy 71.218275 -152.617968) (xy 71.229863 -152.671222) (xy 71.233753 -152.725583)
			(xy 71.229867 -152.779945) (xy 71.218284 -152.8332) (xy 71.199239 -152.884264) (xy 71.17312 -152.932098)
			(xy 71.14046 -152.975728) (xy 71.101922 -153.014265) (xy 71.058291 -153.046925) (xy 71.010457 -153.073043)
			(xy 70.959392 -153.092086) (xy 70.906137 -153.103669) (xy 70.851775 -153.107553) (xy 70.797414 -153.103662)
			(xy 70.74416 -153.092072) (xy 70.693098 -153.073022) (xy 70.645267 -153.046898) (xy 70.623176 -153.030936)
			(xy 70.604164 -153.01734) (xy 70.562281 -152.996608) (xy 70.517313 -152.983882) (xy 70.470776 -152.979592)
			(xy 70.424239 -152.983882) (xy 70.379271 -152.996608) (xy 70.337388 -153.01734) (xy 70.318376 -153.030936)
			(xy 70.296262 -153.046856) (xy 70.24844 -153.072969) (xy 70.197388 -153.092011) (xy 70.144146 -153.103593)
			(xy 70.089798 -153.10748) (xy 70.035449 -153.103592) (xy 69.982207 -153.092009) (xy 69.931156 -153.072967)
			(xy 69.883334 -153.046854) (xy 69.839715 -153.0142) (xy 69.801188 -152.97567) (xy 69.768536 -152.93205)
			(xy 69.742425 -152.884227) (xy 69.723385 -152.833174) (xy 69.711805 -152.779932) (xy 69.70792 -152.725583)
			(xy 68.242161 -152.725583) (xy 68.238274 -152.779946) (xy 68.226691 -152.833203) (xy 68.207645 -152.884269)
			(xy 68.181525 -152.932104) (xy 68.148863 -152.975735) (xy 68.110324 -153.014273) (xy 68.066692 -153.046933)
			(xy 68.018855 -153.073051) (xy 67.967789 -153.092095) (xy 67.914532 -153.103677) (xy 67.860168 -153.107561)
			(xy 67.805806 -153.103668) (xy 67.75255 -153.092077) (xy 67.701487 -153.073025) (xy 67.653655 -153.046899)
			(xy 67.631564 -153.030936) (xy 67.612552 -153.01734) (xy 67.570669 -152.996608) (xy 67.525701 -152.983882)
			(xy 67.479164 -152.979592) (xy 67.432627 -152.983882) (xy 67.387659 -152.996608) (xy 67.345776 -153.01734)
			(xy 67.326764 -153.030936) (xy 67.30465 -153.046855) (xy 67.256829 -153.072966) (xy 67.205778 -153.092006)
			(xy 67.152538 -153.103587) (xy 67.098191 -153.107473) (xy 67.043844 -153.103584) (xy 66.990604 -153.092001)
			(xy 66.939554 -153.072959) (xy 66.891734 -153.046845) (xy 66.848117 -153.014192) (xy 66.809591 -152.975663)
			(xy 66.776941 -152.932044) (xy 66.75083 -152.884222) (xy 66.731792 -152.833171) (xy 66.720212 -152.77993)
			(xy 66.716327 -152.725583) (xy 52.698367 -152.725583) (xy 52.694497 -152.726757) (xy 52.614946 -152.74258)
			(xy 52.534227 -152.75053) (xy 52.453117 -152.75053) (xy 52.372398 -152.74258) (xy 52.292847 -152.726757)
			(xy 52.215231 -152.703212) (xy 52.140295 -152.672173) (xy 52.068763 -152.633938) (xy 52.001323 -152.588876)
			(xy 51.938624 -152.537421) (xy 51.881271 -152.480068) (xy 51.829816 -152.417369) (xy 51.784754 -152.349929)
			(xy 51.746519 -152.278397) (xy 51.71548 -152.203461) (xy 51.691935 -152.125845) (xy 51.676112 -152.046294)
			(xy 51.668162 -151.965575) (xy 49.819062 -151.965575) (xy 49.811112 -152.046294) (xy 49.795289 -152.125845)
			(xy 49.771744 -152.203461) (xy 49.740705 -152.278397) (xy 49.70247 -152.349929) (xy 49.657408 -152.417369)
			(xy 49.605953 -152.480068) (xy 49.5486 -152.537421) (xy 49.485901 -152.588876) (xy 49.418461 -152.633938)
			(xy 49.346929 -152.672173) (xy 49.271993 -152.703212) (xy 49.194377 -152.726757) (xy 49.114826 -152.74258)
			(xy 49.034107 -152.75053) (xy 48.952997 -152.75053) (xy 48.872278 -152.74258) (xy 48.792727 -152.726757)
			(xy 48.715111 -152.703212) (xy 48.640175 -152.672173) (xy 48.568643 -152.633938) (xy 48.501203 -152.588876)
			(xy 48.438504 -152.537421) (xy 48.381151 -152.480068) (xy 48.329696 -152.417369) (xy 48.284634 -152.349929)
			(xy 48.246399 -152.278397) (xy 48.21536 -152.203461) (xy 48.191815 -152.125845) (xy 48.175992 -152.046294)
			(xy 48.168042 -151.965575) (xy 36.297736 -151.965575) (xy 36.263477 -152.010941) (xy 36.204933 -152.075161)
			(xy 36.140713 -152.133705) (xy 36.071366 -152.186074) (xy 35.997482 -152.231821) (xy 35.919693 -152.270555)
			(xy 35.838661 -152.301947) (xy 35.755079 -152.325728) (xy 35.669659 -152.341696) (xy 35.58313 -152.349714)
			(xy 35.49623 -152.349714) (xy 35.409701 -152.341696) (xy 35.324281 -152.325728) (xy 35.240699 -152.301947)
			(xy 35.159667 -152.270555) (xy 35.081878 -152.231821) (xy 35.007994 -152.186074) (xy 34.938647 -152.133705)
			(xy 34.874427 -152.075161) (xy 34.815883 -152.010941) (xy 34.763514 -151.941594) (xy 34.717767 -151.86771)
			(xy 34.679033 -151.789921) (xy 34.647641 -151.708889) (xy 34.62386 -151.625307) (xy 34.607892 -151.539887)
			(xy 34.599874 -151.453358) (xy 31.399486 -151.453358) (xy 31.391468 -151.539887) (xy 31.3755 -151.625307)
			(xy 31.351719 -151.708889) (xy 31.320327 -151.789921) (xy 31.281593 -151.86771) (xy 31.235846 -151.941594)
			(xy 31.183477 -152.010941) (xy 31.124933 -152.075161) (xy 31.060713 -152.133705) (xy 30.991366 -152.186074)
			(xy 30.917482 -152.231821) (xy 30.839693 -152.270555) (xy 30.758661 -152.301947) (xy 30.675079 -152.325728)
			(xy 30.589659 -152.341696) (xy 30.50313 -152.349714) (xy 30.41623 -152.349714) (xy 30.329701 -152.341696)
			(xy 30.244281 -152.325728) (xy 30.160699 -152.301947) (xy 30.079667 -152.270555) (xy 30.001878 -152.231821)
			(xy 29.927994 -152.186074) (xy 29.858647 -152.133705) (xy 29.794427 -152.075161) (xy 29.735883 -152.010941)
			(xy 29.683514 -151.941594) (xy 29.637767 -151.86771) (xy 29.599033 -151.789921) (xy 29.567641 -151.708889)
			(xy 29.54386 -151.625307) (xy 29.527892 -151.539887) (xy 29.519874 -151.453358) (xy 28.884372 -151.453358)
			(xy 28.884372 -153.993358) (xy 29.519874 -153.993358) (xy 29.519874 -153.906458) (xy 29.527892 -153.819929)
			(xy 29.54386 -153.734509) (xy 29.567641 -153.650927) (xy 29.599033 -153.569895) (xy 29.637767 -153.492106)
			(xy 29.683514 -153.418222) (xy 29.735883 -153.348875) (xy 29.794427 -153.284655) (xy 29.858647 -153.226111)
			(xy 29.927994 -153.173742) (xy 30.001878 -153.127995) (xy 30.079667 -153.089261) (xy 30.160699 -153.057869)
			(xy 30.244281 -153.034088) (xy 30.329701 -153.01812) (xy 30.41623 -153.010102) (xy 30.50313 -153.010102)
			(xy 30.589659 -153.01812) (xy 30.675079 -153.034088) (xy 30.758661 -153.057869) (xy 30.839693 -153.089261)
			(xy 30.917482 -153.127995) (xy 30.991366 -153.173742) (xy 31.060713 -153.226111) (xy 31.124933 -153.284655)
			(xy 31.183477 -153.348875) (xy 31.235846 -153.418222) (xy 31.281593 -153.492106) (xy 31.320327 -153.569895)
			(xy 31.351719 -153.650927) (xy 31.3755 -153.734509) (xy 31.391468 -153.819929) (xy 31.399486 -153.906458)
			(xy 31.399988 -153.949908) (xy 31.399486 -153.993358) (xy 34.599874 -153.993358) (xy 34.599874 -153.906458)
			(xy 34.607892 -153.819929) (xy 34.62386 -153.734509) (xy 34.647641 -153.650927) (xy 34.679033 -153.569895)
			(xy 34.717767 -153.492106) (xy 34.763514 -153.418222) (xy 34.815883 -153.348875) (xy 34.874427 -153.284655)
			(xy 34.938647 -153.226111) (xy 35.007994 -153.173742) (xy 35.081878 -153.127995) (xy 35.159667 -153.089261)
			(xy 35.240699 -153.057869) (xy 35.324281 -153.034088) (xy 35.409701 -153.01812) (xy 35.49623 -153.010102)
			(xy 35.58313 -153.010102) (xy 35.669659 -153.01812) (xy 35.755079 -153.034088) (xy 35.838661 -153.057869)
			(xy 35.919693 -153.089261) (xy 35.997482 -153.127995) (xy 36.071366 -153.173742) (xy 36.140713 -153.226111)
			(xy 36.204933 -153.284655) (xy 36.263477 -153.348875) (xy 36.315846 -153.418222) (xy 36.361593 -153.492106)
			(xy 36.400327 -153.569895) (xy 36.416745 -153.612275) (xy 39.565224 -153.612275) (xy 39.569115 -153.557927)
			(xy 39.580701 -153.504685) (xy 39.599747 -153.453635) (xy 39.625864 -153.405815) (xy 39.65852 -153.362198)
			(xy 39.697052 -153.323674) (xy 39.740675 -153.291025) (xy 39.7885 -153.264917) (xy 39.839554 -153.245881)
			(xy 39.892797 -153.234305) (xy 39.947146 -153.230424) (xy 40.001494 -153.234318) (xy 40.054735 -153.245907)
			(xy 40.105784 -153.264955) (xy 40.153603 -153.291075) (xy 40.175688 -153.307034) (xy 40.1947 -153.32063)
			(xy 40.236583 -153.341362) (xy 40.281551 -153.354088) (xy 40.328088 -153.358378) (xy 40.374625 -153.354088)
			(xy 40.419593 -153.341362) (xy 40.461476 -153.32063) (xy 40.480488 -153.307034) (xy 40.502537 -153.291016)
			(xy 40.550366 -153.264888) (xy 40.601426 -153.245833) (xy 40.654679 -153.234239) (xy 40.70904 -153.230343)
			(xy 40.763402 -153.234222) (xy 40.816658 -153.245799) (xy 40.867725 -153.264838) (xy 40.915562 -153.290951)
			(xy 40.959195 -153.323607) (xy 40.997737 -153.36214) (xy 41.030402 -153.405766) (xy 41.056526 -153.453598)
			(xy 41.075576 -153.50466) (xy 41.087166 -153.557914) (xy 41.091057 -153.612275) (xy 41.087173 -153.666636)
			(xy 41.075591 -153.719892) (xy 41.056547 -153.770957) (xy 41.03043 -153.818791) (xy 40.99777 -153.862422)
			(xy 40.959234 -153.90096) (xy 40.915604 -153.933621) (xy 40.867771 -153.959741) (xy 40.816707 -153.978786)
			(xy 40.763452 -153.99037) (xy 40.70909 -153.994257) (xy 40.654729 -153.990368) (xy 40.601475 -153.978781)
			(xy 40.550412 -153.959733) (xy 40.502579 -153.933611) (xy 40.480488 -153.91765) (xy 40.461476 -153.904054)
			(xy 40.419593 -153.883322) (xy 40.374625 -153.870596) (xy 40.328088 -153.866306) (xy 40.281551 -153.870596)
			(xy 40.236583 -153.883322) (xy 40.1947 -153.904054) (xy 40.175688 -153.91765) (xy 40.153561 -153.933552)
			(xy 40.105739 -153.959666) (xy 40.054687 -153.978707) (xy 40.001445 -153.990289) (xy 39.947096 -153.994176)
			(xy 39.892748 -153.990288) (xy 39.839506 -153.978705) (xy 39.788454 -153.959662) (xy 39.740633 -153.933548)
			(xy 39.697014 -153.900893) (xy 39.658487 -153.862364) (xy 39.625836 -153.818743) (xy 39.599726 -153.770919)
			(xy 39.580687 -153.719866) (xy 39.569108 -153.666624) (xy 39.565224 -153.612275) (xy 36.416745 -153.612275)
			(xy 36.431719 -153.650927) (xy 36.4555 -153.734509) (xy 36.471468 -153.819929) (xy 36.479486 -153.906458)
			(xy 36.479988 -153.949908) (xy 36.479486 -153.993358) (xy 36.471468 -154.079887) (xy 36.4555 -154.165307)
			(xy 36.431719 -154.248889) (xy 36.400327 -154.329921) (xy 36.361593 -154.40771) (xy 36.315846 -154.481594)
			(xy 36.263477 -154.550941) (xy 36.204933 -154.615161) (xy 36.140713 -154.673705) (xy 36.121153 -154.688476)
			(xy 66.716337 -154.688476) (xy 66.720227 -154.634131) (xy 66.731812 -154.580892) (xy 66.750856 -154.529845)
			(xy 66.776971 -154.482027) (xy 66.809625 -154.438412) (xy 66.848154 -154.399889) (xy 66.891774 -154.367241)
			(xy 66.939595 -154.341133) (xy 66.990646 -154.322097) (xy 67.043886 -154.310519) (xy 67.098232 -154.306637)
			(xy 67.152577 -154.310528) (xy 67.205815 -154.322114) (xy 67.256862 -154.341159) (xy 67.30468 -154.367275)
			(xy 67.326764 -154.383232) (xy 67.345776 -154.396828) (xy 67.387659 -154.41756) (xy 67.432627 -154.430286)
			(xy 67.479164 -154.434576) (xy 67.525701 -154.430286) (xy 67.570669 -154.41756) (xy 67.612552 -154.396828)
			(xy 67.631564 -154.383232) (xy 67.653616 -154.367215) (xy 67.701446 -154.341083) (xy 67.752509 -154.322025)
			(xy 67.805764 -154.310429) (xy 67.860127 -154.30653) (xy 67.914493 -154.310408) (xy 67.967752 -154.321984)
			(xy 68.018822 -154.341023) (xy 68.066662 -154.367137) (xy 68.110299 -154.399793) (xy 68.148844 -154.438328)
			(xy 68.181511 -154.481956) (xy 68.207637 -154.52979) (xy 68.226688 -154.580855) (xy 68.238278 -154.634112)
			(xy 68.24217 -154.688476) (xy 69.70793 -154.688476) (xy 69.71182 -154.634129) (xy 69.723406 -154.580889)
			(xy 69.74245 -154.52984) (xy 69.768566 -154.482021) (xy 69.801222 -154.438405) (xy 69.839752 -154.399881)
			(xy 69.883373 -154.367232) (xy 69.931197 -154.341124) (xy 69.982249 -154.322088) (xy 70.035491 -154.310511)
			(xy 70.089838 -154.30663) (xy 70.144185 -154.310522) (xy 70.197425 -154.32211) (xy 70.248473 -154.341156)
			(xy 70.296291 -154.367274) (xy 70.318376 -154.383232) (xy 70.337388 -154.396828) (xy 70.379271 -154.41756)
			(xy 70.424239 -154.430286) (xy 70.470776 -154.434576) (xy 70.517313 -154.430286) (xy 70.562281 -154.41756)
			(xy 70.604164 -154.396828) (xy 70.623176 -154.383232) (xy 70.645227 -154.367216) (xy 70.693057 -154.341086)
			(xy 70.744118 -154.32203) (xy 70.797372 -154.310435) (xy 70.851734 -154.306537) (xy 70.906098 -154.310416)
			(xy 70.959356 -154.321993) (xy 71.010424 -154.341032) (xy 71.058262 -154.367145) (xy 71.101897 -154.399801)
			(xy 71.14044 -154.438335) (xy 71.173106 -154.481962) (xy 71.199231 -154.529795) (xy 71.218282 -154.580858)
			(xy 71.229871 -154.634113) (xy 71.233763 -154.688476) (xy 71.229878 -154.742839) (xy 71.218295 -154.796096)
			(xy 71.199251 -154.847162) (xy 71.173132 -154.894997) (xy 71.140472 -154.938629) (xy 71.101933 -154.977167)
			(xy 71.058303 -155.009829) (xy 71.010467 -155.035948) (xy 70.959402 -155.054994) (xy 70.906145 -155.066577)
			(xy 70.851782 -155.070463) (xy 70.79742 -155.066572) (xy 70.744164 -155.054984) (xy 70.6931 -155.035934)
			(xy 70.645268 -155.00981) (xy 70.623176 -154.993848) (xy 70.604164 -154.980252) (xy 70.562281 -154.95952)
			(xy 70.517313 -154.946794) (xy 70.470776 -154.942504) (xy 70.424239 -154.946794) (xy 70.379271 -154.95952)
			(xy 70.337388 -154.980252) (xy 70.318376 -154.993848) (xy 70.296251 -155.009752) (xy 70.248429 -155.035864)
			(xy 70.197379 -155.054904) (xy 70.144138 -155.066484) (xy 70.08979 -155.07037) (xy 70.035443 -155.066482)
			(xy 69.982203 -155.054898) (xy 69.931153 -155.035856) (xy 69.883333 -155.009742) (xy 69.839716 -154.977088)
			(xy 69.80119 -154.938559) (xy 69.76854 -154.894939) (xy 69.74243 -154.847116) (xy 69.723392 -154.796065)
			(xy 69.711814 -154.742823) (xy 69.70793 -154.688476) (xy 68.24217 -154.688476) (xy 68.238285 -154.742841)
			(xy 68.226702 -154.796099) (xy 68.207657 -154.847166) (xy 68.181537 -154.895003) (xy 68.148875 -154.938636)
			(xy 68.110335 -154.977175) (xy 68.066703 -155.009837) (xy 68.018866 -155.035957) (xy 67.967798 -155.055002)
			(xy 67.91454 -155.066585) (xy 67.860175 -155.07047) (xy 67.805811 -155.066578) (xy 67.752555 -155.054988)
			(xy 67.70149 -155.035937) (xy 67.653656 -155.009811) (xy 67.631564 -154.993848) (xy 67.612552 -154.980252)
			(xy 67.570669 -154.95952) (xy 67.525701 -154.946794) (xy 67.479164 -154.942504) (xy 67.432627 -154.946794)
			(xy 67.387659 -154.95952) (xy 67.345776 -154.980252) (xy 67.326764 -154.993848) (xy 67.304639 -155.009751)
			(xy 67.256819 -155.035861) (xy 67.205769 -155.054899) (xy 67.152529 -155.066478) (xy 67.098184 -155.070363)
			(xy 67.043838 -155.066474) (xy 66.9906 -155.05489) (xy 66.939552 -155.035847) (xy 66.891733 -155.009733)
			(xy 66.848118 -154.97708) (xy 66.809594 -154.938551) (xy 66.776945 -154.894933) (xy 66.750836 -154.847112)
			(xy 66.731799 -154.796062) (xy 66.720221 -154.742822) (xy 66.716337 -154.688476) (xy 36.121153 -154.688476)
			(xy 36.071366 -154.726074) (xy 35.997482 -154.771821) (xy 35.919693 -154.810555) (xy 35.838661 -154.841947)
			(xy 35.755079 -154.865728) (xy 35.669659 -154.881696) (xy 35.58313 -154.889714) (xy 35.49623 -154.889714)
			(xy 35.409701 -154.881696) (xy 35.324281 -154.865728) (xy 35.240699 -154.841947) (xy 35.159667 -154.810555)
			(xy 35.081878 -154.771821) (xy 35.007994 -154.726074) (xy 34.938647 -154.673705) (xy 34.874427 -154.615161)
			(xy 34.815883 -154.550941) (xy 34.763514 -154.481594) (xy 34.717767 -154.40771) (xy 34.679033 -154.329921)
			(xy 34.647641 -154.248889) (xy 34.62386 -154.165307) (xy 34.607892 -154.079887) (xy 34.599874 -153.993358)
			(xy 31.399486 -153.993358) (xy 31.391468 -154.079887) (xy 31.3755 -154.165307) (xy 31.351719 -154.248889)
			(xy 31.320327 -154.329921) (xy 31.281593 -154.40771) (xy 31.235846 -154.481594) (xy 31.183477 -154.550941)
			(xy 31.124933 -154.615161) (xy 31.060713 -154.673705) (xy 30.991366 -154.726074) (xy 30.917482 -154.771821)
			(xy 30.839693 -154.810555) (xy 30.758661 -154.841947) (xy 30.675079 -154.865728) (xy 30.589659 -154.881696)
			(xy 30.50313 -154.889714) (xy 30.41623 -154.889714) (xy 30.329701 -154.881696) (xy 30.244281 -154.865728)
			(xy 30.160699 -154.841947) (xy 30.079667 -154.810555) (xy 30.001878 -154.771821) (xy 29.927994 -154.726074)
			(xy 29.858647 -154.673705) (xy 29.794427 -154.615161) (xy 29.735883 -154.550941) (xy 29.683514 -154.481594)
			(xy 29.637767 -154.40771) (xy 29.599033 -154.329921) (xy 29.567641 -154.248889) (xy 29.54386 -154.165307)
			(xy 29.527892 -154.079887) (xy 29.519874 -153.993358) (xy 28.884372 -153.993358) (xy 28.884372 -156.533358)
			(xy 29.519874 -156.533358) (xy 29.519874 -156.446458) (xy 29.527892 -156.359929) (xy 29.54386 -156.274509)
			(xy 29.567641 -156.190927) (xy 29.599033 -156.109895) (xy 29.637767 -156.032106) (xy 29.683514 -155.958222)
			(xy 29.735883 -155.888875) (xy 29.794427 -155.824655) (xy 29.858647 -155.766111) (xy 29.927994 -155.713742)
			(xy 30.001878 -155.667995) (xy 30.079667 -155.629261) (xy 30.160699 -155.597869) (xy 30.244281 -155.574088)
			(xy 30.329701 -155.55812) (xy 30.41623 -155.550102) (xy 30.50313 -155.550102) (xy 30.589659 -155.55812)
			(xy 30.675079 -155.574088) (xy 30.758661 -155.597869) (xy 30.839693 -155.629261) (xy 30.917482 -155.667995)
			(xy 30.991366 -155.713742) (xy 31.060713 -155.766111) (xy 31.124933 -155.824655) (xy 31.183477 -155.888875)
			(xy 31.235846 -155.958222) (xy 31.281593 -156.032106) (xy 31.320327 -156.109895) (xy 31.351719 -156.190927)
			(xy 31.3755 -156.274509) (xy 31.391468 -156.359929) (xy 31.399486 -156.446458) (xy 31.399988 -156.489908)
			(xy 31.399486 -156.533358) (xy 34.599874 -156.533358) (xy 34.599874 -156.446458) (xy 34.607892 -156.359929)
			(xy 34.62386 -156.274509) (xy 34.647641 -156.190927) (xy 34.679033 -156.109895) (xy 34.717767 -156.032106)
			(xy 34.763514 -155.958222) (xy 34.815883 -155.888875) (xy 34.874427 -155.824655) (xy 34.938647 -155.766111)
			(xy 35.007994 -155.713742) (xy 35.081878 -155.667995) (xy 35.159667 -155.629261) (xy 35.240699 -155.597869)
			(xy 35.324281 -155.574088) (xy 35.409701 -155.55812) (xy 35.49623 -155.550102) (xy 35.58313 -155.550102)
			(xy 35.669659 -155.55812) (xy 35.755079 -155.574088) (xy 35.838661 -155.597869) (xy 35.919693 -155.629261)
			(xy 35.997482 -155.667995) (xy 36.071366 -155.713742) (xy 36.140713 -155.766111) (xy 36.204933 -155.824655)
			(xy 36.226034 -155.847802) (xy 39.565187 -155.847802) (xy 39.569075 -155.793449) (xy 39.580658 -155.740201)
			(xy 39.599702 -155.689145) (xy 39.625818 -155.641318) (xy 39.658475 -155.597695) (xy 39.697007 -155.559164)
			(xy 39.740632 -155.526509) (xy 39.78846 -155.500395) (xy 39.839517 -155.481353) (xy 39.892765 -155.469772)
			(xy 39.947119 -155.465887) (xy 40.001472 -155.469778) (xy 40.054719 -155.481364) (xy 40.105775 -155.50041)
			(xy 40.1536 -155.526529) (xy 40.175688 -155.542488) (xy 40.1947 -155.556084) (xy 40.236583 -155.576816)
			(xy 40.281551 -155.589542) (xy 40.328088 -155.593832) (xy 40.374625 -155.589542) (xy 40.419593 -155.576816)
			(xy 40.461476 -155.556084) (xy 40.480488 -155.542488) (xy 40.50258 -155.526532) (xy 40.550406 -155.50041)
			(xy 40.601463 -155.481361) (xy 40.654712 -155.469772) (xy 40.709068 -155.465879) (xy 40.763424 -155.469763)
			(xy 40.816674 -155.481343) (xy 40.867735 -155.500383) (xy 40.915565 -155.526497) (xy 40.959192 -155.559153)
			(xy 40.997727 -155.597685) (xy 41.030386 -155.64131) (xy 41.056504 -155.689138) (xy 41.075549 -155.740197)
			(xy 41.087133 -155.793446) (xy 41.091021 -155.847802) (xy 41.087132 -155.902158) (xy 41.075548 -155.955408)
			(xy 41.056502 -156.006466) (xy 41.030384 -156.054295) (xy 40.997724 -156.097919) (xy 40.959189 -156.13645)
			(xy 40.915561 -156.169105) (xy 40.86773 -156.195219) (xy 40.81667 -156.214259) (xy 40.763419 -156.225838)
			(xy 40.709063 -156.229721) (xy 40.654707 -156.225827) (xy 40.601459 -156.214238) (xy 40.550402 -156.195188)
			(xy 40.502576 -156.169065) (xy 40.480488 -156.153104) (xy 40.461476 -156.139508) (xy 40.419593 -156.118776)
			(xy 40.374625 -156.10605) (xy 40.328088 -156.10176) (xy 40.281551 -156.10605) (xy 40.236583 -156.118776)
			(xy 40.1947 -156.139508) (xy 40.175688 -156.153104) (xy 40.153604 -156.169068) (xy 40.105779 -156.195188)
			(xy 40.054724 -156.214235) (xy 40.001477 -156.225822) (xy 39.947124 -156.229713) (xy 39.89277 -156.225828)
			(xy 39.839522 -156.214248) (xy 39.788464 -156.195207) (xy 39.740636 -156.169094) (xy 39.697011 -156.136439)
			(xy 39.658478 -156.097909) (xy 39.62582 -156.054286) (xy 39.599704 -156.00646) (xy 39.580659 -155.955403)
			(xy 39.569075 -155.902156) (xy 39.565187 -155.847802) (xy 36.226034 -155.847802) (xy 36.263477 -155.888875)
			(xy 36.315846 -155.958222) (xy 36.361593 -156.032106) (xy 36.400327 -156.109895) (xy 36.431719 -156.190927)
			(xy 36.4555 -156.274509) (xy 36.471468 -156.359929) (xy 36.479486 -156.446458) (xy 36.479988 -156.489908)
			(xy 36.479486 -156.533358) (xy 36.471468 -156.619887) (xy 36.4555 -156.705307) (xy 36.431719 -156.788889)
			(xy 36.415029 -156.831972) (xy 66.716342 -156.831972) (xy 66.720233 -156.777628) (xy 66.731818 -156.72439)
			(xy 66.750862 -156.673343) (xy 66.776977 -156.625526) (xy 66.809631 -156.581913) (xy 66.84816 -156.54339)
			(xy 66.891779 -156.510743) (xy 66.939601 -156.484636) (xy 66.990651 -156.4656) (xy 67.04389 -156.454024)
			(xy 67.098235 -156.450142) (xy 67.15258 -156.454034) (xy 67.205817 -156.46562) (xy 67.256863 -156.484665)
			(xy 67.30468 -156.510781) (xy 67.326764 -156.526738) (xy 67.345776 -156.540334) (xy 67.387659 -156.561066)
			(xy 67.432627 -156.573792) (xy 67.479164 -156.578082) (xy 67.525701 -156.573792) (xy 67.570669 -156.561066)
			(xy 67.612552 -156.540334) (xy 67.631564 -156.526738) (xy 67.65361 -156.510713) (xy 67.701441 -156.484581)
			(xy 67.752504 -156.465522) (xy 67.80576 -156.453925) (xy 67.860124 -156.450025) (xy 67.91449 -156.453903)
			(xy 67.96775 -156.465479) (xy 68.018821 -156.484517) (xy 68.066662 -156.510631) (xy 68.1103 -156.543287)
			(xy 68.148845 -156.581822) (xy 68.181513 -156.625451) (xy 68.20764 -156.673285) (xy 68.226692 -156.72435)
			(xy 68.238282 -156.777608) (xy 68.242175 -156.831972) (xy 69.707935 -156.831972) (xy 69.711826 -156.777626)
			(xy 69.723411 -156.724387) (xy 69.742456 -156.673339) (xy 69.768572 -156.62552) (xy 69.801228 -156.581906)
			(xy 69.839758 -156.543382) (xy 69.883379 -156.510735) (xy 69.931202 -156.484627) (xy 69.982254 -156.465592)
			(xy 70.035495 -156.454016) (xy 70.089842 -156.450135) (xy 70.144188 -156.454028) (xy 70.197427 -156.465615)
			(xy 70.248474 -156.484662) (xy 70.296292 -156.51078) (xy 70.318376 -156.526738) (xy 70.337388 -156.540334)
			(xy 70.379271 -156.561066) (xy 70.424239 -156.573792) (xy 70.470776 -156.578082) (xy 70.517313 -156.573792)
			(xy 70.562281 -156.561066) (xy 70.604164 -156.540334) (xy 70.623176 -156.526738) (xy 70.645222 -156.510714)
			(xy 70.693051 -156.484583) (xy 70.744113 -156.465526) (xy 70.797368 -156.453931) (xy 70.851731 -156.450032)
			(xy 70.906095 -156.453911) (xy 70.959354 -156.465487) (xy 71.010422 -156.484526) (xy 71.058262 -156.510639)
			(xy 71.101898 -156.543295) (xy 71.140441 -156.581829) (xy 71.173109 -156.625457) (xy 71.199234 -156.673289)
			(xy 71.218285 -156.724353) (xy 71.229875 -156.777609) (xy 71.233768 -156.831972) (xy 71.229883 -156.886336)
			(xy 71.218301 -156.939594) (xy 71.199257 -156.99066) (xy 71.173138 -157.038497) (xy 71.140478 -157.082129)
			(xy 71.101939 -157.120669) (xy 71.058308 -157.153331) (xy 71.010473 -157.179451) (xy 70.959407 -157.198497)
			(xy 70.906149 -157.210081) (xy 70.851786 -157.213968) (xy 70.797423 -157.210077) (xy 70.744166 -157.198489)
			(xy 70.693102 -157.179439) (xy 70.645268 -157.153316) (xy 70.623176 -157.137354) (xy 70.604164 -157.123758)
			(xy 70.562281 -157.103026) (xy 70.517313 -157.0903) (xy 70.470776 -157.08601) (xy 70.424239 -157.0903)
			(xy 70.379271 -157.103026) (xy 70.337388 -157.123758) (xy 70.318376 -157.137354) (xy 70.296245 -157.15325)
			(xy 70.248424 -157.179361) (xy 70.197374 -157.1984) (xy 70.144133 -157.20998) (xy 70.089787 -157.213865)
			(xy 70.035441 -157.209976) (xy 69.982201 -157.198393) (xy 69.931152 -157.17935) (xy 69.883333 -157.153236)
			(xy 69.839716 -157.120582) (xy 69.801192 -157.082053) (xy 69.768542 -157.038433) (xy 69.742433 -156.990611)
			(xy 69.723396 -156.93956) (xy 69.711818 -156.886319) (xy 69.707935 -156.831972) (xy 68.242175 -156.831972)
			(xy 68.23829 -156.886338) (xy 68.226708 -156.939597) (xy 68.207663 -156.990665) (xy 68.181543 -157.038503)
			(xy 68.148881 -157.082136) (xy 68.110341 -157.120677) (xy 68.066708 -157.15334) (xy 68.018871 -157.17946)
			(xy 67.967803 -157.198506) (xy 67.914544 -157.210089) (xy 67.860179 -157.213975) (xy 67.805814 -157.210083)
			(xy 67.752557 -157.198494) (xy 67.701491 -157.179442) (xy 67.653656 -157.153317) (xy 67.631564 -157.137354)
			(xy 67.612552 -157.123758) (xy 67.570669 -157.103026) (xy 67.525701 -157.0903) (xy 67.479164 -157.08601)
			(xy 67.432627 -157.0903) (xy 67.387659 -157.103026) (xy 67.345776 -157.123758) (xy 67.326764 -157.137354)
			(xy 67.304634 -157.153249) (xy 67.256813 -157.179358) (xy 67.205764 -157.198395) (xy 67.152525 -157.209974)
			(xy 67.09818 -157.213858) (xy 67.043835 -157.209968) (xy 66.990598 -157.198384) (xy 66.93955 -157.179341)
			(xy 66.891733 -157.153227) (xy 66.848118 -157.120574) (xy 66.809595 -157.082046) (xy 66.776947 -157.038427)
			(xy 66.750839 -156.990606) (xy 66.731802 -156.939557) (xy 66.720225 -156.886317) (xy 66.716342 -156.831972)
			(xy 36.415029 -156.831972) (xy 36.400327 -156.869921) (xy 36.361593 -156.94771) (xy 36.315846 -157.021594)
			(xy 36.263477 -157.090941) (xy 36.204933 -157.155161) (xy 36.140713 -157.213705) (xy 36.071366 -157.266074)
			(xy 35.997482 -157.311821) (xy 35.919693 -157.350555) (xy 35.838661 -157.381947) (xy 35.755079 -157.405728)
			(xy 35.669659 -157.421696) (xy 35.58313 -157.429714) (xy 35.49623 -157.429714) (xy 35.409701 -157.421696)
			(xy 35.324281 -157.405728) (xy 35.240699 -157.381947) (xy 35.159667 -157.350555) (xy 35.081878 -157.311821)
			(xy 35.007994 -157.266074) (xy 34.938647 -157.213705) (xy 34.874427 -157.155161) (xy 34.815883 -157.090941)
			(xy 34.763514 -157.021594) (xy 34.717767 -156.94771) (xy 34.679033 -156.869921) (xy 34.647641 -156.788889)
			(xy 34.62386 -156.705307) (xy 34.607892 -156.619887) (xy 34.599874 -156.533358) (xy 31.399486 -156.533358)
			(xy 31.391468 -156.619887) (xy 31.3755 -156.705307) (xy 31.351719 -156.788889) (xy 31.320327 -156.869921)
			(xy 31.281593 -156.94771) (xy 31.235846 -157.021594) (xy 31.183477 -157.090941) (xy 31.124933 -157.155161)
			(xy 31.060713 -157.213705) (xy 30.991366 -157.266074) (xy 30.917482 -157.311821) (xy 30.839693 -157.350555)
			(xy 30.758661 -157.381947) (xy 30.675079 -157.405728) (xy 30.589659 -157.421696) (xy 30.50313 -157.429714)
			(xy 30.41623 -157.429714) (xy 30.329701 -157.421696) (xy 30.244281 -157.405728) (xy 30.160699 -157.381947)
			(xy 30.079667 -157.350555) (xy 30.001878 -157.311821) (xy 29.927994 -157.266074) (xy 29.858647 -157.213705)
			(xy 29.794427 -157.155161) (xy 29.735883 -157.090941) (xy 29.683514 -157.021594) (xy 29.637767 -156.94771)
			(xy 29.599033 -156.869921) (xy 29.567641 -156.788889) (xy 29.54386 -156.705307) (xy 29.527892 -156.619887)
			(xy 29.519874 -156.533358) (xy 28.884372 -156.533358) (xy 28.884372 -159.073358) (xy 29.519874 -159.073358)
			(xy 29.519874 -158.986458) (xy 29.527892 -158.899929) (xy 29.54386 -158.814509) (xy 29.567641 -158.730927)
			(xy 29.599033 -158.649895) (xy 29.637767 -158.572106) (xy 29.683514 -158.498222) (xy 29.735883 -158.428875)
			(xy 29.794427 -158.364655) (xy 29.858647 -158.306111) (xy 29.927994 -158.253742) (xy 30.001878 -158.207995)
			(xy 30.079667 -158.169261) (xy 30.160699 -158.137869) (xy 30.244281 -158.114088) (xy 30.329701 -158.09812)
			(xy 30.41623 -158.090102) (xy 30.50313 -158.090102) (xy 30.589659 -158.09812) (xy 30.675079 -158.114088)
			(xy 30.758661 -158.137869) (xy 30.839693 -158.169261) (xy 30.917482 -158.207995) (xy 30.991366 -158.253742)
			(xy 31.060713 -158.306111) (xy 31.124933 -158.364655) (xy 31.183477 -158.428875) (xy 31.235846 -158.498222)
			(xy 31.281593 -158.572106) (xy 31.320327 -158.649895) (xy 31.351719 -158.730927) (xy 31.3755 -158.814509)
			(xy 31.391468 -158.899929) (xy 31.399486 -158.986458) (xy 31.399988 -159.029908) (xy 31.399486 -159.073358)
			(xy 34.599874 -159.073358) (xy 34.599874 -158.986458) (xy 34.607892 -158.899929) (xy 34.62386 -158.814509)
			(xy 34.647641 -158.730927) (xy 34.679033 -158.649895) (xy 34.717767 -158.572106) (xy 34.763514 -158.498222)
			(xy 34.815883 -158.428875) (xy 34.874427 -158.364655) (xy 34.938647 -158.306111) (xy 35.007994 -158.253742)
			(xy 35.081878 -158.207995) (xy 35.159667 -158.169261) (xy 35.240699 -158.137869) (xy 35.324281 -158.114088)
			(xy 35.409701 -158.09812) (xy 35.49623 -158.090102) (xy 35.58313 -158.090102) (xy 35.669659 -158.09812)
			(xy 35.755079 -158.114088) (xy 35.838661 -158.137869) (xy 35.919693 -158.169261) (xy 35.997482 -158.207995)
			(xy 36.071366 -158.253742) (xy 36.140713 -158.306111) (xy 36.204933 -158.364655) (xy 36.263477 -158.428875)
			(xy 36.315846 -158.498222) (xy 36.326928 -158.51612) (xy 39.565163 -158.51612) (xy 39.569048 -158.461763)
			(xy 39.58063 -158.408512) (xy 39.599672 -158.357451) (xy 39.625788 -158.30962) (xy 39.658445 -158.265993)
			(xy 39.696978 -158.227457) (xy 39.740604 -158.194798) (xy 39.788433 -158.16868) (xy 39.839493 -158.149635)
			(xy 39.892744 -158.138051) (xy 39.947101 -158.134163) (xy 40.001458 -158.138051) (xy 40.054708 -158.149636)
			(xy 40.105768 -158.168681) (xy 40.153598 -158.194799) (xy 40.175688 -158.210758) (xy 40.1947 -158.224354)
			(xy 40.236583 -158.245086) (xy 40.281551 -158.257812) (xy 40.328088 -158.262102) (xy 40.374625 -158.257812)
			(xy 40.419593 -158.245086) (xy 40.461476 -158.224354) (xy 40.480488 -158.210758) (xy 40.502608 -158.194843)
			(xy 40.550433 -158.168725) (xy 40.601487 -158.149679) (xy 40.654733 -158.138093) (xy 40.709086 -158.134204)
			(xy 40.763438 -158.138089) (xy 40.816685 -158.149671) (xy 40.867741 -158.168713) (xy 40.915567 -158.194827)
			(xy 40.95919 -158.227483) (xy 40.997721 -158.266014) (xy 41.030376 -158.309638) (xy 41.05649 -158.357464)
			(xy 41.075531 -158.408521) (xy 41.087112 -158.461768) (xy 41.090996 -158.51612) (xy 41.087106 -158.570473)
			(xy 41.075519 -158.623718) (xy 41.056473 -158.674773) (xy 41.030354 -158.722597) (xy 40.997694 -158.766216)
			(xy 40.959159 -158.804744) (xy 40.915533 -158.837395) (xy 40.867704 -158.863504) (xy 40.816646 -158.882541)
			(xy 40.763398 -158.894117) (xy 40.709045 -158.897996) (xy 40.654693 -158.894101) (xy 40.601448 -158.88251)
			(xy 40.550396 -158.863458) (xy 40.502574 -158.837335) (xy 40.480488 -158.821374) (xy 40.461476 -158.807778)
			(xy 40.419593 -158.787046) (xy 40.374625 -158.77432) (xy 40.328088 -158.77003) (xy 40.281551 -158.77432)
			(xy 40.236583 -158.787046) (xy 40.1947 -158.807778) (xy 40.175688 -158.821374) (xy 40.153632 -158.837379)
			(xy 40.105805 -158.863502) (xy 40.054748 -158.882553) (xy 40.001498 -158.894143) (xy 39.947142 -158.898037)
			(xy 39.892784 -158.894155) (xy 39.839532 -158.882576) (xy 39.78847 -158.863537) (xy 39.740638 -158.837424)
			(xy 39.697009 -158.804769) (xy 39.658471 -158.766238) (xy 39.62581 -158.722614) (xy 39.599689 -158.674786)
			(xy 39.580641 -158.623727) (xy 39.569054 -158.570477) (xy 39.565163 -158.51612) (xy 36.326928 -158.51612)
			(xy 36.361593 -158.572106) (xy 36.400327 -158.649895) (xy 36.431719 -158.730927) (xy 36.4555 -158.814509)
			(xy 36.471468 -158.899929) (xy 36.479486 -158.986458) (xy 36.479988 -159.029908) (xy 36.479486 -159.073358)
			(xy 36.471468 -159.159887) (xy 36.4555 -159.245307) (xy 36.431719 -159.328889) (xy 36.400327 -159.409921)
			(xy 36.361593 -159.48771) (xy 36.315846 -159.561594) (xy 36.263477 -159.630941) (xy 36.204933 -159.695161)
			(xy 36.140713 -159.753705) (xy 36.071366 -159.806074) (xy 35.997482 -159.851821) (xy 35.919693 -159.890555)
			(xy 35.838661 -159.921947) (xy 35.755079 -159.945728) (xy 35.669659 -159.961696) (xy 35.58313 -159.969714)
			(xy 35.49623 -159.969714) (xy 35.409701 -159.961696) (xy 35.324281 -159.945728) (xy 35.240699 -159.921947)
			(xy 35.159667 -159.890555) (xy 35.081878 -159.851821) (xy 35.007994 -159.806074) (xy 34.938647 -159.753705)
			(xy 34.874427 -159.695161) (xy 34.815883 -159.630941) (xy 34.763514 -159.561594) (xy 34.717767 -159.48771)
			(xy 34.679033 -159.409921) (xy 34.647641 -159.328889) (xy 34.62386 -159.245307) (xy 34.607892 -159.159887)
			(xy 34.599874 -159.073358) (xy 31.399486 -159.073358) (xy 31.391468 -159.159887) (xy 31.3755 -159.245307)
			(xy 31.351719 -159.328889) (xy 31.320327 -159.409921) (xy 31.281593 -159.48771) (xy 31.235846 -159.561594)
			(xy 31.183477 -159.630941) (xy 31.124933 -159.695161) (xy 31.060713 -159.753705) (xy 30.991366 -159.806074)
			(xy 30.917482 -159.851821) (xy 30.839693 -159.890555) (xy 30.758661 -159.921947) (xy 30.675079 -159.945728)
			(xy 30.589659 -159.961696) (xy 30.50313 -159.969714) (xy 30.41623 -159.969714) (xy 30.329701 -159.961696)
			(xy 30.244281 -159.945728) (xy 30.160699 -159.921947) (xy 30.079667 -159.890555) (xy 30.001878 -159.851821)
			(xy 29.927994 -159.806074) (xy 29.858647 -159.753705) (xy 29.794427 -159.695161) (xy 29.735883 -159.630941)
			(xy 29.683514 -159.561594) (xy 29.637767 -159.48771) (xy 29.599033 -159.409921) (xy 29.567641 -159.328889)
			(xy 29.54386 -159.245307) (xy 29.527892 -159.159887) (xy 29.519874 -159.073358) (xy 28.884372 -159.073358)
			(xy 28.884372 -161.613358) (xy 29.519874 -161.613358) (xy 29.519874 -161.526458) (xy 29.527892 -161.439929)
			(xy 29.54386 -161.354509) (xy 29.567641 -161.270927) (xy 29.599033 -161.189895) (xy 29.637767 -161.112106)
			(xy 29.683514 -161.038222) (xy 29.735883 -160.968875) (xy 29.794427 -160.904655) (xy 29.858647 -160.846111)
			(xy 29.927994 -160.793742) (xy 30.001878 -160.747995) (xy 30.079667 -160.709261) (xy 30.160699 -160.677869)
			(xy 30.244281 -160.654088) (xy 30.329701 -160.63812) (xy 30.41623 -160.630102) (xy 30.50313 -160.630102)
			(xy 30.589659 -160.63812) (xy 30.675079 -160.654088) (xy 30.758661 -160.677869) (xy 30.839693 -160.709261)
			(xy 30.917482 -160.747995) (xy 30.991366 -160.793742) (xy 31.060713 -160.846111) (xy 31.124933 -160.904655)
			(xy 31.183477 -160.968875) (xy 31.235846 -161.038222) (xy 31.281593 -161.112106) (xy 31.320327 -161.189895)
			(xy 31.351719 -161.270927) (xy 31.3755 -161.354509) (xy 31.391468 -161.439929) (xy 31.399486 -161.526458)
			(xy 31.399988 -161.569908) (xy 31.399486 -161.613358) (xy 34.599874 -161.613358) (xy 34.599874 -161.526458)
			(xy 34.607892 -161.439929) (xy 34.62386 -161.354509) (xy 34.647641 -161.270927) (xy 34.679033 -161.189895)
			(xy 34.717767 -161.112106) (xy 34.763514 -161.038222) (xy 34.815883 -160.968875) (xy 34.874427 -160.904655)
			(xy 34.938647 -160.846111) (xy 35.007994 -160.793742) (xy 35.081878 -160.747995) (xy 35.159667 -160.709261)
			(xy 35.240699 -160.677869) (xy 35.324281 -160.654088) (xy 35.409701 -160.63812) (xy 35.49623 -160.630102)
			(xy 35.58313 -160.630102) (xy 35.669659 -160.63812) (xy 35.755079 -160.654088) (xy 35.838661 -160.677869)
			(xy 35.919693 -160.709261) (xy 35.997482 -160.747995) (xy 36.071366 -160.793742) (xy 36.140713 -160.846111)
			(xy 36.186358 -160.887722) (xy 39.565162 -160.887722) (xy 39.569047 -160.833364) (xy 39.580628 -160.780113)
			(xy 39.59967 -160.729052) (xy 39.625786 -160.68122) (xy 39.658443 -160.637593) (xy 39.696976 -160.599057)
			(xy 39.740602 -160.566398) (xy 39.788432 -160.540279) (xy 39.839492 -160.521234) (xy 39.892742 -160.50965)
			(xy 39.9471 -160.505762) (xy 40.001457 -160.50965) (xy 40.054708 -160.521234) (xy 40.105768 -160.540279)
			(xy 40.153598 -160.566397) (xy 40.175688 -160.582356) (xy 40.1947 -160.595952) (xy 40.236583 -160.616684)
			(xy 40.281551 -160.62941) (xy 40.328088 -160.6337) (xy 40.374625 -160.62941) (xy 40.419593 -160.616684)
			(xy 40.461476 -160.595952) (xy 40.480488 -160.582356) (xy 40.50261 -160.566444) (xy 40.550434 -160.540326)
			(xy 40.601489 -160.52128) (xy 40.654734 -160.509695) (xy 40.709087 -160.505805) (xy 40.763439 -160.509691)
			(xy 40.816686 -160.521273) (xy 40.867741 -160.540315) (xy 40.915567 -160.566429) (xy 40.95919 -160.599085)
			(xy 40.997721 -160.637616) (xy 41.030375 -160.68124) (xy 41.056489 -160.729066) (xy 41.07553 -160.780122)
			(xy 41.08711 -160.833369) (xy 41.090995 -160.887722) (xy 41.087104 -160.942074) (xy 41.075518 -160.995319)
			(xy 41.056471 -161.046373) (xy 41.030352 -161.094197) (xy 40.997692 -161.137816) (xy 40.959157 -161.176344)
			(xy 40.915531 -161.208994) (xy 40.867702 -161.235103) (xy 40.816644 -161.25414) (xy 40.763397 -161.265715)
			(xy 40.709044 -161.269595) (xy 40.654692 -161.265699) (xy 40.601448 -161.254108) (xy 40.550395 -161.235056)
			(xy 40.502574 -161.208933) (xy 40.480488 -161.192972) (xy 40.461476 -161.179376) (xy 40.419593 -161.158644)
			(xy 40.374625 -161.145918) (xy 40.328088 -161.141628) (xy 40.281551 -161.145918) (xy 40.236583 -161.158644)
			(xy 40.1947 -161.179376) (xy 40.175688 -161.192972) (xy 40.153634 -161.208979) (xy 40.105807 -161.235103)
			(xy 40.054749 -161.254154) (xy 40.0015 -161.265744) (xy 39.947143 -161.269638) (xy 39.892785 -161.265756)
			(xy 39.839533 -161.254178) (xy 39.788471 -161.235139) (xy 39.740638 -161.209026) (xy 39.697009 -161.176371)
			(xy 39.658471 -161.13784) (xy 39.625809 -161.094216) (xy 39.599688 -161.046388) (xy 39.58064 -160.995329)
			(xy 39.569053 -160.942079) (xy 39.565162 -160.887722) (xy 36.186358 -160.887722) (xy 36.204933 -160.904655)
			(xy 36.263477 -160.968875) (xy 36.315846 -161.038222) (xy 36.361593 -161.112106) (xy 36.400327 -161.189895)
			(xy 36.431719 -161.270927) (xy 36.4555 -161.354509) (xy 36.471468 -161.439929) (xy 36.479486 -161.526458)
			(xy 36.479988 -161.569908) (xy 36.479486 -161.613358) (xy 36.471468 -161.699887) (xy 36.4555 -161.785307)
			(xy 36.431719 -161.868889) (xy 36.400327 -161.949921) (xy 36.361593 -162.02771) (xy 36.315846 -162.101594)
			(xy 36.263477 -162.170941) (xy 36.204933 -162.235161) (xy 36.140713 -162.293705) (xy 36.071366 -162.346074)
			(xy 35.997482 -162.391821) (xy 35.919693 -162.430555) (xy 35.838661 -162.461947) (xy 35.755079 -162.485728)
			(xy 35.669659 -162.501696) (xy 35.58313 -162.509714) (xy 35.49623 -162.509714) (xy 35.409701 -162.501696)
			(xy 35.324281 -162.485728) (xy 35.240699 -162.461947) (xy 35.159667 -162.430555) (xy 35.081878 -162.391821)
			(xy 35.007994 -162.346074) (xy 34.938647 -162.293705) (xy 34.874427 -162.235161) (xy 34.815883 -162.170941)
			(xy 34.763514 -162.101594) (xy 34.717767 -162.02771) (xy 34.679033 -161.949921) (xy 34.647641 -161.868889)
			(xy 34.62386 -161.785307) (xy 34.607892 -161.699887) (xy 34.599874 -161.613358) (xy 31.399486 -161.613358)
			(xy 31.391468 -161.699887) (xy 31.3755 -161.785307) (xy 31.351719 -161.868889) (xy 31.320327 -161.949921)
			(xy 31.281593 -162.02771) (xy 31.235846 -162.101594) (xy 31.183477 -162.170941) (xy 31.124933 -162.235161)
			(xy 31.060713 -162.293705) (xy 30.991366 -162.346074) (xy 30.917482 -162.391821) (xy 30.839693 -162.430555)
			(xy 30.758661 -162.461947) (xy 30.675079 -162.485728) (xy 30.589659 -162.501696) (xy 30.50313 -162.509714)
			(xy 30.41623 -162.509714) (xy 30.329701 -162.501696) (xy 30.244281 -162.485728) (xy 30.160699 -162.461947)
			(xy 30.079667 -162.430555) (xy 30.001878 -162.391821) (xy 29.927994 -162.346074) (xy 29.858647 -162.293705)
			(xy 29.794427 -162.235161) (xy 29.735883 -162.170941) (xy 29.683514 -162.101594) (xy 29.637767 -162.02771)
			(xy 29.599033 -161.949921) (xy 29.567641 -161.868889) (xy 29.54386 -161.785307) (xy 29.527892 -161.699887)
			(xy 29.519874 -161.613358) (xy 28.884372 -161.613358) (xy 28.884372 -162.850614) (xy 39.565171 -162.850614)
			(xy 39.569057 -162.796258) (xy 39.580639 -162.743008) (xy 39.599682 -162.691949) (xy 39.625798 -162.644119)
			(xy 39.658455 -162.600494) (xy 39.696988 -162.56196) (xy 39.740613 -162.529302) (xy 39.788442 -162.503185)
			(xy 39.839501 -162.484141) (xy 39.892751 -162.472558) (xy 39.947107 -162.468671) (xy 40.001463 -162.47256)
			(xy 40.054712 -162.484145) (xy 40.10577 -162.503191) (xy 40.153598 -162.529309) (xy 40.175688 -162.545268)
			(xy 40.1947 -162.558864) (xy 40.236583 -162.579596) (xy 40.281551 -162.592322) (xy 40.328088 -162.596612)
			(xy 40.374625 -162.592322) (xy 40.419593 -162.579596) (xy 40.461476 -162.558864) (xy 40.480488 -162.545268)
			(xy 40.502599 -162.529339) (xy 40.550424 -162.50322) (xy 40.601479 -162.484173) (xy 40.654726 -162.472586)
			(xy 40.70908 -162.468695) (xy 40.763434 -162.47258) (xy 40.816681 -162.484161) (xy 40.867739 -162.503203)
			(xy 40.915567 -162.529317) (xy 40.959191 -162.561973) (xy 40.997723 -162.600505) (xy 41.030379 -162.644128)
			(xy 41.056495 -162.691956) (xy 41.075537 -162.743013) (xy 41.087119 -162.79626) (xy 41.091005 -162.850614)
			(xy 41.087115 -162.904968) (xy 41.075529 -162.958215) (xy 41.056483 -163.009271) (xy 41.030364 -163.057096)
			(xy 40.997704 -163.100717) (xy 40.959169 -163.139246) (xy 40.915542 -163.171898) (xy 40.867713 -163.198009)
			(xy 40.816654 -163.217047) (xy 40.763405 -163.228624) (xy 40.709051 -163.232505) (xy 40.654697 -163.22861)
			(xy 40.601452 -163.217019) (xy 40.550398 -163.197968) (xy 40.502575 -163.171845) (xy 40.480488 -163.155884)
			(xy 40.461476 -163.142288) (xy 40.419593 -163.121556) (xy 40.374625 -163.10883) (xy 40.328088 -163.10454)
			(xy 40.281551 -163.10883) (xy 40.236583 -163.121556) (xy 40.1947 -163.142288) (xy 40.175688 -163.155884)
			(xy 40.153623 -163.171875) (xy 40.105797 -163.197997) (xy 40.05474 -163.217047) (xy 40.001491 -163.228636)
			(xy 39.947136 -163.232529) (xy 39.892779 -163.228646) (xy 39.839529 -163.217067) (xy 39.788468 -163.198027)
			(xy 39.740637 -163.171914) (xy 39.69701 -163.139259) (xy 39.658473 -163.100728) (xy 39.625813 -163.057105)
			(xy 39.599694 -163.009277) (xy 39.580647 -162.958219) (xy 39.569061 -162.90497) (xy 39.565171 -162.850614)
			(xy 28.884372 -162.850614) (xy 28.884372 -164.153358) (xy 29.519874 -164.153358) (xy 29.519874 -164.066458)
			(xy 29.527892 -163.979929) (xy 29.54386 -163.894509) (xy 29.567641 -163.810927) (xy 29.599033 -163.729895)
			(xy 29.637767 -163.652106) (xy 29.683514 -163.578222) (xy 29.735883 -163.508875) (xy 29.794427 -163.444655)
			(xy 29.858647 -163.386111) (xy 29.927994 -163.333742) (xy 30.001878 -163.287995) (xy 30.079667 -163.249261)
			(xy 30.160699 -163.217869) (xy 30.244281 -163.194088) (xy 30.329701 -163.17812) (xy 30.41623 -163.170102)
			(xy 30.50313 -163.170102) (xy 30.589659 -163.17812) (xy 30.675079 -163.194088) (xy 30.758661 -163.217869)
			(xy 30.839693 -163.249261) (xy 30.917482 -163.287995) (xy 30.991366 -163.333742) (xy 31.060713 -163.386111)
			(xy 31.124933 -163.444655) (xy 31.183477 -163.508875) (xy 31.235846 -163.578222) (xy 31.281593 -163.652106)
			(xy 31.320327 -163.729895) (xy 31.351719 -163.810927) (xy 31.3755 -163.894509) (xy 31.391468 -163.979929)
			(xy 31.399486 -164.066458) (xy 31.399988 -164.109908) (xy 31.399486 -164.153358) (xy 34.599874 -164.153358)
			(xy 34.599874 -164.066458) (xy 34.607892 -163.979929) (xy 34.62386 -163.894509) (xy 34.647641 -163.810927)
			(xy 34.679033 -163.729895) (xy 34.717767 -163.652106) (xy 34.763514 -163.578222) (xy 34.815883 -163.508875)
			(xy 34.874427 -163.444655) (xy 34.938647 -163.386111) (xy 35.007994 -163.333742) (xy 35.081878 -163.287995)
			(xy 35.159667 -163.249261) (xy 35.240699 -163.217869) (xy 35.324281 -163.194088) (xy 35.409701 -163.17812)
			(xy 35.49623 -163.170102) (xy 35.58313 -163.170102) (xy 35.669659 -163.17812) (xy 35.755079 -163.194088)
			(xy 35.838661 -163.217869) (xy 35.919693 -163.249261) (xy 35.997482 -163.287995) (xy 36.071366 -163.333742)
			(xy 36.140713 -163.386111) (xy 36.204933 -163.444655) (xy 36.263477 -163.508875) (xy 36.315846 -163.578222)
			(xy 36.361593 -163.652106) (xy 36.400327 -163.729895) (xy 36.431719 -163.810927) (xy 36.4555 -163.894509)
			(xy 36.471468 -163.979929) (xy 36.479486 -164.066458) (xy 36.479988 -164.109908) (xy 36.479486 -164.153358)
			(xy 36.471468 -164.239887) (xy 36.4555 -164.325307) (xy 36.431719 -164.408889) (xy 36.400327 -164.489921)
			(xy 36.361593 -164.56771) (xy 36.315846 -164.641594) (xy 36.263477 -164.710941) (xy 36.204933 -164.775161)
			(xy 36.140713 -164.833705) (xy 36.071366 -164.886074) (xy 35.997482 -164.931821) (xy 35.919693 -164.970555)
			(xy 35.858888 -164.994111) (xy 39.565176 -164.994111) (xy 39.569062 -164.939755) (xy 39.580645 -164.886506)
			(xy 39.599688 -164.835448) (xy 39.625804 -164.787619) (xy 39.658461 -164.743994) (xy 39.696994 -164.705461)
			(xy 39.740619 -164.672804) (xy 39.788447 -164.646688) (xy 39.839506 -164.627645) (xy 39.892755 -164.616062)
			(xy 39.94711 -164.612176) (xy 40.001466 -164.616065) (xy 40.054714 -164.627651) (xy 40.105772 -164.646697)
			(xy 40.153599 -164.672815) (xy 40.175688 -164.688774) (xy 40.1947 -164.70237) (xy 40.236583 -164.723102)
			(xy 40.281551 -164.735828) (xy 40.328088 -164.740118) (xy 40.374625 -164.735828) (xy 40.419593 -164.723102)
			(xy 40.461476 -164.70237) (xy 40.480488 -164.688774) (xy 40.502593 -164.672837) (xy 40.550419 -164.646717)
			(xy 40.601475 -164.627669) (xy 40.654722 -164.616082) (xy 40.709076 -164.612191) (xy 40.763431 -164.616075)
			(xy 40.816679 -164.627656) (xy 40.867738 -164.646697) (xy 40.915566 -164.672811) (xy 40.959191 -164.705467)
			(xy 40.997724 -164.743999) (xy 41.030382 -164.787623) (xy 41.056497 -164.83545) (xy 41.075541 -164.886508)
			(xy 41.087123 -164.939756) (xy 41.091009 -164.994111) (xy 41.08712 -165.048465) (xy 41.075534 -165.101713)
			(xy 41.056488 -165.152769) (xy 41.03037 -165.200596) (xy 40.99771 -165.244218) (xy 40.959175 -165.282747)
			(xy 40.915548 -165.3154) (xy 40.867718 -165.341512) (xy 40.816659 -165.36055) (xy 40.763409 -165.372128)
			(xy 40.709054 -165.376009) (xy 40.6547 -165.372115) (xy 40.601454 -165.360525) (xy 40.550399 -165.341474)
			(xy 40.502575 -165.315351) (xy 40.480488 -165.29939) (xy 40.461476 -165.285794) (xy 40.419593 -165.265062)
			(xy 40.374625 -165.252336) (xy 40.328088 -165.248046) (xy 40.281551 -165.252336) (xy 40.236583 -165.265062)
			(xy 40.1947 -165.285794) (xy 40.175688 -165.29939) (xy 40.153617 -165.315373) (xy 40.105791 -165.341494)
			(xy 40.054735 -165.360543) (xy 40.001487 -165.372131) (xy 39.947132 -165.376024) (xy 39.892776 -165.372141)
			(xy 39.839527 -165.360561) (xy 39.788467 -165.341521) (xy 39.740637 -165.315408) (xy 39.69701 -165.282753)
			(xy 39.658475 -165.244222) (xy 39.625815 -165.200599) (xy 39.599697 -165.152772) (xy 39.580651 -165.101714)
			(xy 39.569066 -165.048466) (xy 39.565176 -164.994111) (xy 35.858888 -164.994111) (xy 35.838661 -165.001947)
			(xy 35.755079 -165.025728) (xy 35.669659 -165.041696) (xy 35.58313 -165.049714) (xy 35.49623 -165.049714)
			(xy 35.409701 -165.041696) (xy 35.324281 -165.025728) (xy 35.240699 -165.001947) (xy 35.159667 -164.970555)
			(xy 35.081878 -164.931821) (xy 35.007994 -164.886074) (xy 34.938647 -164.833705) (xy 34.874427 -164.775161)
			(xy 34.815883 -164.710941) (xy 34.763514 -164.641594) (xy 34.717767 -164.56771) (xy 34.679033 -164.489921)
			(xy 34.647641 -164.408889) (xy 34.62386 -164.325307) (xy 34.607892 -164.239887) (xy 34.599874 -164.153358)
			(xy 31.399486 -164.153358) (xy 31.391468 -164.239887) (xy 31.3755 -164.325307) (xy 31.351719 -164.408889)
			(xy 31.320327 -164.489921) (xy 31.281593 -164.56771) (xy 31.235846 -164.641594) (xy 31.183477 -164.710941)
			(xy 31.124933 -164.775161) (xy 31.060713 -164.833705) (xy 30.991366 -164.886074) (xy 30.917482 -164.931821)
			(xy 30.839693 -164.970555) (xy 30.758661 -165.001947) (xy 30.675079 -165.025728) (xy 30.589659 -165.041696)
			(xy 30.50313 -165.049714) (xy 30.41623 -165.049714) (xy 30.329701 -165.041696) (xy 30.244281 -165.025728)
			(xy 30.160699 -165.001947) (xy 30.079667 -164.970555) (xy 30.001878 -164.931821) (xy 29.927994 -164.886074)
			(xy 29.858647 -164.833705) (xy 29.794427 -164.775161) (xy 29.735883 -164.710941) (xy 29.683514 -164.641594)
			(xy 29.637767 -164.56771) (xy 29.599033 -164.489921) (xy 29.567641 -164.408889) (xy 29.54386 -164.325307)
			(xy 29.527892 -164.239887) (xy 29.519874 -164.153358) (xy 28.884372 -164.153358) (xy 28.884372 -166.693358)
			(xy 29.519874 -166.693358) (xy 29.519874 -166.606458) (xy 29.527892 -166.519929) (xy 29.54386 -166.434509)
			(xy 29.567641 -166.350927) (xy 29.599033 -166.269895) (xy 29.637767 -166.192106) (xy 29.683514 -166.118222)
			(xy 29.735883 -166.048875) (xy 29.794427 -165.984655) (xy 29.858647 -165.926111) (xy 29.927994 -165.873742)
			(xy 30.001878 -165.827995) (xy 30.079667 -165.789261) (xy 30.160699 -165.757869) (xy 30.244281 -165.734088)
			(xy 30.329701 -165.71812) (xy 30.41623 -165.710102) (xy 30.50313 -165.710102) (xy 30.589659 -165.71812)
			(xy 30.675079 -165.734088) (xy 30.758661 -165.757869) (xy 30.839693 -165.789261) (xy 30.917482 -165.827995)
			(xy 30.991366 -165.873742) (xy 31.060713 -165.926111) (xy 31.124933 -165.984655) (xy 31.183477 -166.048875)
			(xy 31.235846 -166.118222) (xy 31.281593 -166.192106) (xy 31.320327 -166.269895) (xy 31.351719 -166.350927)
			(xy 31.3755 -166.434509) (xy 31.391468 -166.519929) (xy 31.399486 -166.606458) (xy 31.399988 -166.649908)
			(xy 31.399486 -166.693358) (xy 34.599874 -166.693358) (xy 34.599874 -166.606458) (xy 34.607892 -166.519929)
			(xy 34.62386 -166.434509) (xy 34.647641 -166.350927) (xy 34.679033 -166.269895) (xy 34.717767 -166.192106)
			(xy 34.763514 -166.118222) (xy 34.815883 -166.048875) (xy 34.874427 -165.984655) (xy 34.938647 -165.926111)
			(xy 35.007994 -165.873742) (xy 35.081878 -165.827995) (xy 35.159667 -165.789261) (xy 35.240699 -165.757869)
			(xy 35.324281 -165.734088) (xy 35.409701 -165.71812) (xy 35.49623 -165.710102) (xy 35.58313 -165.710102)
			(xy 35.669659 -165.71812) (xy 35.755079 -165.734088) (xy 35.838661 -165.757869) (xy 35.919693 -165.789261)
			(xy 35.997482 -165.827995) (xy 36.071366 -165.873742) (xy 36.140713 -165.926111) (xy 36.204933 -165.984655)
			(xy 36.263477 -166.048875) (xy 36.315846 -166.118222) (xy 36.361593 -166.192106) (xy 36.400327 -166.269895)
			(xy 36.431719 -166.350927) (xy 36.4555 -166.434509) (xy 36.471468 -166.519929) (xy 36.479486 -166.606458)
			(xy 36.479988 -166.649908) (xy 36.479486 -166.693358) (xy 36.471468 -166.779887) (xy 36.4555 -166.865307)
			(xy 36.431719 -166.948889) (xy 36.400327 -167.029921) (xy 36.361593 -167.10771) (xy 36.315846 -167.181594)
			(xy 36.263477 -167.250941) (xy 36.204933 -167.315161) (xy 36.140713 -167.373705) (xy 36.071366 -167.426074)
			(xy 35.997482 -167.471821) (xy 35.919693 -167.510555) (xy 35.838661 -167.541947) (xy 35.755079 -167.565728)
			(xy 35.669659 -167.581696) (xy 35.58313 -167.589714) (xy 35.49623 -167.589714) (xy 35.409701 -167.581696)
			(xy 35.324281 -167.565728) (xy 35.240699 -167.541947) (xy 35.159667 -167.510555) (xy 35.081878 -167.471821)
			(xy 35.007994 -167.426074) (xy 34.938647 -167.373705) (xy 34.874427 -167.315161) (xy 34.815883 -167.250941)
			(xy 34.763514 -167.181594) (xy 34.717767 -167.10771) (xy 34.679033 -167.029921) (xy 34.647641 -166.948889)
			(xy 34.62386 -166.865307) (xy 34.607892 -166.779887) (xy 34.599874 -166.693358) (xy 31.399486 -166.693358)
			(xy 31.391468 -166.779887) (xy 31.3755 -166.865307) (xy 31.351719 -166.948889) (xy 31.320327 -167.029921)
			(xy 31.281593 -167.10771) (xy 31.235846 -167.181594) (xy 31.183477 -167.250941) (xy 31.124933 -167.315161)
			(xy 31.060713 -167.373705) (xy 30.991366 -167.426074) (xy 30.917482 -167.471821) (xy 30.839693 -167.510555)
			(xy 30.758661 -167.541947) (xy 30.675079 -167.565728) (xy 30.589659 -167.581696) (xy 30.50313 -167.589714)
			(xy 30.41623 -167.589714) (xy 30.329701 -167.581696) (xy 30.244281 -167.565728) (xy 30.160699 -167.541947)
			(xy 30.079667 -167.510555) (xy 30.001878 -167.471821) (xy 29.927994 -167.426074) (xy 29.858647 -167.373705)
			(xy 29.794427 -167.315161) (xy 29.735883 -167.250941) (xy 29.683514 -167.181594) (xy 29.637767 -167.10771)
			(xy 29.599033 -167.029921) (xy 29.567641 -166.948889) (xy 29.54386 -166.865307) (xy 29.527892 -166.779887)
			(xy 29.519874 -166.693358) (xy 28.884372 -166.693358) (xy 28.884372 -169.233358) (xy 29.519874 -169.233358)
			(xy 29.519874 -169.146458) (xy 29.527892 -169.059929) (xy 29.54386 -168.974509) (xy 29.567641 -168.890927)
			(xy 29.599033 -168.809895) (xy 29.637767 -168.732106) (xy 29.683514 -168.658222) (xy 29.735883 -168.588875)
			(xy 29.794427 -168.524655) (xy 29.858647 -168.466111) (xy 29.927994 -168.413742) (xy 30.001878 -168.367995)
			(xy 30.079667 -168.329261) (xy 30.160699 -168.297869) (xy 30.244281 -168.274088) (xy 30.329701 -168.25812)
			(xy 30.41623 -168.250102) (xy 30.50313 -168.250102) (xy 30.589659 -168.25812) (xy 30.675079 -168.274088)
			(xy 30.758661 -168.297869) (xy 30.839693 -168.329261) (xy 30.917482 -168.367995) (xy 30.991366 -168.413742)
			(xy 31.060713 -168.466111) (xy 31.124933 -168.524655) (xy 31.183477 -168.588875) (xy 31.235846 -168.658222)
			(xy 31.281593 -168.732106) (xy 31.320327 -168.809895) (xy 31.351719 -168.890927) (xy 31.3755 -168.974509)
			(xy 31.391468 -169.059929) (xy 31.399486 -169.146458) (xy 31.399988 -169.189908) (xy 31.399486 -169.233358)
			(xy 34.599874 -169.233358) (xy 34.599874 -169.146458) (xy 34.607892 -169.059929) (xy 34.62386 -168.974509)
			(xy 34.647641 -168.890927) (xy 34.679033 -168.809895) (xy 34.717767 -168.732106) (xy 34.763514 -168.658222)
			(xy 34.815883 -168.588875) (xy 34.874427 -168.524655) (xy 34.938647 -168.466111) (xy 35.007994 -168.413742)
			(xy 35.081878 -168.367995) (xy 35.159667 -168.329261) (xy 35.240699 -168.297869) (xy 35.324281 -168.274088)
			(xy 35.409701 -168.25812) (xy 35.49623 -168.250102) (xy 35.58313 -168.250102) (xy 35.669659 -168.25812)
			(xy 35.755079 -168.274088) (xy 35.838661 -168.297869) (xy 35.919693 -168.329261) (xy 35.997482 -168.367995)
			(xy 36.071366 -168.413742) (xy 36.140713 -168.466111) (xy 36.204933 -168.524655) (xy 36.263477 -168.588875)
			(xy 36.315846 -168.658222) (xy 36.361593 -168.732106) (xy 36.400327 -168.809895) (xy 36.431719 -168.890927)
			(xy 36.4555 -168.974509) (xy 36.471468 -169.059929) (xy 36.479486 -169.146458) (xy 36.479988 -169.189908)
			(xy 36.479486 -169.233358) (xy 36.471468 -169.319887) (xy 36.4555 -169.405307) (xy 36.431719 -169.488889)
			(xy 36.400327 -169.569921) (xy 36.361593 -169.64771) (xy 36.315846 -169.721594) (xy 36.263477 -169.790941)
			(xy 36.204933 -169.855161) (xy 36.140713 -169.913705) (xy 36.071366 -169.966074) (xy 35.997482 -170.011821)
			(xy 35.919693 -170.050555) (xy 35.838661 -170.081947) (xy 35.755079 -170.105728) (xy 35.669659 -170.121696)
			(xy 35.58313 -170.129714) (xy 35.49623 -170.129714) (xy 35.409701 -170.121696) (xy 35.324281 -170.105728)
			(xy 35.240699 -170.081947) (xy 35.159667 -170.050555) (xy 35.081878 -170.011821) (xy 35.007994 -169.966074)
			(xy 34.938647 -169.913705) (xy 34.874427 -169.855161) (xy 34.815883 -169.790941) (xy 34.763514 -169.721594)
			(xy 34.717767 -169.64771) (xy 34.679033 -169.569921) (xy 34.647641 -169.488889) (xy 34.62386 -169.405307)
			(xy 34.607892 -169.319887) (xy 34.599874 -169.233358) (xy 31.399486 -169.233358) (xy 31.391468 -169.319887)
			(xy 31.3755 -169.405307) (xy 31.351719 -169.488889) (xy 31.320327 -169.569921) (xy 31.281593 -169.64771)
			(xy 31.235846 -169.721594) (xy 31.183477 -169.790941) (xy 31.124933 -169.855161) (xy 31.060713 -169.913705)
			(xy 30.991366 -169.966074) (xy 30.917482 -170.011821) (xy 30.839693 -170.050555) (xy 30.758661 -170.081947)
			(xy 30.675079 -170.105728) (xy 30.589659 -170.121696) (xy 30.50313 -170.129714) (xy 30.41623 -170.129714)
			(xy 30.329701 -170.121696) (xy 30.244281 -170.105728) (xy 30.160699 -170.081947) (xy 30.079667 -170.050555)
			(xy 30.001878 -170.011821) (xy 29.927994 -169.966074) (xy 29.858647 -169.913705) (xy 29.794427 -169.855161)
			(xy 29.735883 -169.790941) (xy 29.683514 -169.721594) (xy 29.637767 -169.64771) (xy 29.599033 -169.569921)
			(xy 29.567641 -169.488889) (xy 29.54386 -169.405307) (xy 29.527892 -169.319887) (xy 29.519874 -169.233358)
			(xy 28.884372 -169.233358) (xy 28.884372 -171.773358) (xy 29.519874 -171.773358) (xy 29.519874 -171.686458)
			(xy 29.527892 -171.599929) (xy 29.54386 -171.514509) (xy 29.567641 -171.430927) (xy 29.599033 -171.349895)
			(xy 29.637767 -171.272106) (xy 29.683514 -171.198222) (xy 29.735883 -171.128875) (xy 29.794427 -171.064655)
			(xy 29.858647 -171.006111) (xy 29.927994 -170.953742) (xy 30.001878 -170.907995) (xy 30.079667 -170.869261)
			(xy 30.160699 -170.837869) (xy 30.244281 -170.814088) (xy 30.329701 -170.79812) (xy 30.41623 -170.790102)
			(xy 30.50313 -170.790102) (xy 30.589659 -170.79812) (xy 30.675079 -170.814088) (xy 30.758661 -170.837869)
			(xy 30.839693 -170.869261) (xy 30.917482 -170.907995) (xy 30.991366 -170.953742) (xy 31.060713 -171.006111)
			(xy 31.124933 -171.064655) (xy 31.183477 -171.128875) (xy 31.235846 -171.198222) (xy 31.281593 -171.272106)
			(xy 31.320327 -171.349895) (xy 31.351719 -171.430927) (xy 31.3755 -171.514509) (xy 31.391468 -171.599929)
			(xy 31.399486 -171.686458) (xy 31.399988 -171.729908) (xy 31.399486 -171.773358) (xy 34.599874 -171.773358)
			(xy 34.599874 -171.686458) (xy 34.607892 -171.599929) (xy 34.62386 -171.514509) (xy 34.647641 -171.430927)
			(xy 34.679033 -171.349895) (xy 34.717767 -171.272106) (xy 34.763514 -171.198222) (xy 34.815883 -171.128875)
			(xy 34.874427 -171.064655) (xy 34.938647 -171.006111) (xy 35.007994 -170.953742) (xy 35.081878 -170.907995)
			(xy 35.159667 -170.869261) (xy 35.240699 -170.837869) (xy 35.324281 -170.814088) (xy 35.409701 -170.79812)
			(xy 35.49623 -170.790102) (xy 35.58313 -170.790102) (xy 35.669659 -170.79812) (xy 35.755079 -170.814088)
			(xy 35.838661 -170.837869) (xy 35.919693 -170.869261) (xy 35.997482 -170.907995) (xy 36.071366 -170.953742)
			(xy 36.140713 -171.006111) (xy 36.204933 -171.064655) (xy 36.263477 -171.128875) (xy 36.315846 -171.198222)
			(xy 36.361593 -171.272106) (xy 36.400327 -171.349895) (xy 36.431719 -171.430927) (xy 36.4555 -171.514509)
			(xy 36.471468 -171.599929) (xy 36.479486 -171.686458) (xy 36.479988 -171.729908) (xy 36.479486 -171.773358)
			(xy 36.471468 -171.859887) (xy 36.4555 -171.945307) (xy 36.431719 -172.028889) (xy 36.400327 -172.109921)
			(xy 36.361593 -172.18771) (xy 36.315846 -172.261594) (xy 36.263477 -172.330941) (xy 36.204933 -172.395161)
			(xy 36.140713 -172.453705) (xy 36.071366 -172.506074) (xy 35.997482 -172.551821) (xy 35.919693 -172.590555)
			(xy 35.838661 -172.621947) (xy 35.755079 -172.645728) (xy 35.669659 -172.661696) (xy 35.58313 -172.669714)
			(xy 35.49623 -172.669714) (xy 35.409701 -172.661696) (xy 35.324281 -172.645728) (xy 35.240699 -172.621947)
			(xy 35.159667 -172.590555) (xy 35.081878 -172.551821) (xy 35.007994 -172.506074) (xy 34.938647 -172.453705)
			(xy 34.874427 -172.395161) (xy 34.815883 -172.330941) (xy 34.763514 -172.261594) (xy 34.717767 -172.18771)
			(xy 34.679033 -172.109921) (xy 34.647641 -172.028889) (xy 34.62386 -171.945307) (xy 34.607892 -171.859887)
			(xy 34.599874 -171.773358) (xy 31.399486 -171.773358) (xy 31.391468 -171.859887) (xy 31.3755 -171.945307)
			(xy 31.351719 -172.028889) (xy 31.320327 -172.109921) (xy 31.281593 -172.18771) (xy 31.235846 -172.261594)
			(xy 31.183477 -172.330941) (xy 31.124933 -172.395161) (xy 31.060713 -172.453705) (xy 30.991366 -172.506074)
			(xy 30.917482 -172.551821) (xy 30.839693 -172.590555) (xy 30.758661 -172.621947) (xy 30.675079 -172.645728)
			(xy 30.589659 -172.661696) (xy 30.50313 -172.669714) (xy 30.41623 -172.669714) (xy 30.329701 -172.661696)
			(xy 30.244281 -172.645728) (xy 30.160699 -172.621947) (xy 30.079667 -172.590555) (xy 30.001878 -172.551821)
			(xy 29.927994 -172.506074) (xy 29.858647 -172.453705) (xy 29.794427 -172.395161) (xy 29.735883 -172.330941)
			(xy 29.683514 -172.261594) (xy 29.637767 -172.18771) (xy 29.599033 -172.109921) (xy 29.567641 -172.028889)
			(xy 29.54386 -171.945307) (xy 29.527892 -171.859887) (xy 29.519874 -171.773358) (xy 28.884372 -171.773358)
			(xy 28.884372 -173.178385) (xy 47.641754 -173.178385) (xy 47.641754 -173.097275) (xy 47.649704 -173.016556)
			(xy 47.665527 -172.937005) (xy 47.689072 -172.859389) (xy 47.720111 -172.784453) (xy 47.758346 -172.712921)
			(xy 47.803408 -172.645481) (xy 47.854863 -172.582782) (xy 47.912216 -172.525429) (xy 47.974915 -172.473974)
			(xy 48.042355 -172.428912) (xy 48.113887 -172.390677) (xy 48.188823 -172.359638) (xy 48.266439 -172.336093)
			(xy 48.34599 -172.32027) (xy 48.426709 -172.31232) (xy 48.507819 -172.31232) (xy 48.588538 -172.32027)
			(xy 48.668089 -172.336093) (xy 48.745705 -172.359638) (xy 48.820641 -172.390677) (xy 48.892173 -172.428912)
			(xy 48.959613 -172.473974) (xy 49.022312 -172.525429) (xy 49.079665 -172.582782) (xy 49.13112 -172.645481)
			(xy 49.176182 -172.712921) (xy 49.214417 -172.784453) (xy 49.245456 -172.859389) (xy 49.269001 -172.937005)
			(xy 49.284824 -173.016556) (xy 49.292774 -173.097275) (xy 49.293272 -173.13783) (xy 49.292774 -173.178385)
			(xy 51.141874 -173.178385) (xy 51.141874 -173.097275) (xy 51.149824 -173.016556) (xy 51.165647 -172.937005)
			(xy 51.189192 -172.859389) (xy 51.220231 -172.784453) (xy 51.258466 -172.712921) (xy 51.303528 -172.645481)
			(xy 51.354983 -172.582782) (xy 51.412336 -172.525429) (xy 51.475035 -172.473974) (xy 51.542475 -172.428912)
			(xy 51.614007 -172.390677) (xy 51.688943 -172.359638) (xy 51.766559 -172.336093) (xy 51.84611 -172.32027)
			(xy 51.926829 -172.31232) (xy 52.007939 -172.31232) (xy 52.088658 -172.32027) (xy 52.168209 -172.336093)
			(xy 52.245825 -172.359638) (xy 52.320761 -172.390677) (xy 52.392293 -172.428912) (xy 52.459733 -172.473974)
			(xy 52.522432 -172.525429) (xy 52.579785 -172.582782) (xy 52.63124 -172.645481) (xy 52.676302 -172.712921)
			(xy 52.714537 -172.784453) (xy 52.745576 -172.859389) (xy 52.769121 -172.937005) (xy 52.784944 -173.016556)
			(xy 52.792894 -173.097275) (xy 52.793392 -173.13783) (xy 52.792894 -173.178385) (xy 52.784944 -173.259104)
			(xy 52.769121 -173.338655) (xy 52.745576 -173.416271) (xy 52.714537 -173.491207) (xy 52.676302 -173.562739)
			(xy 52.63124 -173.630179) (xy 52.579785 -173.692878) (xy 52.522432 -173.750231) (xy 52.459733 -173.801686)
			(xy 52.392293 -173.846748) (xy 52.320761 -173.884983) (xy 52.245825 -173.916022) (xy 52.168209 -173.939567)
			(xy 52.088658 -173.95539) (xy 52.007939 -173.96334) (xy 51.926829 -173.96334) (xy 51.84611 -173.95539)
			(xy 51.766559 -173.939567) (xy 51.688943 -173.916022) (xy 51.614007 -173.884983) (xy 51.542475 -173.846748)
			(xy 51.475035 -173.801686) (xy 51.412336 -173.750231) (xy 51.354983 -173.692878) (xy 51.303528 -173.630179)
			(xy 51.258466 -173.562739) (xy 51.220231 -173.491207) (xy 51.189192 -173.416271) (xy 51.165647 -173.338655)
			(xy 51.149824 -173.259104) (xy 51.141874 -173.178385) (xy 49.292774 -173.178385) (xy 49.284824 -173.259104)
			(xy 49.269001 -173.338655) (xy 49.245456 -173.416271) (xy 49.214417 -173.491207) (xy 49.176182 -173.562739)
			(xy 49.13112 -173.630179) (xy 49.079665 -173.692878) (xy 49.022312 -173.750231) (xy 48.959613 -173.801686)
			(xy 48.892173 -173.846748) (xy 48.820641 -173.884983) (xy 48.745705 -173.916022) (xy 48.668089 -173.939567)
			(xy 48.588538 -173.95539) (xy 48.507819 -173.96334) (xy 48.426709 -173.96334) (xy 48.34599 -173.95539)
			(xy 48.266439 -173.939567) (xy 48.188823 -173.916022) (xy 48.113887 -173.884983) (xy 48.042355 -173.846748)
			(xy 47.974915 -173.801686) (xy 47.912216 -173.750231) (xy 47.854863 -173.692878) (xy 47.803408 -173.630179)
			(xy 47.758346 -173.562739) (xy 47.720111 -173.491207) (xy 47.689072 -173.416271) (xy 47.665527 -173.338655)
			(xy 47.649704 -173.259104) (xy 47.641754 -173.178385) (xy 28.884372 -173.178385) (xy 28.884372 -173.741588)
			(xy 28.473146 -174.153068) (xy 28.297632 -174.328582) (xy 28.282519 -174.345525) (xy 28.257951 -174.383699)
			(xy 28.240555 -174.42563) (xy 28.230886 -174.469985) (xy 28.229251 -174.515352) (xy 28.235702 -174.560288)
			(xy 28.250033 -174.603364) (xy 28.271789 -174.643208) (xy 28.300277 -174.678552) (xy 28.334592 -174.708274)
			(xy 28.373641 -174.731426) (xy 28.416182 -174.747273) (xy 28.460861 -174.75531) (xy 28.48356 -174.75581)
			(xy 59.304428 -174.75581) (xy 81.445862 -152.614376) (xy 81.456205 -152.603479) (xy 81.47192 -152.577884)
			(xy 81.481185 -152.549314) (xy 81.483481 -152.519367) (xy 81.47868 -152.489718) (xy 81.473294 -152.475692)
			(xy 81.453736 -152.428448) (xy 81.439258 -152.412192) (xy 81.4211 -152.391354) (xy 81.39036 -152.34542)
			(xy 81.366568 -152.295533) (xy 81.350221 -152.242735) (xy 81.341661 -152.188131) (xy 81.341066 -152.132864)
			(xy 81.348451 -152.078089) (xy 81.363659 -152.024952) (xy 81.386373 -151.974564) (xy 81.416118 -151.92798)
			(xy 81.452272 -151.886174) (xy 81.494077 -151.85002) (xy 81.540661 -151.820275) (xy 81.591049 -151.79756)
			(xy 81.644186 -151.782351) (xy 81.69896 -151.774967) (xy 81.754228 -151.77556) (xy 81.808832 -151.78412)
			(xy 81.86163 -151.800467) (xy 81.911517 -151.824258) (xy 81.957451 -151.854998) (xy 81.978246 -151.873204)
			(xy 81.994502 -151.887682) (xy 82.041746 -151.90724) (xy 82.055768 -151.912616) (xy 82.085417 -151.917351)
			(xy 82.115351 -151.915035) (xy 82.143918 -151.905798) (xy 82.169541 -151.890148) (xy 82.18043 -151.879808)
			(xy 83.409536 -150.650702) (xy 83.409536 -148.73097) (xy 83.393788 -148.702268) (xy 83.380873 -148.677928)
			(xy 83.361409 -148.626379) (xy 83.349566 -148.572566) (xy 83.34559 -148.517609) (xy 83.349564 -148.462651)
			(xy 83.361404 -148.408838) (xy 83.380866 -148.357288) (xy 83.393788 -148.332952) (xy 83.409536 -148.30425)
			(xy 83.409536 -139.146026) (xy 83.954366 -138.601196) (xy 85.8774 -136.678416) (xy 91.987116 -136.678416)
			(xy 92.714064 -137.40511) (xy 93.1545 -137.845546) (xy 93.1545 -139.009882) (xy 92.943934 -139.220448)
			(xy 92.596716 -139.567412) (xy 91.555824 -139.567412) (xy 91.54005 -139.567885) (xy 91.509467 -139.575632)
			(xy 91.481726 -139.590657) (xy 91.458528 -139.612038) (xy 91.441296 -139.638464) (xy 91.431086 -139.668314)
			(xy 91.429332 -139.683998) (xy 91.425887 -139.720159) (xy 91.412557 -139.79157) (xy 91.39202 -139.861251)
			(xy 91.364488 -139.928476) (xy 91.330249 -139.992545) (xy 91.289659 -140.052791) (xy 91.24314 -140.108588)
			(xy 91.191178 -140.159353) (xy 91.134313 -140.204559) (xy 91.103958 -140.22451) (xy 91.070539 -140.24528)
			(xy 90.999995 -140.280139) (xy 90.926035 -140.307004) (xy 90.849564 -140.325547) (xy 90.771514 -140.335542)
			(xy 90.692838 -140.336867) (xy 90.653616 -140.33373) (xy 90.618137 -140.329964) (xy 90.548121 -140.316225)
			(xy 90.479833 -140.295544) (xy 90.413959 -140.26813) (xy 90.351161 -140.234257) (xy 90.321384 -140.214604)
			(xy 90.289717 -140.192578) (xy 90.230869 -140.142699) (xy 90.177765 -140.086745) (xy 90.153998 -140.056362)
			(xy 90.131556 -140.026118) (xy 90.092469 -139.96174) (xy 90.060399 -139.893594) (xy 90.035704 -139.822442)
			(xy 90.01866 -139.749081) (xy 90.009458 -139.67433) (xy 90.0082 -139.599025) (xy 90.014901 -139.524009)
			(xy 90.029486 -139.45012) (xy 90.051791 -139.378183) (xy 90.081567 -139.309004) (xy 90.118482 -139.243356)
			(xy 90.162123 -139.181973) (xy 90.212 -139.125541) (xy 90.267558 -139.074691) (xy 90.328175 -139.029992)
			(xy 90.393172 -138.991944) (xy 90.461824 -138.960971) (xy 90.533363 -138.937421) (xy 90.606988 -138.921556)
			(xy 90.681877 -138.913555) (xy 90.757192 -138.913505) (xy 90.832091 -138.921409) (xy 90.869008 -138.928856)
			(xy 90.882216 -138.931904) (xy 91.09583 -138.931904) (xy 91.119043 -138.929914) (xy 91.164222 -138.91856)
			(xy 91.206578 -138.899168) (xy 91.244696 -138.872389) (xy 91.277299 -138.839116) (xy 91.303299 -138.800462)
			(xy 91.321825 -138.75772) (xy 91.332259 -138.71232) (xy 91.334251 -138.665778) (xy 91.327735 -138.619652)
			(xy 91.320874 -138.597386) (xy 91.309956 -138.56611) (xy 91.293285 -138.501992) (xy 91.28263 -138.436605)
			(xy 91.27998 -138.403584) (xy 91.278013 -138.368681) (xy 91.280113 -138.2988) (xy 91.289054 -138.229463)
			(xy 91.29649 -138.195304) (xy 91.299628 -138.179511) (xy 91.298744 -138.147333) (xy 91.289839 -138.1164)
			(xy 91.273479 -138.088677) (xy 91.262454 -138.07694) (xy 90.84183 -137.656316) (xy 90.307414 -137.656316)
			(xy 90.285716 -137.656757) (xy 90.242951 -137.664128) (xy 90.202061 -137.678658) (xy 90.164234 -137.699925)
			(xy 90.13057 -137.727309) (xy 90.102049 -137.760016) (xy 90.0795 -137.797093) (xy 90.063578 -137.837462)
			(xy 90.054747 -137.87995) (xy 90.053264 -137.92332) (xy 90.059172 -137.966311) (xy 90.072298 -138.007674)
			(xy 90.081862 -138.027156) (xy 90.098675 -138.060583) (xy 90.125992 -138.130246) (xy 90.145849 -138.202391)
			(xy 90.158028 -138.276221) (xy 90.162394 -138.350922) (xy 90.158899 -138.425668) (xy 90.147581 -138.499635)
			(xy 90.128565 -138.572007) (xy 90.102061 -138.641983) (xy 90.068362 -138.708794) (xy 90.027839 -138.771699)
			(xy 89.980941 -138.830007) (xy 89.928184 -138.883072) (xy 89.870151 -138.930309) (xy 89.807482 -138.971197)
			(xy 89.740869 -139.005285) (xy 89.671048 -139.032196) (xy 89.598788 -139.051633) (xy 89.524889 -139.063382)
			(xy 89.450164 -139.067312) (xy 89.375439 -139.063382) (xy 89.30154 -139.051633) (xy 89.22928 -139.032196)
			(xy 89.159459 -139.005285) (xy 89.092846 -138.971197) (xy 89.030177 -138.930309) (xy 88.972144 -138.883072)
			(xy 88.919387 -138.830007) (xy 88.872489 -138.771699) (xy 88.831966 -138.708794) (xy 88.798267 -138.641983)
			(xy 88.771763 -138.572007) (xy 88.752747 -138.499635) (xy 88.741429 -138.425668) (xy 88.737934 -138.350922)
			(xy 88.7423 -138.276221) (xy 88.754479 -138.202391) (xy 88.774336 -138.130246) (xy 88.801653 -138.060583)
			(xy 88.818466 -138.027156) (xy 88.828056 -138.007684) (xy 88.841183 -137.966316) (xy 88.84709 -137.923318)
			(xy 88.845606 -137.879942) (xy 88.836774 -137.837449) (xy 88.820852 -137.797074) (xy 88.7983 -137.759991)
			(xy 88.769777 -137.727279) (xy 88.73611 -137.699889) (xy 88.698279 -137.678617) (xy 88.657385 -137.664081)
			(xy 88.614615 -137.656705) (xy 88.592914 -137.656316) (xy 87.767414 -137.656316) (xy 87.745716 -137.656757)
			(xy 87.702951 -137.664128) (xy 87.662061 -137.678658) (xy 87.624234 -137.699925) (xy 87.59057 -137.727309)
			(xy 87.562049 -137.760016) (xy 87.5395 -137.797093) (xy 87.523578 -137.837462) (xy 87.514747 -137.87995)
			(xy 87.513264 -137.92332) (xy 87.519172 -137.966311) (xy 87.532298 -138.007674) (xy 87.541862 -138.027156)
			(xy 87.55876 -138.060769) (xy 87.586186 -138.130829) (xy 87.60607 -138.203391) (xy 87.618189 -138.277646)
			(xy 87.622409 -138.352765) (xy 87.618682 -138.427909) (xy 87.60705 -138.502242) (xy 87.587642 -138.574932)
			(xy 87.560676 -138.645171) (xy 87.526451 -138.712173) (xy 87.506302 -138.743944) (xy 87.493962 -138.762511)
			(xy 87.467273 -138.798224) (xy 87.452962 -138.815318) (xy 87.423651 -138.848853) (xy 87.358053 -138.9091)
			(xy 87.322152 -138.93546) (xy 87.298276 -138.952478) (xy 87.240872 -139.057888) (xy 87.240872 -139.415774)
			(xy 87.241412 -139.432426) (xy 87.250025 -139.464597) (xy 87.266671 -139.493442) (xy 87.290215 -139.516996)
			(xy 87.319053 -139.533654) (xy 87.35122 -139.542281) (xy 87.367872 -139.542774) (xy 87.411306 -139.542774)
			(xy 87.479886 -139.489688) (xy 87.490808 -139.44727) (xy 87.50058 -139.411247) (xy 87.526669 -139.34131)
			(xy 87.559934 -139.274488) (xy 87.600008 -139.211513) (xy 87.646453 -139.153078) (xy 87.698758 -139.099824)
			(xy 87.756349 -139.052336) (xy 87.818592 -139.011135) (xy 87.884806 -138.976674) (xy 87.954262 -138.949332)
			(xy 88.026198 -138.929408) (xy 88.099824 -138.917121) (xy 88.174332 -138.912607) (xy 88.248903 -138.915914)
			(xy 88.322719 -138.927007) (xy 88.394968 -138.945763) (xy 88.464858 -138.971977) (xy 88.531621 -139.005361)
			(xy 88.594524 -139.045549) (xy 88.652876 -139.092098) (xy 88.706036 -139.144498) (xy 88.753421 -139.202173)
			(xy 88.79451 -139.26449) (xy 88.828853 -139.330766) (xy 88.856071 -139.400271) (xy 88.875866 -139.472242)
			(xy 88.888021 -139.54589) (xy 88.892403 -139.620406) (xy 88.888962 -139.694971) (xy 88.877737 -139.768766)
			(xy 88.858851 -139.840982) (xy 88.832512 -139.910825) (xy 88.799009 -139.977528) (xy 88.758709 -140.040359)
			(xy 88.712056 -140.098628) (xy 88.659561 -140.151694) (xy 88.631014 -140.175742) (xy 88.602185 -140.19875)
			(xy 88.540589 -140.239332) (xy 88.475123 -140.27332) (xy 88.406491 -140.300349) (xy 88.335429 -140.320128)
			(xy 88.262701 -140.332445) (xy 88.189089 -140.337167) (xy 88.115384 -140.334244) (xy 88.078818 -140.329412)
			(xy 88.041376 -140.323518) (xy 87.96792 -140.304817) (xy 87.896867 -140.27842) (xy 87.829019 -140.244624)
			(xy 87.765145 -140.203813) (xy 87.705967 -140.156447) (xy 87.652156 -140.103064) (xy 87.604319 -140.044266)
			(xy 87.562999 -139.98072) (xy 87.545418 -139.947142) (xy 87.535163 -139.927898) (xy 87.509106 -139.892938)
			(xy 87.477461 -139.862941) (xy 87.441159 -139.838788) (xy 87.401267 -139.821188) (xy 87.358954 -139.810659)
			(xy 87.315466 -139.807509) (xy 87.272078 -139.811832) (xy 87.230065 -139.8235) (xy 87.190662 -139.84217)
			(xy 87.155026 -139.867294) (xy 87.139272 -139.882372) (xy 87.107776 -139.913868) (xy 87.098196 -139.934022)
			(xy 87.085476 -139.976791) (xy 87.080418 -140.021125) (xy 87.083179 -140.06566) (xy 87.093674 -140.109029)
			(xy 87.111581 -140.149899) (xy 87.136348 -140.187015) (xy 87.167216 -140.219236) (xy 87.203235 -140.245573)
			(xy 87.223092 -140.255752) (xy 87.256797 -140.272806) (xy 87.320745 -140.313018) (xy 87.380076 -140.359776)
			(xy 87.434121 -140.412554) (xy 87.482274 -140.470758) (xy 87.523992 -140.533734) (xy 87.558807 -140.600774)
			(xy 87.586328 -140.671124) (xy 87.606243 -140.743992) (xy 87.618331 -140.818559) (xy 87.622454 -140.893988)
			(xy 87.622398 -140.89507) (xy 88.737951 -140.89507) (xy 88.741986 -140.819366) (xy 88.754045 -140.744521)
			(xy 88.773991 -140.67138) (xy 88.801598 -140.600775) (xy 88.836554 -140.533504) (xy 88.878462 -140.470329)
			(xy 88.926848 -140.411967) (xy 88.981164 -140.359079) (xy 89.040793 -140.312264) (xy 89.105061 -140.272052)
			(xy 89.173238 -140.2389) (xy 89.244554 -140.213182) (xy 89.318199 -140.19519) (xy 89.393339 -140.185128)
			(xy 89.469123 -140.183109) (xy 89.544693 -140.189158) (xy 89.619191 -140.203205) (xy 89.691774 -140.225091)
			(xy 89.76162 -140.254568) (xy 89.827937 -140.291303) (xy 89.889973 -140.334878) (xy 89.947026 -140.3848)
			(xy 89.99845 -140.440504) (xy 90.043661 -140.501359) (xy 90.082148 -140.566674) (xy 90.113474 -140.63571)
			(xy 90.137284 -140.707685) (xy 90.153309 -140.781783) (xy 90.161368 -140.857164) (xy 90.161872 -140.89507)
			(xy 90.161368 -140.932976) (xy 90.153309 -141.008357) (xy 90.137284 -141.082455) (xy 90.113474 -141.15443)
			(xy 90.082148 -141.223466) (xy 90.043661 -141.288781) (xy 89.99845 -141.349636) (xy 89.947026 -141.40534)
			(xy 89.889973 -141.455262) (xy 89.827937 -141.498837) (xy 89.76162 -141.535572) (xy 89.691774 -141.565049)
			(xy 89.619191 -141.586935) (xy 89.544693 -141.600982) (xy 89.469123 -141.607031) (xy 89.393339 -141.605012)
			(xy 89.318199 -141.59495) (xy 89.244554 -141.576958) (xy 89.173238 -141.55124) (xy 89.105061 -141.518088)
			(xy 89.040793 -141.477876) (xy 88.981164 -141.431061) (xy 88.926848 -141.378173) (xy 88.878462 -141.319811)
			(xy 88.836554 -141.256636) (xy 88.801598 -141.189365) (xy 88.773991 -141.11876) (xy 88.754045 -141.045619)
			(xy 88.741986 -140.970774) (xy 88.737951 -140.89507) (xy 87.622398 -140.89507) (xy 87.618566 -140.969429)
			(xy 87.606712 -141.044033) (xy 87.587024 -141.116964) (xy 87.573866 -141.152372) (xy 87.559046 -141.189101)
			(xy 87.522392 -141.259313) (xy 87.478166 -141.32502) (xy 87.452962 -141.355572) (xy 87.430544 -141.381359)
			(xy 87.381532 -141.428974) (xy 87.328176 -141.471666) (xy 87.2998 -141.4907) (xy 87.263901 -141.513429)
			(xy 87.18775 -141.551121) (xy 87.147908 -141.565884) (xy 87.12073 -141.575536) (xy 87.10041 -141.595602)
			(xy 87.088954 -141.607735) (xy 87.072253 -141.636613) (xy 87.063608 -141.668833) (xy 87.063612 -141.702192)
			(xy 87.072262 -141.734411) (xy 87.088969 -141.763285) (xy 87.10041 -141.775434) (xy 87.103712 -141.778736)
			(xy 87.103712 -142.16507) (xy 87.467951 -142.16507) (xy 87.471986 -142.089366) (xy 87.484045 -142.014521)
			(xy 87.503991 -141.94138) (xy 87.531598 -141.870775) (xy 87.566554 -141.803504) (xy 87.608462 -141.740329)
			(xy 87.656848 -141.681967) (xy 87.711164 -141.629079) (xy 87.770793 -141.582264) (xy 87.835061 -141.542052)
			(xy 87.903238 -141.5089) (xy 87.974554 -141.483182) (xy 88.048199 -141.46519) (xy 88.123339 -141.455128)
			(xy 88.199123 -141.453109) (xy 88.274693 -141.459158) (xy 88.349191 -141.473205) (xy 88.421774 -141.495091)
			(xy 88.49162 -141.524568) (xy 88.557937 -141.561303) (xy 88.619973 -141.604878) (xy 88.677026 -141.6548)
			(xy 88.72845 -141.710504) (xy 88.773661 -141.771359) (xy 88.812148 -141.836674) (xy 88.843474 -141.90571)
			(xy 88.867284 -141.977685) (xy 88.883309 -142.051783) (xy 88.891368 -142.127164) (xy 88.891872 -142.16507)
			(xy 88.891368 -142.202976) (xy 88.883309 -142.278357) (xy 88.867284 -142.352455) (xy 88.843474 -142.42443)
			(xy 88.812148 -142.493466) (xy 88.773661 -142.558781) (xy 88.72845 -142.619636) (xy 88.677026 -142.67534)
			(xy 88.619973 -142.725262) (xy 88.557937 -142.768837) (xy 88.49162 -142.805572) (xy 88.421774 -142.835049)
			(xy 88.349191 -142.856935) (xy 88.274693 -142.870982) (xy 88.199123 -142.877031) (xy 88.123339 -142.875012)
			(xy 88.048199 -142.86495) (xy 87.974554 -142.846958) (xy 87.903238 -142.82124) (xy 87.835061 -142.788088)
			(xy 87.770793 -142.747876) (xy 87.711164 -142.701061) (xy 87.656848 -142.648173) (xy 87.608462 -142.589811)
			(xy 87.566554 -142.526636) (xy 87.531598 -142.459365) (xy 87.503991 -142.38876) (xy 87.484045 -142.315619)
			(xy 87.471986 -142.240774) (xy 87.467951 -142.16507) (xy 87.103712 -142.16507) (xy 87.103712 -145.488914)
			(xy 87.111561 -145.510613) (xy 87.133954 -145.550955) (xy 87.163258 -145.586594) (xy 87.198512 -145.61636)
			(xy 87.238558 -145.639277) (xy 87.282082 -145.654592) (xy 87.327655 -145.661802) (xy 87.373781 -145.660671)
			(xy 87.418945 -145.651235) (xy 87.461666 -145.633806) (xy 87.500541 -145.608953) (xy 87.517732 -145.593562)
			(xy 90.15349 -142.957804) (xy 90.169657 -142.940875) (xy 90.196131 -142.902276) (xy 90.215095 -142.859485)
			(xy 90.225911 -142.813946) (xy 90.228212 -142.767198) (xy 90.221921 -142.720817) (xy 90.207251 -142.67637)
			(xy 90.184697 -142.635357) (xy 90.170254 -142.616936) (xy 90.148792 -142.590169) (xy 90.110534 -142.533212)
			(xy 90.077933 -142.472839) (xy 90.051291 -142.409609) (xy 90.030854 -142.344111) (xy 90.023442 -142.310612)
			(xy 90.01616 -142.273345) (xy 90.008637 -142.197782) (xy 90.009202 -142.121847) (xy 90.017846 -142.046404)
			(xy 90.034473 -141.97231) (xy 90.058893 -141.900407) (xy 90.090829 -141.831512) (xy 90.129917 -141.766408)
			(xy 90.175714 -141.705835) (xy 90.227699 -141.650482) (xy 90.285281 -141.600977) (xy 90.347806 -141.557883)
			(xy 90.414563 -141.521691) (xy 90.484793 -141.492811) (xy 90.557699 -141.471571) (xy 90.632452 -141.458213)
			(xy 90.708202 -141.452888) (xy 90.784088 -141.455658) (xy 90.859248 -141.466491) (xy 90.932828 -141.485263)
			(xy 90.968576 -141.498066) (xy 91.004107 -141.511831) (xy 91.072264 -141.545907) (xy 91.136391 -141.58707)
			(xy 91.195752 -141.63485) (xy 91.249667 -141.6887) (xy 91.29752 -141.748002) (xy 91.318588 -141.779752)
			(xy 91.342232 -141.817757) (xy 91.38083 -141.898518) (xy 91.39555 -141.940788) (xy 91.40952 -141.982698)
			(xy 91.483942 -142.031466) (xy 91.557348 -142.024354) (xy 91.572869 -142.022401) (xy 91.602331 -142.011918)
			(xy 91.628354 -141.994575) (xy 91.649369 -141.971417) (xy 91.664112 -141.943838) (xy 91.671695 -141.913499)
			(xy 91.672156 -141.897862) (xy 91.672156 -141.606016) (xy 91.671686 -141.589921) (xy 91.663628 -141.558756)
			(xy 91.648022 -141.530602) (xy 91.625862 -141.507254) (xy 91.612466 -141.49832) (xy 91.580925 -141.478001)
			(xy 91.521871 -141.431714) (xy 91.468014 -141.379472) (xy 91.419952 -141.321853) (xy 91.378218 -141.259498)
			(xy 91.343276 -141.193098) (xy 91.315512 -141.123392) (xy 91.295236 -141.051151) (xy 91.282673 -140.977178)
			(xy 91.277961 -140.902293) (xy 91.281153 -140.827329) (xy 91.292214 -140.753116) (xy 91.31102 -140.680479)
			(xy 91.337364 -140.610223) (xy 91.370953 -140.543129) (xy 91.411413 -140.47994) (xy 91.458297 -140.421358)
			(xy 91.511083 -140.368034) (xy 91.569186 -140.320559) (xy 91.631961 -140.27946) (xy 91.698711 -140.245192)
			(xy 91.768696 -140.218138) (xy 91.841139 -140.198595) (xy 91.915236 -140.186782) (xy 91.990164 -140.18283)
			(xy 92.065092 -140.186782) (xy 92.139189 -140.198595) (xy 92.211632 -140.218138) (xy 92.281617 -140.245192)
			(xy 92.348367 -140.27946) (xy 92.411142 -140.320559) (xy 92.469245 -140.368034) (xy 92.522031 -140.421358)
			(xy 92.568915 -140.47994) (xy 92.609375 -140.543129) (xy 92.642964 -140.610223) (xy 92.669308 -140.680479)
			(xy 92.688114 -140.753116) (xy 92.699175 -140.827329) (xy 92.702367 -140.902293) (xy 92.697655 -140.977178)
			(xy 92.685092 -141.051151) (xy 92.664816 -141.123392) (xy 92.637052 -141.193098) (xy 92.60211 -141.259498)
			(xy 92.560376 -141.321853) (xy 92.512314 -141.379472) (xy 92.458457 -141.431714) (xy 92.399403 -141.478001)
			(xy 92.367862 -141.49832) (xy 92.354467 -141.507252) (xy 92.332318 -141.530606) (xy 92.316721 -141.55876)
			(xy 92.308668 -141.589923) (xy 92.308172 -141.606016) (xy 92.308172 -141.61008) (xy 93.15476 -141.61008)
			(xy 93.158776 -141.49381) (xy 93.170803 -141.378095) (xy 93.190785 -141.263485) (xy 93.218627 -141.150526)
			(xy 93.254196 -141.039758) (xy 93.297322 -140.931707) (xy 93.347799 -140.826889) (xy 93.405388 -140.725804)
			(xy 93.469814 -140.628932) (xy 93.540769 -140.536736) (xy 93.617916 -140.449655) (xy 93.700887 -140.368104)
			(xy 93.789287 -140.292472) (xy 93.882694 -140.223118) (xy 93.980663 -140.160375) (xy 94.082727 -140.104539)
			(xy 94.188401 -140.055878) (xy 94.29718 -140.014624) (xy 94.408545 -139.980973) (xy 94.521968 -139.955085)
			(xy 94.636905 -139.937084) (xy 94.752811 -139.927055) (xy 94.869133 -139.925047) (xy 94.985316 -139.931069)
			(xy 95.100807 -139.945092) (xy 95.215055 -139.96705) (xy 95.327516 -139.996837) (xy 95.437654 -140.034312)
			(xy 95.544944 -140.079297) (xy 95.648875 -140.131576) (xy 95.748951 -140.190901) (xy 95.844697 -140.256989)
			(xy 95.935654 -140.329525) (xy 96.02139 -140.408164) (xy 96.101497 -140.49253) (xy 96.175593 -140.582222)
			(xy 96.243323 -140.676812) (xy 96.304367 -140.77585) (xy 96.358432 -140.878863) (xy 96.405262 -140.98536)
			(xy 96.444633 -141.094835) (xy 96.476357 -141.206765) (xy 96.500283 -141.320617) (xy 96.516297 -141.435849)
			(xy 96.524324 -141.551911) (xy 96.524826 -141.61008) (xy 96.524324 -141.668249) (xy 96.516297 -141.784311)
			(xy 96.500283 -141.899543) (xy 96.476357 -142.013395) (xy 96.444633 -142.125325) (xy 96.405262 -142.2348)
			(xy 96.358432 -142.341297) (xy 96.304367 -142.44431) (xy 96.243323 -142.543348) (xy 96.175593 -142.637938)
			(xy 96.101497 -142.72763) (xy 96.02139 -142.811996) (xy 95.935654 -142.890635) (xy 95.844697 -142.963171)
			(xy 95.748951 -143.029259) (xy 95.648875 -143.088584) (xy 95.544944 -143.140863) (xy 95.437654 -143.185848)
			(xy 95.327516 -143.223323) (xy 95.215055 -143.25311) (xy 95.100807 -143.275068) (xy 94.985316 -143.289091)
			(xy 94.869133 -143.295113) (xy 94.752811 -143.293105) (xy 94.636905 -143.283076) (xy 94.521968 -143.265075)
			(xy 94.408545 -143.239187) (xy 94.29718 -143.205536) (xy 94.188401 -143.164282) (xy 94.082727 -143.115621)
			(xy 93.980663 -143.059785) (xy 93.882694 -142.997042) (xy 93.789287 -142.927688) (xy 93.700887 -142.852056)
			(xy 93.617916 -142.770505) (xy 93.540769 -142.683424) (xy 93.469814 -142.591228) (xy 93.405388 -142.494356)
			(xy 93.347799 -142.393271) (xy 93.297322 -142.288453) (xy 93.254196 -142.180402) (xy 93.218627 -142.069634)
			(xy 93.190785 -141.956675) (xy 93.170803 -141.842065) (xy 93.158776 -141.72635) (xy 93.15476 -141.61008)
			(xy 92.308172 -141.61008) (xy 92.308172 -142.590012) (xy 87.472266 -147.425918) (xy 87.463376 -147.457414)
			(xy 87.455293 -147.483781) (xy 87.432589 -147.534038) (xy 87.402888 -147.580504) (xy 87.366808 -147.622212)
			(xy 87.3251 -147.658291) (xy 87.278634 -147.687992) (xy 87.228376 -147.710694) (xy 87.20201 -147.71878)
			(xy 87.170514 -147.72767) (xy 86.462108 -148.436076) (xy 86.462108 -152.433528) (xy 85.53577 -153.359866)
			(xy 86.877404 -153.359866) (xy 86.881424 -153.169215) (xy 86.893478 -152.978902) (xy 86.913544 -152.789267)
			(xy 86.941587 -152.600646) (xy 86.977556 -152.413376) (xy 87.021388 -152.227788) (xy 87.073005 -152.044213)
			(xy 87.132315 -151.862977) (xy 87.199213 -151.684402) (xy 87.273579 -151.508807) (xy 87.355281 -151.336502)
			(xy 87.444175 -151.167795) (xy 87.540101 -151.002985) (xy 87.64289 -150.842366) (xy 87.752359 -150.686223)
			(xy 87.868313 -150.534834) (xy 87.990547 -150.388467) (xy 88.118841 -150.247383) (xy 88.252969 -150.111834)
			(xy 88.392693 -149.982059) (xy 88.537763 -149.858289) (xy 88.687921 -149.740746) (xy 88.842902 -149.629637)
			(xy 89.002429 -149.52516) (xy 89.166218 -149.427501) (xy 89.333978 -149.336834) (xy 89.505412 -149.25332)
			(xy 89.680214 -149.177107) (xy 89.858073 -149.108331) (xy 90.038674 -149.047113) (xy 90.221694 -148.993564)
			(xy 90.40681 -148.947778) (xy 90.593691 -148.909836) (xy 90.782006 -148.879807) (xy 90.971419 -148.857742)
			(xy 91.161593 -148.843683) (xy 91.352192 -148.837653) (xy 91.542875 -148.839663) (xy 91.733304 -148.84971)
			(xy 91.92314 -148.867776) (xy 92.112046 -148.893829) (xy 92.299685 -148.927822) (xy 92.485725 -148.969695)
			(xy 92.669834 -149.019374) (xy 92.851685 -149.07677) (xy 93.030955 -149.141781) (xy 93.207325 -149.214292)
			(xy 93.380481 -149.294173) (xy 93.550116 -149.381283) (xy 93.715928 -149.475467) (xy 93.877622 -149.576558)
			(xy 94.03491 -149.684374) (xy 94.187513 -149.798726) (xy 94.335161 -149.919409) (xy 94.477589 -150.04621)
			(xy 94.614545 -150.178901) (xy 94.745786 -150.317249) (xy 94.871078 -150.461006) (xy 94.990198 -150.609917)
			(xy 95.102934 -150.763718) (xy 95.209087 -150.922134) (xy 95.308467 -151.084885) (xy 95.400897 -151.25168)
			(xy 95.486214 -151.422224) (xy 95.564266 -151.596212) (xy 95.634913 -151.773337) (xy 95.698031 -151.953282)
			(xy 95.753507 -152.135728) (xy 95.801242 -152.320351) (xy 95.841152 -152.506821) (xy 95.873165 -152.694809)
			(xy 95.897225 -152.883979) (xy 95.913288 -153.073995) (xy 95.921327 -153.264519) (xy 95.92183 -153.359866)
			(xy 95.921327 -153.455213) (xy 95.913288 -153.645737) (xy 95.897225 -153.835753) (xy 95.873165 -154.024923)
			(xy 95.841152 -154.212911) (xy 95.801242 -154.399381) (xy 95.753507 -154.584004) (xy 95.698031 -154.76645)
			(xy 95.634913 -154.946395) (xy 95.564266 -155.12352) (xy 95.486214 -155.297508) (xy 95.400897 -155.468052)
			(xy 95.308467 -155.634847) (xy 95.209087 -155.797598) (xy 95.102934 -155.956014) (xy 94.990198 -156.109815)
			(xy 94.871078 -156.258726) (xy 94.745786 -156.402483) (xy 94.614545 -156.540831) (xy 94.477589 -156.673522)
			(xy 94.335161 -156.800323) (xy 94.187513 -156.921006) (xy 94.03491 -157.035358) (xy 93.877622 -157.143174)
			(xy 93.715928 -157.244265) (xy 93.550116 -157.338449) (xy 93.380481 -157.425559) (xy 93.207325 -157.50544)
			(xy 93.030955 -157.577951) (xy 92.851685 -157.642962) (xy 92.669834 -157.700358) (xy 92.485725 -157.750037)
			(xy 92.299685 -157.79191) (xy 92.112046 -157.825903) (xy 91.92314 -157.851956) (xy 91.733304 -157.870022)
			(xy 91.542875 -157.880069) (xy 91.352192 -157.882079) (xy 91.161593 -157.876049) (xy 90.971419 -157.86199)
			(xy 90.782006 -157.839925) (xy 90.593691 -157.809896) (xy 90.40681 -157.771954) (xy 90.221694 -157.726168)
			(xy 90.038674 -157.672619) (xy 89.858073 -157.611401) (xy 89.680214 -157.542625) (xy 89.505412 -157.466412)
			(xy 89.333978 -157.382898) (xy 89.166218 -157.292231) (xy 89.002429 -157.194572) (xy 88.842902 -157.090095)
			(xy 88.687921 -156.978986) (xy 88.537763 -156.861443) (xy 88.392693 -156.737673) (xy 88.252969 -156.607898)
			(xy 88.118841 -156.472349) (xy 87.990547 -156.331265) (xy 87.868313 -156.184898) (xy 87.752359 -156.033509)
			(xy 87.64289 -155.877366) (xy 87.540101 -155.716747) (xy 87.444175 -155.551937) (xy 87.355281 -155.38323)
			(xy 87.273579 -155.210925) (xy 87.199213 -155.03533) (xy 87.132315 -154.856755) (xy 87.073005 -154.675519)
			(xy 87.021388 -154.491944) (xy 86.977556 -154.306356) (xy 86.941587 -154.119086) (xy 86.913544 -153.930465)
			(xy 86.893478 -153.74083) (xy 86.881424 -153.550517) (xy 86.877404 -153.359866) (xy 85.53577 -153.359866)
			(xy 79.250794 -159.644842) (xy 79.234859 -159.66149) (xy 79.208689 -159.699419) (xy 79.189787 -159.741445)
			(xy 79.178773 -159.78619) (xy 79.176008 -159.832188) (xy 79.181582 -159.87793) (xy 79.195312 -159.921918)
			(xy 79.216749 -159.962708) (xy 79.245189 -159.998965) (xy 79.279701 -160.0295) (xy 79.319154 -160.053311)
			(xy 79.362252 -160.069618) (xy 79.407585 -160.077887) (xy 79.430626 -160.07842) (xy 91.68638 -160.07842)
			(xy 98.997008 -152.767792) (xy 98.997008 -109.08411) (xy 92.337636 -102.424738) (xy 92.30614 -102.415848)
			(xy 92.279776 -102.407762) (xy 92.229525 -102.385053) (xy 92.183066 -102.355348) (xy 92.141366 -102.319266)
			(xy 92.105294 -102.277557) (xy 92.075601 -102.23109) (xy 92.052905 -102.180833) (xy 92.044774 -102.154482)
			(xy 92.035884 -102.122986) (xy 91.808046 -101.895148) (xy 88.370664 -101.895148) (xy 85.322156 -98.846386)
			(xy 85.322156 -98.426016) (xy 85.321686 -98.409921) (xy 85.313628 -98.378756) (xy 85.298022 -98.350602)
			(xy 85.275862 -98.327254) (xy 85.262466 -98.31832) (xy 85.230702 -98.297858) (xy 85.171254 -98.251217)
			(xy 85.117083 -98.198538) (xy 85.068799 -98.140416) (xy 85.026946 -98.077505) (xy 84.991995 -98.010513)
			(xy 84.964339 -97.940195) (xy 84.944291 -97.867342) (xy 84.932075 -97.792775) (xy 84.927829 -97.717333)
			(xy 84.931602 -97.641866) (xy 84.94335 -97.567223) (xy 84.962941 -97.494246) (xy 84.990155 -97.423756)
			(xy 85.024686 -97.356546) (xy 85.066143 -97.293374) (xy 85.114062 -97.23495) (xy 85.167901 -97.181933)
			(xy 85.227056 -97.134919) (xy 85.290859 -97.094439) (xy 85.358592 -97.060947) (xy 85.429493 -97.034822)
			(xy 85.502763 -97.016356) (xy 85.540088 -97.010474) (xy 85.555034 -97.007918) (xy 85.583197 -96.996708)
			(xy 85.607918 -96.979165) (xy 85.627799 -96.956283) (xy 85.641716 -96.929354) (xy 85.648883 -96.8999)
			(xy 85.649308 -96.884744) (xy 85.649308 -96.005396) (xy 85.64887 -95.990239) (xy 85.641711 -95.960782)
			(xy 85.627799 -95.933848) (xy 85.607921 -95.910961) (xy 85.583201 -95.893414) (xy 85.555037 -95.882201)
			(xy 85.540088 -95.879666) (xy 85.501698 -95.873704) (xy 85.426418 -95.854494) (xy 85.353677 -95.827199)
			(xy 85.284342 -95.792143) (xy 85.219238 -95.749744) (xy 85.15914 -95.700506) (xy 85.104762 -95.645015)
			(xy 85.056752 -95.583932) (xy 85.01568 -95.517982) (xy 84.982036 -95.447951) (xy 84.95622 -95.374673)
			(xy 84.93854 -95.299019) (xy 84.929204 -95.221888) (xy 84.928325 -95.1442) (xy 84.935914 -95.066879)
			(xy 84.943442 -95.028766) (xy 84.951473 -94.992753) (xy 84.974008 -94.92249) (xy 85.00369 -94.854935)
			(xy 85.040201 -94.790812) (xy 85.061298 -94.760542) (xy 85.083176 -94.730811) (xy 85.132152 -94.675574)
			(xy 85.186581 -94.625704) (xy 85.245879 -94.581735) (xy 85.309411 -94.54414) (xy 85.376492 -94.513322)
			(xy 85.446402 -94.489613) (xy 85.518391 -94.473267) (xy 85.591685 -94.46446) (xy 85.665497 -94.463286)
			(xy 85.739035 -94.469759) (xy 85.811507 -94.483807) (xy 85.882136 -94.505282) (xy 85.950163 -94.533952)
			(xy 86.014857 -94.569508) (xy 86.075523 -94.61157) (xy 86.131511 -94.659684) (xy 86.182217 -94.713336)
			(xy 86.227098 -94.771947) (xy 86.265672 -94.834889) (xy 86.282022 -94.867984) (xy 86.291962 -94.887693)
			(xy 86.317584 -94.923632) (xy 86.349029 -94.954604) (xy 86.385354 -94.979676) (xy 86.425464 -94.998094)
			(xy 86.468154 -95.009305) (xy 86.512138 -95.01297) (xy 86.556095 -95.00898) (xy 86.598701 -94.997455)
			(xy 86.638674 -94.978741) (xy 86.674813 -94.953402) (xy 86.690708 -94.938088) (xy 86.77656 -94.852236)
			(xy 86.787482 -94.852236) (xy 86.86165 -94.778068) (xy 86.86165 -94.725236) (xy 86.861062 -94.707949)
			(xy 86.851767 -94.674647) (xy 86.833875 -94.645061) (xy 86.808699 -94.621362) (xy 86.778087 -94.605289)
			(xy 86.76132 -94.60103) (xy 86.761066 -94.60103) (xy 86.724071 -94.592618) (xy 86.651987 -94.568948)
			(xy 86.582829 -94.537745) (xy 86.517384 -94.499361) (xy 86.456392 -94.454233) (xy 86.400547 -94.402874)
			(xy 86.350483 -94.345865) (xy 86.306767 -94.283854) (xy 86.269896 -94.217545) (xy 86.240287 -94.147689)
			(xy 86.218278 -94.07508) (xy 86.204117 -94.000542) (xy 86.197966 -93.924921) (xy 86.199894 -93.849074)
			(xy 86.209879 -93.773863) (xy 86.227808 -93.70014) (xy 86.253478 -93.628744) (xy 86.286598 -93.560483)
			(xy 86.32679 -93.496132) (xy 86.3736 -93.436422) (xy 86.426496 -93.382031) (xy 86.484878 -93.333575)
			(xy 86.548084 -93.291604) (xy 86.615395 -93.256595) (xy 86.686049 -93.228945) (xy 86.759243 -93.208968)
			(xy 86.834146 -93.19689) (xy 86.90991 -93.192849) (xy 86.985674 -93.19689) (xy 87.060577 -93.208968)
			(xy 87.133771 -93.228945) (xy 87.204425 -93.256595) (xy 87.271736 -93.291604) (xy 87.334942 -93.333575)
			(xy 87.393324 -93.382031) (xy 87.44622 -93.436422) (xy 87.49303 -93.496132) (xy 87.533222 -93.560483)
			(xy 87.566342 -93.628744) (xy 87.592012 -93.70014) (xy 87.609941 -93.773863) (xy 87.619926 -93.849074)
			(xy 87.621349 -93.90507) (xy 88.737697 -93.90507) (xy 88.741732 -93.829366) (xy 88.753791 -93.754521)
			(xy 88.773737 -93.68138) (xy 88.801344 -93.610775) (xy 88.8363 -93.543504) (xy 88.878208 -93.480329)
			(xy 88.926594 -93.421967) (xy 88.98091 -93.369079) (xy 89.040539 -93.322264) (xy 89.104807 -93.282052)
			(xy 89.172984 -93.2489) (xy 89.2443 -93.223182) (xy 89.317945 -93.20519) (xy 89.393085 -93.195128)
			(xy 89.468869 -93.193109) (xy 89.544439 -93.199158) (xy 89.618937 -93.213205) (xy 89.69152 -93.235091)
			(xy 89.761366 -93.264568) (xy 89.827683 -93.301303) (xy 89.889719 -93.344878) (xy 89.946772 -93.3948)
			(xy 89.998196 -93.450504) (xy 90.043407 -93.511359) (xy 90.081894 -93.576674) (xy 90.11322 -93.64571)
			(xy 90.13703 -93.717685) (xy 90.153055 -93.791783) (xy 90.161114 -93.867164) (xy 90.161618 -93.90507)
			(xy 91.277697 -93.90507) (xy 91.281732 -93.829366) (xy 91.293791 -93.754521) (xy 91.313737 -93.68138)
			(xy 91.341344 -93.610775) (xy 91.3763 -93.543504) (xy 91.418208 -93.480329) (xy 91.466594 -93.421967)
			(xy 91.52091 -93.369079) (xy 91.580539 -93.322264) (xy 91.644807 -93.282052) (xy 91.712984 -93.2489)
			(xy 91.7843 -93.223182) (xy 91.857945 -93.20519) (xy 91.933085 -93.195128) (xy 92.008869 -93.193109)
			(xy 92.084439 -93.199158) (xy 92.158937 -93.213205) (xy 92.23152 -93.235091) (xy 92.301366 -93.264568)
			(xy 92.367683 -93.301303) (xy 92.429719 -93.344878) (xy 92.486772 -93.3948) (xy 92.538196 -93.450504)
			(xy 92.583407 -93.511359) (xy 92.621894 -93.576674) (xy 92.65322 -93.64571) (xy 92.67703 -93.717685)
			(xy 92.693055 -93.791783) (xy 92.701114 -93.867164) (xy 92.701618 -93.90507) (xy 92.701114 -93.942976)
			(xy 92.693055 -94.018357) (xy 92.67703 -94.092455) (xy 92.65322 -94.16443) (xy 92.621894 -94.233466)
			(xy 92.583407 -94.298781) (xy 92.538196 -94.359636) (xy 92.486772 -94.41534) (xy 92.429719 -94.465262)
			(xy 92.367683 -94.508837) (xy 92.301366 -94.545572) (xy 92.23152 -94.575049) (xy 92.158937 -94.596935)
			(xy 92.084439 -94.610982) (xy 92.008869 -94.617031) (xy 91.933085 -94.615012) (xy 91.857945 -94.60495)
			(xy 91.7843 -94.586958) (xy 91.712984 -94.56124) (xy 91.644807 -94.528088) (xy 91.580539 -94.487876)
			(xy 91.52091 -94.441061) (xy 91.466594 -94.388173) (xy 91.418208 -94.329811) (xy 91.3763 -94.266636)
			(xy 91.341344 -94.199365) (xy 91.313737 -94.12876) (xy 91.293791 -94.055619) (xy 91.281732 -93.980774)
			(xy 91.277697 -93.90507) (xy 90.161618 -93.90507) (xy 90.161114 -93.942976) (xy 90.153055 -94.018357)
			(xy 90.13703 -94.092455) (xy 90.11322 -94.16443) (xy 90.081894 -94.233466) (xy 90.043407 -94.298781)
			(xy 89.998196 -94.359636) (xy 89.946772 -94.41534) (xy 89.889719 -94.465262) (xy 89.827683 -94.508837)
			(xy 89.761366 -94.545572) (xy 89.69152 -94.575049) (xy 89.618937 -94.596935) (xy 89.544439 -94.610982)
			(xy 89.468869 -94.617031) (xy 89.393085 -94.615012) (xy 89.317945 -94.60495) (xy 89.2443 -94.586958)
			(xy 89.172984 -94.56124) (xy 89.104807 -94.528088) (xy 89.040539 -94.487876) (xy 88.98091 -94.441061)
			(xy 88.926594 -94.388173) (xy 88.878208 -94.329811) (xy 88.8363 -94.266636) (xy 88.801344 -94.199365)
			(xy 88.773737 -94.12876) (xy 88.753791 -94.055619) (xy 88.741732 -93.980774) (xy 88.737697 -93.90507)
			(xy 87.621349 -93.90507) (xy 87.621854 -93.924921) (xy 87.615703 -94.000542) (xy 87.601542 -94.07508)
			(xy 87.579533 -94.147689) (xy 87.549924 -94.217545) (xy 87.513053 -94.283854) (xy 87.469337 -94.345865)
			(xy 87.419273 -94.402874) (xy 87.363428 -94.454233) (xy 87.302436 -94.499361) (xy 87.236991 -94.537745)
			(xy 87.167833 -94.568948) (xy 87.095749 -94.592618) (xy 87.058754 -94.60103) (xy 87.0585 -94.60103)
			(xy 87.041707 -94.605222) (xy 87.011068 -94.621291) (xy 86.985873 -94.645002) (xy 86.967975 -94.674609)
			(xy 86.958689 -94.707937) (xy 86.95817 -94.725236) (xy 86.95817 -94.778068) (xy 87.032338 -94.852236)
			(xy 87.472012 -94.852236) (xy 87.578184 -94.793816) (xy 87.595202 -94.769432) (xy 87.616693 -94.739258)
			(xy 87.664989 -94.683079) (xy 87.718855 -94.632218) (xy 87.777711 -94.587225) (xy 87.80907 -94.567502)
			(xy 87.839941 -94.549183) (xy 87.904672 -94.518144) (xy 87.972201 -94.493784) (xy 88.04184 -94.476351)
			(xy 88.077294 -94.470728) (xy 88.115859 -94.465637) (xy 88.193602 -94.462884) (xy 88.271182 -94.468626)
			(xy 88.347674 -94.482794) (xy 88.422163 -94.505219) (xy 88.493763 -94.535635) (xy 88.561619 -94.573678)
			(xy 88.624921 -94.618894) (xy 88.682914 -94.670744) (xy 88.734907 -94.728609) (xy 88.780279 -94.791799)
			(xy 88.818489 -94.859561) (xy 88.849081 -94.931085) (xy 88.87169 -95.005519) (xy 88.886047 -95.081975)
			(xy 88.889586 -95.120714) (xy 88.891998 -95.158594) (xy 88.891501 -95.17507) (xy 90.007697 -95.17507)
			(xy 90.011732 -95.099366) (xy 90.023791 -95.024521) (xy 90.043737 -94.95138) (xy 90.071344 -94.880775)
			(xy 90.1063 -94.813504) (xy 90.148208 -94.750329) (xy 90.196594 -94.691967) (xy 90.25091 -94.639079)
			(xy 90.310539 -94.592264) (xy 90.374807 -94.552052) (xy 90.442984 -94.5189) (xy 90.5143 -94.493182)
			(xy 90.587945 -94.47519) (xy 90.663085 -94.465128) (xy 90.738869 -94.463109) (xy 90.814439 -94.469158)
			(xy 90.888937 -94.483205) (xy 90.96152 -94.505091) (xy 91.031366 -94.534568) (xy 91.097683 -94.571303)
			(xy 91.159719 -94.614878) (xy 91.216772 -94.6648) (xy 91.268196 -94.720504) (xy 91.313407 -94.781359)
			(xy 91.351894 -94.846674) (xy 91.38322 -94.91571) (xy 91.40703 -94.987685) (xy 91.423055 -95.061783)
			(xy 91.431114 -95.137164) (xy 91.431618 -95.17507) (xy 91.431114 -95.212976) (xy 91.423055 -95.288357)
			(xy 91.40703 -95.362455) (xy 91.38322 -95.43443) (xy 91.351894 -95.503466) (xy 91.313407 -95.568781)
			(xy 91.268196 -95.629636) (xy 91.216772 -95.68534) (xy 91.159719 -95.735262) (xy 91.097683 -95.778837)
			(xy 91.031366 -95.815572) (xy 90.96152 -95.845049) (xy 90.888937 -95.866935) (xy 90.814439 -95.880982)
			(xy 90.738869 -95.887031) (xy 90.663085 -95.885012) (xy 90.587945 -95.87495) (xy 90.5143 -95.856958)
			(xy 90.442984 -95.83124) (xy 90.374807 -95.798088) (xy 90.310539 -95.757876) (xy 90.25091 -95.711061)
			(xy 90.196594 -95.658173) (xy 90.148208 -95.599811) (xy 90.1063 -95.536636) (xy 90.071344 -95.469365)
			(xy 90.043737 -95.39876) (xy 90.023791 -95.325619) (xy 90.011732 -95.250774) (xy 90.007697 -95.17507)
			(xy 88.891501 -95.17507) (xy 88.889711 -95.234466) (xy 88.879363 -95.309664) (xy 88.861072 -95.383334)
			(xy 88.835044 -95.454639) (xy 88.801577 -95.52277) (xy 88.761049 -95.586952) (xy 88.713921 -95.646457)
			(xy 88.660729 -95.700609) (xy 88.602076 -95.748793) (xy 88.538629 -95.790461) (xy 88.471108 -95.825142)
			(xy 88.40028 -95.85244) (xy 88.326949 -95.872045) (xy 88.251947 -95.883736) (xy 88.176128 -95.887379)
			(xy 88.100352 -95.882933) (xy 88.025479 -95.870449) (xy 87.952359 -95.850068) (xy 87.881824 -95.822021)
			(xy 87.814674 -95.786628) (xy 87.751671 -95.744289) (xy 87.693532 -95.695487) (xy 87.640917 -95.640775)
			(xy 87.594422 -95.580774) (xy 87.57412 -95.548704) (xy 87.57412 -95.54845) (xy 87.565185 -95.534937)
			(xy 87.541758 -95.512576) (xy 87.513459 -95.496827) (xy 87.482109 -95.488701) (xy 87.465916 -95.488252)
			(xy 87.039704 -95.488252) (xy 86.993476 -95.53448) (xy 86.968584 -95.559118) (xy 86.951312 -95.626682)
			(xy 86.961472 -95.660464) (xy 86.966854 -95.676651) (xy 86.984873 -95.705603) (xy 87.009905 -95.728759)
			(xy 87.04017 -95.744471) (xy 87.056722 -95.748602) (xy 87.056976 -95.748602) (xy 87.094912 -95.757149)
			(xy 87.168795 -95.781421) (xy 87.239592 -95.8136) (xy 87.306461 -95.853304) (xy 87.368604 -95.900058)
			(xy 87.425282 -95.953306) (xy 87.45093 -95.982536) (xy 87.474609 -96.010974) (xy 87.516588 -96.07192)
			(xy 87.552014 -96.136895) (xy 87.580506 -96.205195) (xy 87.601754 -96.276084) (xy 87.615529 -96.348796)
			(xy 87.621683 -96.422544) (xy 87.621489 -96.44507) (xy 88.737697 -96.44507) (xy 88.741732 -96.369366)
			(xy 88.753791 -96.294521) (xy 88.773737 -96.22138) (xy 88.801344 -96.150775) (xy 88.8363 -96.083504)
			(xy 88.878208 -96.020329) (xy 88.926594 -95.961967) (xy 88.98091 -95.909079) (xy 89.040539 -95.862264)
			(xy 89.104807 -95.822052) (xy 89.172984 -95.7889) (xy 89.2443 -95.763182) (xy 89.317945 -95.74519)
			(xy 89.393085 -95.735128) (xy 89.468869 -95.733109) (xy 89.544439 -95.739158) (xy 89.618937 -95.753205)
			(xy 89.69152 -95.775091) (xy 89.761366 -95.804568) (xy 89.827683 -95.841303) (xy 89.889719 -95.884878)
			(xy 89.946772 -95.9348) (xy 89.998196 -95.990504) (xy 90.043407 -96.051359) (xy 90.081894 -96.116674)
			(xy 90.11322 -96.18571) (xy 90.13703 -96.257685) (xy 90.153055 -96.331783) (xy 90.161114 -96.407164)
			(xy 90.161618 -96.44507) (xy 91.277697 -96.44507) (xy 91.281732 -96.369366) (xy 91.293791 -96.294521)
			(xy 91.313737 -96.22138) (xy 91.341344 -96.150775) (xy 91.3763 -96.083504) (xy 91.418208 -96.020329)
			(xy 91.466594 -95.961967) (xy 91.52091 -95.909079) (xy 91.580539 -95.862264) (xy 91.644807 -95.822052)
			(xy 91.712984 -95.7889) (xy 91.7843 -95.763182) (xy 91.857945 -95.74519) (xy 91.933085 -95.735128)
			(xy 92.008869 -95.733109) (xy 92.084439 -95.739158) (xy 92.158937 -95.753205) (xy 92.23152 -95.775091)
			(xy 92.301366 -95.804568) (xy 92.367683 -95.841303) (xy 92.429719 -95.884878) (xy 92.486772 -95.9348)
			(xy 92.538196 -95.990504) (xy 92.583407 -96.051359) (xy 92.621894 -96.116674) (xy 92.65322 -96.18571)
			(xy 92.67703 -96.257685) (xy 92.693055 -96.331783) (xy 92.701114 -96.407164) (xy 92.701618 -96.44507)
			(xy 92.701114 -96.482976) (xy 92.693055 -96.558357) (xy 92.67703 -96.632455) (xy 92.65322 -96.70443)
			(xy 92.621894 -96.773466) (xy 92.583407 -96.838781) (xy 92.538196 -96.899636) (xy 92.486772 -96.95534)
			(xy 92.429719 -97.005262) (xy 92.367683 -97.048837) (xy 92.301366 -97.085572) (xy 92.23152 -97.115049)
			(xy 92.158937 -97.136935) (xy 92.084439 -97.150982) (xy 92.008869 -97.157031) (xy 91.933085 -97.155012)
			(xy 91.857945 -97.14495) (xy 91.7843 -97.126958) (xy 91.712984 -97.10124) (xy 91.644807 -97.068088)
			(xy 91.580539 -97.027876) (xy 91.52091 -96.981061) (xy 91.466594 -96.928173) (xy 91.418208 -96.869811)
			(xy 91.3763 -96.806636) (xy 91.341344 -96.739365) (xy 91.313737 -96.66876) (xy 91.293791 -96.595619)
			(xy 91.281732 -96.520774) (xy 91.277697 -96.44507) (xy 90.161618 -96.44507) (xy 90.161114 -96.482976)
			(xy 90.153055 -96.558357) (xy 90.13703 -96.632455) (xy 90.11322 -96.70443) (xy 90.081894 -96.773466)
			(xy 90.043407 -96.838781) (xy 89.998196 -96.899636) (xy 89.946772 -96.95534) (xy 89.889719 -97.005262)
			(xy 89.827683 -97.048837) (xy 89.761366 -97.085572) (xy 89.69152 -97.115049) (xy 89.618937 -97.136935)
			(xy 89.544439 -97.150982) (xy 89.468869 -97.157031) (xy 89.393085 -97.155012) (xy 89.317945 -97.14495)
			(xy 89.2443 -97.126958) (xy 89.172984 -97.10124) (xy 89.104807 -97.068088) (xy 89.040539 -97.027876)
			(xy 88.98091 -96.981061) (xy 88.926594 -96.928173) (xy 88.878208 -96.869811) (xy 88.8363 -96.806636)
			(xy 88.801344 -96.739365) (xy 88.773737 -96.66876) (xy 88.753791 -96.595619) (xy 88.741732 -96.520774)
			(xy 88.737697 -96.44507) (xy 87.621489 -96.44507) (xy 87.621364 -96.459548) (xy 87.620029 -96.498732)
			(xy 87.60983 -96.57647) (xy 87.591146 -96.652617) (xy 87.564206 -96.726248) (xy 87.529334 -96.796472)
			(xy 87.486954 -96.862436) (xy 87.437579 -96.923342) (xy 87.381808 -96.97845) (xy 87.320317 -97.027095)
			(xy 87.287354 -97.04832) (xy 87.27396 -97.057253) (xy 87.251812 -97.080607) (xy 87.236216 -97.108761)
			(xy 87.228163 -97.139923) (xy 87.227664 -97.156016) (xy 87.227664 -97.562924) (xy 87.22821 -97.579572)
			(xy 87.236831 -97.611733) (xy 87.25348 -97.640567) (xy 87.277023 -97.664112) (xy 87.305856 -97.680764)
			(xy 87.338016 -97.689388) (xy 87.354664 -97.689924) (xy 87.400892 -97.689924) (xy 87.47125 -97.63125)
			(xy 87.479632 -97.586038) (xy 87.486629 -97.550615) (xy 87.506872 -97.481302) (xy 87.534025 -97.414392)
			(xy 87.567808 -97.350574) (xy 87.607876 -97.290501) (xy 87.653817 -97.234791) (xy 87.705158 -97.184016)
			(xy 87.761375 -97.138696) (xy 87.821888 -97.099298) (xy 87.853774 -97.082356) (xy 87.887074 -97.065732)
			(xy 87.95643 -97.038715) (xy 88.028226 -97.019083) (xy 88.101679 -97.007053) (xy 88.175987 -97.002755)
			(xy 88.250338 -97.006236) (xy 88.323919 -97.017459) (xy 88.395927 -97.0363) (xy 88.465575 -97.062554)
			(xy 88.532102 -97.095934) (xy 88.594782 -97.136075) (xy 88.65293 -97.182539) (xy 88.705911 -97.234819)
			(xy 88.753146 -97.292342) (xy 88.794119 -97.354482) (xy 88.828382 -97.420559) (xy 88.855562 -97.489851)
			(xy 88.87536 -97.561601) (xy 88.881966 -97.59823) (xy 88.887276 -97.632646) (xy 88.891971 -97.702128)
			(xy 88.89158 -97.71507) (xy 90.007697 -97.71507) (xy 90.011732 -97.639366) (xy 90.023791 -97.564521)
			(xy 90.043737 -97.49138) (xy 90.071344 -97.420775) (xy 90.1063 -97.353504) (xy 90.148208 -97.290329)
			(xy 90.196594 -97.231967) (xy 90.25091 -97.179079) (xy 90.310539 -97.132264) (xy 90.374807 -97.092052)
			(xy 90.442984 -97.0589) (xy 90.5143 -97.033182) (xy 90.587945 -97.01519) (xy 90.663085 -97.005128)
			(xy 90.738869 -97.003109) (xy 90.814439 -97.009158) (xy 90.888937 -97.023205) (xy 90.96152 -97.045091)
			(xy 91.031366 -97.074568) (xy 91.097683 -97.111303) (xy 91.159719 -97.154878) (xy 91.165664 -97.16008)
			(xy 93.154506 -97.16008) (xy 93.158522 -97.04381) (xy 93.170549 -96.928095) (xy 93.190531 -96.813485)
			(xy 93.218373 -96.700526) (xy 93.253942 -96.589758) (xy 93.297068 -96.481707) (xy 93.347545 -96.376889)
			(xy 93.405134 -96.275804) (xy 93.46956 -96.178932) (xy 93.540515 -96.086736) (xy 93.617662 -95.999655)
			(xy 93.700633 -95.918104) (xy 93.789033 -95.842472) (xy 93.88244 -95.773118) (xy 93.980409 -95.710375)
			(xy 94.082473 -95.654539) (xy 94.188147 -95.605878) (xy 94.296926 -95.564624) (xy 94.408291 -95.530973)
			(xy 94.521714 -95.505085) (xy 94.636651 -95.487084) (xy 94.752557 -95.477055) (xy 94.868879 -95.475047)
			(xy 94.985062 -95.481069) (xy 95.100553 -95.495092) (xy 95.214801 -95.51705) (xy 95.327262 -95.546837)
			(xy 95.4374 -95.584312) (xy 95.54469 -95.629297) (xy 95.648621 -95.681576) (xy 95.748697 -95.740901)
			(xy 95.844443 -95.806989) (xy 95.9354 -95.879525) (xy 96.021136 -95.958164) (xy 96.101243 -96.04253)
			(xy 96.175339 -96.132222) (xy 96.243069 -96.226812) (xy 96.304113 -96.32585) (xy 96.358178 -96.428863)
			(xy 96.405008 -96.53536) (xy 96.444379 -96.644835) (xy 96.476103 -96.756765) (xy 96.500029 -96.870617)
			(xy 96.516043 -96.985849) (xy 96.52407 -97.101911) (xy 96.524572 -97.16008) (xy 96.52407 -97.218249)
			(xy 96.516043 -97.334311) (xy 96.500029 -97.449543) (xy 96.476103 -97.563395) (xy 96.444379 -97.675325)
			(xy 96.405008 -97.7848) (xy 96.358178 -97.891297) (xy 96.304113 -97.99431) (xy 96.243069 -98.093348)
			(xy 96.175339 -98.187938) (xy 96.101243 -98.27763) (xy 96.021136 -98.361996) (xy 95.9354 -98.440635)
			(xy 95.844443 -98.513171) (xy 95.748697 -98.579259) (xy 95.648621 -98.638584) (xy 95.54469 -98.690863)
			(xy 95.4374 -98.735848) (xy 95.327262 -98.773323) (xy 95.214801 -98.80311) (xy 95.100553 -98.825068)
			(xy 94.985062 -98.839091) (xy 94.868879 -98.845113) (xy 94.752557 -98.843105) (xy 94.636651 -98.833076)
			(xy 94.521714 -98.815075) (xy 94.408291 -98.789187) (xy 94.296926 -98.755536) (xy 94.188147 -98.714282)
			(xy 94.082473 -98.665621) (xy 93.980409 -98.609785) (xy 93.88244 -98.547042) (xy 93.789033 -98.477688)
			(xy 93.700633 -98.402056) (xy 93.617662 -98.320505) (xy 93.540515 -98.233424) (xy 93.46956 -98.141228)
			(xy 93.405134 -98.044356) (xy 93.347545 -97.943271) (xy 93.297068 -97.838453) (xy 93.253942 -97.730402)
			(xy 93.218373 -97.619634) (xy 93.190531 -97.506675) (xy 93.170549 -97.392065) (xy 93.158522 -97.27635)
			(xy 93.154506 -97.16008) (xy 91.165664 -97.16008) (xy 91.216772 -97.2048) (xy 91.268196 -97.260504)
			(xy 91.313407 -97.321359) (xy 91.351894 -97.386674) (xy 91.38322 -97.45571) (xy 91.40703 -97.527685)
			(xy 91.423055 -97.601783) (xy 91.431114 -97.677164) (xy 91.431618 -97.71507) (xy 91.431114 -97.752976)
			(xy 91.423055 -97.828357) (xy 91.40703 -97.902455) (xy 91.38322 -97.97443) (xy 91.351894 -98.043466)
			(xy 91.313407 -98.108781) (xy 91.268196 -98.169636) (xy 91.216772 -98.22534) (xy 91.159719 -98.275262)
			(xy 91.097683 -98.318837) (xy 91.031366 -98.355572) (xy 90.96152 -98.385049) (xy 90.888937 -98.406935)
			(xy 90.814439 -98.420982) (xy 90.738869 -98.427031) (xy 90.663085 -98.425012) (xy 90.587945 -98.41495)
			(xy 90.5143 -98.396958) (xy 90.442984 -98.37124) (xy 90.374807 -98.338088) (xy 90.310539 -98.297876)
			(xy 90.25091 -98.251061) (xy 90.196594 -98.198173) (xy 90.148208 -98.139811) (xy 90.1063 -98.076636)
			(xy 90.071344 -98.009365) (xy 90.043737 -97.93876) (xy 90.023791 -97.865619) (xy 90.011732 -97.790774)
			(xy 90.007697 -97.71507) (xy 88.89158 -97.71507) (xy 88.889866 -97.771736) (xy 88.880979 -97.840808)
			(xy 88.873584 -97.874836) (xy 88.870438 -97.890632) (xy 88.871309 -97.922817) (xy 88.880202 -97.953762)
			(xy 88.896554 -97.981499) (xy 88.90762 -97.9932) (xy 90.150696 -99.236276) (xy 92.893896 -99.236276)
			(xy 95.207582 -101.549962) (xy 95.239078 -101.558852) (xy 95.265446 -101.566934) (xy 95.315705 -101.589635)
			(xy 95.362173 -101.619335) (xy 95.403882 -101.655415) (xy 95.439962 -101.697123) (xy 95.469663 -101.74359)
			(xy 95.492365 -101.79385) (xy 95.500444 -101.820218) (xy 95.509334 -101.851714) (xy 101.17582 -107.5182)
			(xy 101.17582 -153.044906) (xy 91.963494 -162.257232) (xy 77.04201 -162.257232) (xy 73.575129 -165.724113)
			(xy 76.871175 -165.724113) (xy 76.875061 -165.669758) (xy 76.886643 -165.616509) (xy 76.905686 -165.56545)
			(xy 76.931801 -165.517621) (xy 76.964458 -165.473996) (xy 77.00299 -165.435463) (xy 77.046615 -165.402805)
			(xy 77.094443 -165.376689) (xy 77.145502 -165.357645) (xy 77.19875 -165.346062) (xy 77.253106 -165.342175)
			(xy 77.307461 -165.346064) (xy 77.360709 -165.357649) (xy 77.411767 -165.376694) (xy 77.459595 -165.402811)
			(xy 77.481684 -165.41877) (xy 77.500696 -165.432366) (xy 77.542579 -165.453098) (xy 77.587547 -165.465824)
			(xy 77.634084 -165.470114) (xy 77.680621 -165.465824) (xy 77.725589 -165.453098) (xy 77.767472 -165.432366)
			(xy 77.786484 -165.41877) (xy 77.808593 -165.402838) (xy 77.856418 -165.376718) (xy 77.907474 -165.35767)
			(xy 77.960722 -165.346083) (xy 78.015076 -165.342191) (xy 78.069431 -165.346076) (xy 78.12268 -165.357657)
			(xy 78.173738 -165.376698) (xy 78.221567 -165.402812) (xy 78.265192 -165.435468) (xy 78.303725 -165.474)
			(xy 78.336382 -165.517624) (xy 78.362497 -165.565452) (xy 78.38154 -165.61651) (xy 78.393123 -165.669758)
			(xy 78.397009 -165.724113) (xy 79.675567 -165.724113) (xy 79.679453 -165.669756) (xy 79.691036 -165.616505)
			(xy 79.710079 -165.565445) (xy 79.736196 -165.517614) (xy 79.768854 -165.473988) (xy 79.807388 -165.435453)
			(xy 79.851015 -165.402795) (xy 79.898845 -165.376679) (xy 79.949906 -165.357636) (xy 80.003156 -165.346053)
			(xy 80.057514 -165.342167) (xy 80.111871 -165.346057) (xy 80.165121 -165.357643) (xy 80.21618 -165.37669)
			(xy 80.264008 -165.40281) (xy 80.286098 -165.41877) (xy 80.30511 -165.432366) (xy 80.346993 -165.453098)
			(xy 80.391961 -165.465824) (xy 80.438498 -165.470114) (xy 80.485035 -165.465824) (xy 80.530003 -165.453098)
			(xy 80.571886 -165.432366) (xy 80.590898 -165.41877) (xy 80.613007 -165.40284) (xy 80.660831 -165.376721)
			(xy 80.711886 -165.357676) (xy 80.765132 -165.34609) (xy 80.819484 -165.3422) (xy 80.873837 -165.346085)
			(xy 80.927083 -165.357667) (xy 80.97814 -165.376708) (xy 81.025966 -165.402822) (xy 81.069589 -165.435477)
			(xy 81.108121 -165.474009) (xy 81.140776 -165.517631) (xy 81.166891 -165.565458) (xy 81.185933 -165.616514)
			(xy 81.197514 -165.66976) (xy 81.2014 -165.724113) (xy 81.197511 -165.778466) (xy 81.185925 -165.831711)
			(xy 81.16688 -165.882766) (xy 81.140762 -165.930591) (xy 81.108104 -165.974211) (xy 81.069569 -166.01274)
			(xy 81.025944 -166.045392) (xy 80.978116 -166.071503) (xy 80.927058 -166.090541) (xy 80.873811 -166.102119)
			(xy 80.819458 -166.106) (xy 80.765105 -166.102107) (xy 80.711861 -166.090517) (xy 80.660807 -166.071468)
			(xy 80.612985 -166.045346) (xy 80.590898 -166.029386) (xy 80.571886 -166.01579) (xy 80.530003 -165.995058)
			(xy 80.485035 -165.982332) (xy 80.438498 -165.978042) (xy 80.391961 -165.982332) (xy 80.346993 -165.995058)
			(xy 80.30511 -166.01579) (xy 80.286098 -166.029386) (xy 80.264031 -166.045375) (xy 80.216204 -166.071499)
			(xy 80.165146 -166.090549) (xy 80.111897 -166.102139) (xy 80.05754 -166.106033) (xy 80.003183 -166.102151)
			(xy 79.949931 -166.090572) (xy 79.898869 -166.071532) (xy 79.851037 -166.045419) (xy 79.807408 -166.012764)
			(xy 79.768871 -165.974232) (xy 79.73621 -165.930608) (xy 79.71009 -165.882779) (xy 79.691043 -165.83172)
			(xy 79.679457 -165.77847) (xy 79.675567 -165.724113) (xy 78.397009 -165.724113) (xy 78.393119 -165.778468)
			(xy 78.381533 -165.831715) (xy 78.362486 -165.882772) (xy 78.336367 -165.930598) (xy 78.303707 -165.97422)
			(xy 78.265172 -166.012749) (xy 78.221544 -166.045402) (xy 78.173714 -166.071513) (xy 78.122654 -166.090551)
			(xy 78.069405 -166.102128) (xy 78.01505 -166.106008) (xy 77.960696 -166.102114) (xy 77.907449 -166.090522)
			(xy 77.856394 -166.071471) (xy 77.808571 -166.045347) (xy 77.786484 -166.029386) (xy 77.767472 -166.01579)
			(xy 77.725589 -165.995058) (xy 77.680621 -165.982332) (xy 77.634084 -165.978042) (xy 77.587547 -165.982332)
			(xy 77.542579 -165.995058) (xy 77.500696 -166.01579) (xy 77.481684 -166.029386) (xy 77.459617 -166.045374)
			(xy 77.411791 -166.071495) (xy 77.360735 -166.090544) (xy 77.307487 -166.102132) (xy 77.253132 -166.106025)
			(xy 77.198777 -166.102141) (xy 77.145527 -166.090562) (xy 77.094467 -166.071522) (xy 77.046637 -166.045409)
			(xy 77.00301 -166.012755) (xy 76.964475 -165.974224) (xy 76.931815 -165.930601) (xy 76.905697 -165.882774)
			(xy 76.886651 -165.831717) (xy 76.875065 -165.778468) (xy 76.871175 -165.724113) (xy 73.575129 -165.724113)
			(xy 71.339761 -167.959481) (xy 76.871219 -167.959481) (xy 76.875109 -167.905132) (xy 76.886694 -167.85189)
			(xy 76.905739 -167.800839) (xy 76.931855 -167.753017) (xy 76.964512 -167.7094) (xy 77.003043 -167.670874)
			(xy 77.046666 -167.638224) (xy 77.094491 -167.612115) (xy 77.145545 -167.593078) (xy 77.198789 -167.581501)
			(xy 77.253138 -167.577619) (xy 77.307487 -167.581511) (xy 77.360728 -167.593099) (xy 77.411779 -167.612147)
			(xy 77.459599 -167.638265) (xy 77.481684 -167.654224) (xy 77.500696 -167.66782) (xy 77.542579 -167.688552)
			(xy 77.587547 -167.701278) (xy 77.634084 -167.705568) (xy 77.680621 -167.701278) (xy 77.725589 -167.688552)
			(xy 77.767472 -167.66782) (xy 77.786484 -167.654224) (xy 77.808543 -167.63822) (xy 77.856371 -167.612092)
			(xy 77.907431 -167.593038) (xy 77.960683 -167.581444) (xy 78.015044 -167.577548) (xy 78.069405 -167.581428)
			(xy 78.122661 -167.593006) (xy 78.173726 -167.612045) (xy 78.221563 -167.638159) (xy 78.265195 -167.670814)
			(xy 78.303736 -167.709348) (xy 78.336401 -167.752974) (xy 78.362523 -167.800805) (xy 78.381573 -167.851867)
			(xy 78.393161 -167.90512) (xy 78.397052 -167.959481) (xy 79.67561 -167.959481) (xy 79.6795 -167.90513)
			(xy 79.691086 -167.851886) (xy 79.710132 -167.800833) (xy 79.73625 -167.75301) (xy 79.768908 -167.709392)
			(xy 79.807441 -167.670865) (xy 79.851065 -167.638214) (xy 79.898893 -167.612105) (xy 79.949949 -167.593068)
			(xy 80.003195 -167.581491) (xy 80.057546 -167.57761) (xy 80.111897 -167.581504) (xy 80.16514 -167.593094)
			(xy 80.216191 -167.612143) (xy 80.264012 -167.638264) (xy 80.286098 -167.654224) (xy 80.30511 -167.66782)
			(xy 80.346993 -167.688552) (xy 80.391961 -167.701278) (xy 80.438498 -167.705568) (xy 80.485035 -167.701278)
			(xy 80.530003 -167.688552) (xy 80.571886 -167.66782) (xy 80.590898 -167.654224) (xy 80.612956 -167.638221)
			(xy 80.660784 -167.612096) (xy 80.711843 -167.593043) (xy 80.765093 -167.581452) (xy 80.819452 -167.577557)
			(xy 80.873811 -167.581438) (xy 80.927065 -167.593016) (xy 80.978128 -167.612055) (xy 81.025962 -167.638168)
			(xy 81.069593 -167.670823) (xy 81.108132 -167.709356) (xy 81.140795 -167.752981) (xy 81.166917 -167.80081)
			(xy 81.185965 -167.851871) (xy 81.197553 -167.905122) (xy 81.201443 -167.959481) (xy 81.197558 -168.01384)
			(xy 81.185976 -168.067093) (xy 81.166933 -168.118155) (xy 81.140816 -168.165987) (xy 81.108157 -168.209615)
			(xy 81.069622 -168.248151) (xy 81.025995 -168.280811) (xy 80.978163 -168.306929) (xy 80.927101 -168.325973)
			(xy 80.873849 -168.337557) (xy 80.81949 -168.341443) (xy 80.765131 -168.337554) (xy 80.711879 -168.325968)
			(xy 80.660819 -168.30692) (xy 80.612989 -168.2808) (xy 80.590898 -168.26484) (xy 80.571886 -168.251244)
			(xy 80.530003 -168.230512) (xy 80.485035 -168.217786) (xy 80.438498 -168.213496) (xy 80.391961 -168.217786)
			(xy 80.346993 -168.230512) (xy 80.30511 -168.251244) (xy 80.286098 -168.26484) (xy 80.26398 -168.280757)
			(xy 80.216156 -168.306873) (xy 80.165103 -168.325917) (xy 80.111859 -168.337501) (xy 80.057508 -168.34139)
			(xy 80.003157 -168.337503) (xy 79.949912 -168.325921) (xy 79.898858 -168.306879) (xy 79.851033 -168.280765)
			(xy 79.807412 -168.24811) (xy 79.768882 -168.209579) (xy 79.736229 -168.165957) (xy 79.710116 -168.118132)
			(xy 79.691075 -168.067077) (xy 79.679495 -168.013832) (xy 79.67561 -167.959481) (xy 78.397052 -167.959481)
			(xy 78.393166 -168.013842) (xy 78.381584 -168.067096) (xy 78.362539 -168.11816) (xy 78.336421 -168.165994)
			(xy 78.303761 -168.209623) (xy 78.265224 -168.248161) (xy 78.221595 -168.280821) (xy 78.173761 -168.306939)
			(xy 78.122698 -168.325983) (xy 78.069443 -168.337566) (xy 78.015082 -168.341452) (xy 77.960722 -168.337561)
			(xy 77.907468 -168.325973) (xy 77.856406 -168.306924) (xy 77.808575 -168.280801) (xy 77.786484 -168.26484)
			(xy 77.767472 -168.251244) (xy 77.725589 -168.230512) (xy 77.680621 -168.217786) (xy 77.634084 -168.213496)
			(xy 77.587547 -168.217786) (xy 77.542579 -168.230512) (xy 77.500696 -168.251244) (xy 77.481684 -168.26484)
			(xy 77.459566 -168.280755) (xy 77.411744 -168.306869) (xy 77.360691 -168.325912) (xy 77.307449 -168.337494)
			(xy 77.2531 -168.341381) (xy 77.198751 -168.337494) (xy 77.145508 -168.325911) (xy 77.094456 -168.306869)
			(xy 77.046633 -168.280755) (xy 77.003014 -168.248101) (xy 76.964486 -168.209571) (xy 76.931834 -168.16595)
			(xy 76.905723 -168.118126) (xy 76.886683 -168.067073) (xy 76.875103 -168.01383) (xy 76.871219 -167.959481)
			(xy 71.339761 -167.959481) (xy 68.671443 -170.627799) (xy 76.871195 -170.627799) (xy 76.875082 -170.573446)
			(xy 76.886666 -170.5202) (xy 76.905709 -170.469145) (xy 76.931825 -170.42132) (xy 76.964482 -170.377698)
			(xy 77.003014 -170.339168) (xy 77.046638 -170.306514) (xy 77.094464 -170.2804) (xy 77.145521 -170.26136)
			(xy 77.198767 -170.249779) (xy 77.25312 -170.245895) (xy 77.307472 -170.249785) (xy 77.360718 -170.261371)
			(xy 77.411772 -170.280417) (xy 77.459596 -170.306535) (xy 77.481684 -170.322494) (xy 77.500696 -170.33609)
			(xy 77.542579 -170.356822) (xy 77.587547 -170.369548) (xy 77.634084 -170.373838) (xy 77.680621 -170.369548)
			(xy 77.725589 -170.356822) (xy 77.767472 -170.33609) (xy 77.786484 -170.322494) (xy 77.808571 -170.30653)
			(xy 77.856397 -170.280406) (xy 77.907455 -170.261356) (xy 77.960705 -170.249766) (xy 78.015062 -170.245872)
			(xy 78.069419 -170.249755) (xy 78.122671 -170.261334) (xy 78.173733 -170.280375) (xy 78.221565 -170.306489)
			(xy 78.265193 -170.339144) (xy 78.30373 -170.377677) (xy 78.33639 -170.421302) (xy 78.362509 -170.469131)
			(xy 78.381555 -170.520191) (xy 78.39314 -170.573441) (xy 78.397028 -170.627799) (xy 79.675586 -170.627799)
			(xy 79.679474 -170.573444) (xy 79.691058 -170.520197) (xy 79.710103 -170.46914) (xy 79.73622 -170.421313)
			(xy 79.768878 -170.37769) (xy 79.807412 -170.339158) (xy 79.851037 -170.306504) (xy 79.898866 -170.28039)
			(xy 79.949925 -170.26135) (xy 80.003173 -170.24977) (xy 80.057528 -170.245886) (xy 80.111882 -170.249778)
			(xy 80.165129 -170.261366) (xy 80.216185 -170.280414) (xy 80.26401 -170.306534) (xy 80.286098 -170.322494)
			(xy 80.30511 -170.33609) (xy 80.346993 -170.356822) (xy 80.391961 -170.369548) (xy 80.438498 -170.373838)
			(xy 80.485035 -170.369548) (xy 80.530003 -170.356822) (xy 80.571886 -170.33609) (xy 80.590898 -170.322494)
			(xy 80.612984 -170.306531) (xy 80.66081 -170.28041) (xy 80.711867 -170.261361) (xy 80.765115 -170.249773)
			(xy 80.81947 -170.245881) (xy 80.873825 -170.249764) (xy 80.927075 -170.261344) (xy 80.978135 -170.280385)
			(xy 81.025965 -170.306498) (xy 81.069591 -170.339153) (xy 81.108126 -170.377685) (xy 81.140785 -170.421309)
			(xy 81.166902 -170.469137) (xy 81.185947 -170.520195) (xy 81.197531 -170.573443) (xy 81.201419 -170.627799)
			(xy 81.197532 -170.682154) (xy 81.185948 -170.735403) (xy 81.166903 -170.786461) (xy 81.140786 -170.834289)
			(xy 81.108127 -170.877913) (xy 81.069593 -170.916445) (xy 81.025967 -170.9491) (xy 80.978137 -170.975214)
			(xy 80.927077 -170.994255) (xy 80.873828 -171.005836) (xy 80.819472 -171.009719) (xy 80.765117 -171.005828)
			(xy 80.711869 -170.99424) (xy 80.660812 -170.975191) (xy 80.612986 -170.94907) (xy 80.590898 -170.93311)
			(xy 80.571886 -170.919514) (xy 80.530003 -170.898782) (xy 80.485035 -170.886056) (xy 80.438498 -170.881766)
			(xy 80.391961 -170.886056) (xy 80.346993 -170.898782) (xy 80.30511 -170.919514) (xy 80.286098 -170.93311)
			(xy 80.264008 -170.949067) (xy 80.216183 -170.975187) (xy 80.165127 -170.994235) (xy 80.11188 -171.005822)
			(xy 80.057526 -171.009714) (xy 80.003171 -171.00583) (xy 79.949922 -170.994249) (xy 79.898864 -170.975209)
			(xy 79.851035 -170.949095) (xy 79.80741 -170.91644) (xy 79.768876 -170.877909) (xy 79.736218 -170.834285)
			(xy 79.710102 -170.786458) (xy 79.691058 -170.735401) (xy 79.679474 -170.682153) (xy 79.675586 -170.627799)
			(xy 78.397028 -170.627799) (xy 78.39314 -170.682156) (xy 78.381555 -170.735407) (xy 78.36251 -170.786467)
			(xy 78.336391 -170.834296) (xy 78.303731 -170.877921) (xy 78.265195 -170.916454) (xy 78.221567 -170.94911)
			(xy 78.173735 -170.975224) (xy 78.122673 -170.994265) (xy 78.069422 -171.005845) (xy 78.015064 -171.009728)
			(xy 77.960707 -171.005835) (xy 77.907458 -170.994245) (xy 77.8564 -170.975195) (xy 77.808573 -170.949071)
			(xy 77.786484 -170.93311) (xy 77.767472 -170.919514) (xy 77.725589 -170.898782) (xy 77.680621 -170.886056)
			(xy 77.634084 -170.881766) (xy 77.587547 -170.886056) (xy 77.542579 -170.898782) (xy 77.500696 -170.919514)
			(xy 77.481684 -170.93311) (xy 77.459594 -170.949066) (xy 77.41177 -170.975184) (xy 77.360715 -170.99423)
			(xy 77.30747 -171.005815) (xy 77.253118 -171.009705) (xy 77.198765 -171.00582) (xy 77.145519 -170.99424)
			(xy 77.094462 -170.975199) (xy 77.046636 -170.949085) (xy 77.003012 -170.916431) (xy 76.96448 -170.8779)
			(xy 76.931824 -170.834278) (xy 76.905708 -170.786453) (xy 76.886665 -170.735397) (xy 76.875082 -170.682151)
			(xy 76.871195 -170.627799) (xy 68.671443 -170.627799) (xy 66.299842 -172.9994) (xy 76.871193 -172.9994)
			(xy 76.875081 -172.945047) (xy 76.886664 -172.891801) (xy 76.905707 -172.840745) (xy 76.931823 -172.79292)
			(xy 76.96448 -172.749298) (xy 77.003012 -172.710767) (xy 77.046636 -172.678113) (xy 77.094463 -172.652)
			(xy 77.145519 -172.632959) (xy 77.198766 -172.621378) (xy 77.253119 -172.617493) (xy 77.307471 -172.621383)
			(xy 77.360717 -172.632969) (xy 77.411772 -172.652015) (xy 77.459596 -172.678133) (xy 77.481684 -172.694092)
			(xy 77.500696 -172.707688) (xy 77.542579 -172.72842) (xy 77.587547 -172.741146) (xy 77.634084 -172.745436)
			(xy 77.680621 -172.741146) (xy 77.725589 -172.72842) (xy 77.767472 -172.707688) (xy 77.786484 -172.694092)
			(xy 77.808573 -172.678131) (xy 77.856399 -172.652007) (xy 77.907457 -172.632957) (xy 77.960706 -172.621367)
			(xy 78.015063 -172.617474) (xy 78.06942 -172.621357) (xy 78.122672 -172.632936) (xy 78.173733 -172.651977)
			(xy 78.221565 -172.678091) (xy 78.265193 -172.710746) (xy 78.303729 -172.749279) (xy 78.336389 -172.792904)
			(xy 78.362508 -172.840733) (xy 78.381554 -172.891792) (xy 78.393138 -172.945043) (xy 78.397026 -172.9994)
			(xy 79.675585 -172.9994) (xy 79.679472 -172.945045) (xy 79.691056 -172.891797) (xy 79.710101 -172.84074)
			(xy 79.736218 -172.792913) (xy 79.768876 -172.749289) (xy 79.80741 -172.710758) (xy 79.851035 -172.678103)
			(xy 79.898864 -172.651989) (xy 79.949923 -172.632949) (xy 80.003172 -172.621369) (xy 80.057527 -172.617485)
			(xy 80.111881 -172.621376) (xy 80.165128 -172.632964) (xy 80.216185 -172.652012) (xy 80.26401 -172.678132)
			(xy 80.286098 -172.694092) (xy 80.30511 -172.707688) (xy 80.346993 -172.72842) (xy 80.391961 -172.741146)
			(xy 80.438498 -172.745436) (xy 80.485035 -172.741146) (xy 80.530003 -172.72842) (xy 80.571886 -172.707688)
			(xy 80.590898 -172.694092) (xy 80.612986 -172.678132) (xy 80.660812 -172.652011) (xy 80.711868 -172.632962)
			(xy 80.765116 -172.621374) (xy 80.819471 -172.617482) (xy 80.873826 -172.621366) (xy 80.927076 -172.632946)
			(xy 80.978135 -172.651987) (xy 81.025965 -172.6781) (xy 81.069591 -172.710755) (xy 81.108125 -172.749287)
			(xy 81.140784 -172.792911) (xy 81.166901 -172.840738) (xy 81.185946 -172.891796) (xy 81.19753 -172.945045)
			(xy 81.201418 -172.9994) (xy 81.19753 -173.053755) (xy 81.185946 -173.107004) (xy 81.166901 -173.158062)
			(xy 81.140784 -173.205889) (xy 81.108125 -173.249513) (xy 81.069591 -173.288045) (xy 81.025965 -173.3207)
			(xy 80.978135 -173.346813) (xy 80.927076 -173.365854) (xy 80.873826 -173.377434) (xy 80.819471 -173.381318)
			(xy 80.765116 -173.377426) (xy 80.711868 -173.365838) (xy 80.660812 -173.346789) (xy 80.612986 -173.320668)
			(xy 80.590898 -173.304708) (xy 80.571886 -173.291112) (xy 80.530003 -173.27038) (xy 80.485035 -173.257654)
			(xy 80.438498 -173.253364) (xy 80.391961 -173.257654) (xy 80.346993 -173.27038) (xy 80.30511 -173.291112)
			(xy 80.286098 -173.304708) (xy 80.26401 -173.320668) (xy 80.216185 -173.346788) (xy 80.165128 -173.365836)
			(xy 80.111881 -173.377424) (xy 80.057527 -173.381315) (xy 80.003172 -173.377431) (xy 79.949923 -173.365851)
			(xy 79.898864 -173.346811) (xy 79.851035 -173.320697) (xy 79.80741 -173.288042) (xy 79.768876 -173.249511)
			(xy 79.736218 -173.205887) (xy 79.710101 -173.15806) (xy 79.691056 -173.107003) (xy 79.679472 -173.053755)
			(xy 79.675585 -172.9994) (xy 78.397026 -172.9994) (xy 78.393138 -173.053757) (xy 78.381554 -173.107008)
			(xy 78.362508 -173.158067) (xy 78.336389 -173.205896) (xy 78.303729 -173.249521) (xy 78.265193 -173.288054)
			(xy 78.221565 -173.320709) (xy 78.173733 -173.346823) (xy 78.122672 -173.365864) (xy 78.06942 -173.377443)
			(xy 78.015063 -173.381326) (xy 77.960706 -173.377433) (xy 77.907457 -173.365843) (xy 77.856399 -173.346793)
			(xy 77.808573 -173.320669) (xy 77.786484 -173.304708) (xy 77.767472 -173.291112) (xy 77.725589 -173.27038)
			(xy 77.680621 -173.257654) (xy 77.634084 -173.253364) (xy 77.587547 -173.257654) (xy 77.542579 -173.27038)
			(xy 77.500696 -173.291112) (xy 77.481684 -173.304708) (xy 77.459596 -173.320667) (xy 77.411772 -173.346785)
			(xy 77.360717 -173.365831) (xy 77.307471 -173.377417) (xy 77.253119 -173.381307) (xy 77.198766 -173.377422)
			(xy 77.145519 -173.365841) (xy 77.094463 -173.3468) (xy 77.046636 -173.320687) (xy 77.003012 -173.288033)
			(xy 76.96448 -173.249502) (xy 76.931823 -173.20588) (xy 76.905707 -173.158055) (xy 76.886664 -173.106999)
			(xy 76.875081 -173.053753) (xy 76.871193 -172.9994) (xy 66.299842 -172.9994) (xy 64.336949 -174.962293)
			(xy 76.871203 -174.962293) (xy 76.875091 -174.907942) (xy 76.886675 -174.854697) (xy 76.905719 -174.803643)
			(xy 76.931835 -174.755819) (xy 76.964492 -174.712198) (xy 77.003024 -174.67367) (xy 77.046647 -174.641017)
			(xy 77.094473 -174.614905) (xy 77.145529 -174.595866) (xy 77.198775 -174.584286) (xy 77.253126 -174.580403)
			(xy 77.307477 -174.584294) (xy 77.360721 -174.595881) (xy 77.411774 -174.614927) (xy 77.459597 -174.641045)
			(xy 77.481684 -174.657004) (xy 77.500696 -174.6706) (xy 77.542579 -174.691332) (xy 77.587547 -174.704058)
			(xy 77.634084 -174.708348) (xy 77.680621 -174.704058) (xy 77.725589 -174.691332) (xy 77.767472 -174.6706)
			(xy 77.786484 -174.657004) (xy 77.808561 -174.641027) (xy 77.856389 -174.614902) (xy 77.907447 -174.59585)
			(xy 77.960698 -174.584259) (xy 78.015056 -174.580364) (xy 78.069415 -174.584246) (xy 78.122668 -174.595825)
			(xy 78.173731 -174.614865) (xy 78.221564 -174.640979) (xy 78.265194 -174.673634) (xy 78.303732 -174.712167)
			(xy 78.336394 -174.755793) (xy 78.362514 -174.803622) (xy 78.381561 -174.854683) (xy 78.393147 -174.907934)
			(xy 78.397036 -174.962293) (xy 79.675594 -174.962293) (xy 79.679483 -174.90794) (xy 79.691068 -174.854693)
			(xy 79.710112 -174.803637) (xy 79.73623 -174.755812) (xy 79.768888 -174.71219) (xy 79.807421 -174.673661)
			(xy 79.851047 -174.641007) (xy 79.898875 -174.614895) (xy 79.949933 -174.595856) (xy 80.00318 -174.584277)
			(xy 80.057534 -174.580394) (xy 80.111887 -174.584287) (xy 80.165133 -174.595875) (xy 80.216187 -174.614924)
			(xy 80.264011 -174.641044) (xy 80.286098 -174.657004) (xy 80.30511 -174.6706) (xy 80.346993 -174.691332)
			(xy 80.391961 -174.704058) (xy 80.438498 -174.708348) (xy 80.485035 -174.704058) (xy 80.530003 -174.691332)
			(xy 80.571886 -174.6706) (xy 80.590898 -174.657004) (xy 80.612975 -174.641028) (xy 80.660801 -174.614905)
			(xy 80.711859 -174.595855) (xy 80.765107 -174.584266) (xy 80.819464 -174.580373) (xy 80.873821 -174.584255)
			(xy 80.927072 -174.595835) (xy 80.978132 -174.614875) (xy 81.025964 -174.640988) (xy 81.069592 -174.673643)
			(xy 81.108128 -174.712175) (xy 81.140788 -174.7558) (xy 81.166907 -174.803628) (xy 81.185953 -174.854687)
			(xy 81.197538 -174.907936) (xy 81.201427 -174.962293) (xy 81.197541 -175.016649) (xy 81.185957 -175.0699)
			(xy 81.166913 -175.120959) (xy 81.140796 -175.168788) (xy 81.108137 -175.212414) (xy 81.069603 -175.250947)
			(xy 81.025976 -175.283604) (xy 80.978146 -175.309719) (xy 80.927085 -175.328761) (xy 80.873835 -175.340343)
			(xy 80.819478 -175.344227) (xy 80.765122 -175.340336) (xy 80.711872 -175.328749) (xy 80.660814 -175.309701)
			(xy 80.612987 -175.28358) (xy 80.590898 -175.26762) (xy 80.571886 -175.254024) (xy 80.530003 -175.233292)
			(xy 80.485035 -175.220566) (xy 80.438498 -175.216276) (xy 80.391961 -175.220566) (xy 80.346993 -175.233292)
			(xy 80.30511 -175.254024) (xy 80.286098 -175.26762) (xy 80.263999 -175.283564) (xy 80.216174 -175.309682)
			(xy 80.165119 -175.328729) (xy 80.111873 -175.340315) (xy 80.05752 -175.344206) (xy 80.003166 -175.340321)
			(xy 79.949919 -175.32874) (xy 79.898862 -175.309699) (xy 79.851035 -175.283585) (xy 79.807411 -175.25093)
			(xy 79.768878 -175.212399) (xy 79.736222 -175.168776) (xy 79.710106 -175.120949) (xy 79.691063 -175.069893)
			(xy 79.679481 -175.016646) (xy 79.675594 -174.962293) (xy 78.397036 -174.962293) (xy 78.393149 -175.016651)
			(xy 78.381565 -175.069903) (xy 78.36252 -175.120964) (xy 78.336401 -175.168795) (xy 78.303741 -175.212422)
			(xy 78.265205 -175.250956) (xy 78.221576 -175.283614) (xy 78.173744 -175.309729) (xy 78.122681 -175.328771)
			(xy 78.069429 -175.340352) (xy 78.01507 -175.344236) (xy 77.960712 -175.340343) (xy 77.907461 -175.328754)
			(xy 77.856402 -175.309704) (xy 77.808573 -175.283581) (xy 77.786484 -175.26762) (xy 77.767472 -175.254024)
			(xy 77.725589 -175.233292) (xy 77.680621 -175.220566) (xy 77.634084 -175.216276) (xy 77.587547 -175.220566)
			(xy 77.542579 -175.233292) (xy 77.500696 -175.254024) (xy 77.481684 -175.26762) (xy 77.459585 -175.283562)
			(xy 77.411761 -175.309679) (xy 77.360707 -175.328724) (xy 77.307463 -175.340308) (xy 77.253112 -175.344197)
			(xy 77.19876 -175.340312) (xy 77.145515 -175.32873) (xy 77.09446 -175.309689) (xy 77.046635 -175.283575)
			(xy 77.003013 -175.250921) (xy 76.964482 -175.212391) (xy 76.931827 -175.168769) (xy 76.905713 -175.120944)
			(xy 76.886671 -175.069889) (xy 76.875089 -175.016644) (xy 76.871203 -174.962293) (xy 64.336949 -174.962293)
			(xy 62.193453 -177.105789) (xy 76.871207 -177.105789) (xy 76.875096 -177.051439) (xy 76.886681 -176.998195)
			(xy 76.905725 -176.947142) (xy 76.931841 -176.899318) (xy 76.964498 -176.855699) (xy 77.00303 -176.817171)
			(xy 77.046653 -176.784519) (xy 77.094478 -176.758408) (xy 77.145534 -176.739369) (xy 77.198779 -176.727791)
			(xy 77.25313 -176.723907) (xy 77.30748 -176.727799) (xy 77.360723 -176.739386) (xy 77.411776 -176.758433)
			(xy 77.459597 -176.784551) (xy 77.481684 -176.80051) (xy 77.500696 -176.814106) (xy 77.542579 -176.834838)
			(xy 77.587547 -176.847564) (xy 77.634084 -176.851854) (xy 77.680621 -176.847564) (xy 77.725589 -176.834838)
			(xy 77.767472 -176.814106) (xy 77.786484 -176.80051) (xy 77.808556 -176.784524) (xy 77.856383 -176.758399)
			(xy 77.907442 -176.739346) (xy 77.960693 -176.727754) (xy 78.015052 -176.723859) (xy 78.069412 -176.727741)
			(xy 78.122666 -176.739319) (xy 78.173729 -176.758359) (xy 78.221564 -176.784473) (xy 78.265194 -176.817128)
			(xy 78.303733 -176.855661) (xy 78.336396 -176.899287) (xy 78.362517 -176.947117) (xy 78.381564 -176.998178)
			(xy 78.393151 -177.05143) (xy 78.397041 -177.105789) (xy 79.675599 -177.105789) (xy 79.679488 -177.051437)
			(xy 79.691073 -176.998191) (xy 79.710118 -176.947136) (xy 79.736236 -176.899311) (xy 79.768894 -176.855691)
			(xy 79.807427 -176.817162) (xy 79.851052 -176.784509) (xy 79.89888 -176.758398) (xy 79.949938 -176.73936)
			(xy 80.003185 -176.727781) (xy 80.057538 -176.723899) (xy 80.11189 -176.727792) (xy 80.165135 -176.739381)
			(xy 80.216188 -176.758429) (xy 80.264011 -176.78455) (xy 80.286098 -176.80051) (xy 80.30511 -176.814106)
			(xy 80.346993 -176.834838) (xy 80.391961 -176.847564) (xy 80.438498 -176.851854) (xy 80.485035 -176.847564)
			(xy 80.530003 -176.834838) (xy 80.571886 -176.814106) (xy 80.590898 -176.80051) (xy 80.612969 -176.784526)
			(xy 80.660796 -176.758402) (xy 80.711854 -176.739352) (xy 80.765103 -176.727761) (xy 80.81946 -176.723868)
			(xy 80.873818 -176.72775) (xy 80.927069 -176.739329) (xy 80.978131 -176.758369) (xy 81.025963 -176.784482)
			(xy 81.069592 -176.817137) (xy 81.108129 -176.855669) (xy 81.14079 -176.899294) (xy 81.16691 -176.947123)
			(xy 81.185957 -176.998182) (xy 81.197543 -177.051432) (xy 81.201432 -177.105789) (xy 81.197546 -177.160147)
			(xy 81.185963 -177.213397) (xy 81.166919 -177.264458) (xy 81.140802 -177.312288) (xy 81.108143 -177.355914)
			(xy 81.069608 -177.394448) (xy 81.025982 -177.427106) (xy 80.978151 -177.453222) (xy 80.92709 -177.472265)
			(xy 80.873839 -177.483847) (xy 80.819482 -177.487732) (xy 80.765125 -177.483842) (xy 80.711875 -177.472255)
			(xy 80.660816 -177.453207) (xy 80.612988 -177.427086) (xy 80.590898 -177.411126) (xy 80.571886 -177.39753)
			(xy 80.530003 -177.376798) (xy 80.485035 -177.364072) (xy 80.438498 -177.359782) (xy 80.391961 -177.364072)
			(xy 80.346993 -177.376798) (xy 80.30511 -177.39753) (xy 80.286098 -177.411126) (xy 80.263993 -177.427061)
			(xy 80.216169 -177.45318) (xy 80.165114 -177.472225) (xy 80.111869 -177.483811) (xy 80.057516 -177.487701)
			(xy 80.003163 -177.483816) (xy 79.949917 -177.472234) (xy 79.898861 -177.453193) (xy 79.851034 -177.427079)
			(xy 79.807411 -177.394424) (xy 79.768879 -177.355893) (xy 79.736224 -177.31227) (xy 79.710109 -177.264444)
			(xy 79.691067 -177.213388) (xy 79.679485 -177.160142) (xy 79.675599 -177.105789) (xy 78.397041 -177.105789)
			(xy 78.393154 -177.160148) (xy 78.38157 -177.213401) (xy 78.362526 -177.264463) (xy 78.336407 -177.312295)
			(xy 78.303747 -177.355922) (xy 78.265211 -177.394458) (xy 78.221582 -177.427116) (xy 78.173749 -177.453232)
			(xy 78.122686 -177.472275) (xy 78.069433 -177.483856) (xy 78.015074 -177.487741) (xy 77.960715 -177.483849)
			(xy 77.907463 -177.47226) (xy 77.856403 -177.45321) (xy 77.808574 -177.427087) (xy 77.786484 -177.411126)
			(xy 77.767472 -177.39753) (xy 77.725589 -177.376798) (xy 77.680621 -177.364072) (xy 77.634084 -177.359782)
			(xy 77.587547 -177.364072) (xy 77.542579 -177.376798) (xy 77.500696 -177.39753) (xy 77.481684 -177.411126)
			(xy 77.459579 -177.42706) (xy 77.411756 -177.453176) (xy 77.360703 -177.47222) (xy 77.307459 -177.483804)
			(xy 77.253108 -177.487693) (xy 77.198757 -177.483806) (xy 77.145513 -177.472225) (xy 77.094459 -177.453183)
			(xy 77.046634 -177.427069) (xy 77.003013 -177.394415) (xy 76.964483 -177.355885) (xy 76.931829 -177.312263)
			(xy 76.905716 -177.264439) (xy 76.886675 -177.213384) (xy 76.875093 -177.16014) (xy 76.871207 -177.105789)
			(xy 62.193453 -177.105789) (xy 61.730636 -177.568606) (xy 61.730636 -178.827684) (xy 62.19698 -179.294028)
			(xy 84.305648 -179.294028) (xy 84.319278 -179.29237) (xy 84.345423 -179.284003) (xy 84.36918 -179.270248)
			(xy 84.379562 -179.261262) (xy 90.19032 -173.450504) (xy 90.19921 -173.419008) (xy 90.20547 -173.39836)
			(xy 90.222023 -173.358515) (xy 90.23223 -173.339506) (xy 90.248232 -173.310804) (xy 90.248232 -171.705778)
			(xy 90.23223 -171.677076) (xy 90.219414 -171.652944) (xy 90.200054 -171.601847) (xy 90.188184 -171.548511)
			(xy 90.184046 -171.494027) (xy 90.187725 -171.43951) (xy 90.199145 -171.386076) (xy 90.218073 -171.334818)
			(xy 90.244122 -171.286786) (xy 90.276758 -171.242962) (xy 90.315314 -171.204244) (xy 90.359 -171.171423)
			(xy 90.406922 -171.145172) (xy 90.458099 -171.126028) (xy 90.511485 -171.114383) (xy 90.565986 -171.110474)
			(xy 90.620487 -171.114383) (xy 90.673873 -171.126028) (xy 90.72505 -171.145172) (xy 90.772972 -171.171423)
			(xy 90.816658 -171.204244) (xy 90.855214 -171.242962) (xy 90.88785 -171.286786) (xy 90.913899 -171.334818)
			(xy 90.932827 -171.386076) (xy 90.944247 -171.43951) (xy 90.947926 -171.494027) (xy 90.943788 -171.548511)
			(xy 90.931918 -171.601847) (xy 90.912558 -171.652944) (xy 90.899742 -171.677076) (xy 90.88374 -171.705778)
			(xy 90.88374 -173.310804) (xy 90.899742 -173.339506) (xy 90.913145 -173.364756) (xy 90.933072 -173.418334)
			(xy 90.944785 -173.474284) (xy 90.948021 -173.531356) (xy 90.94271 -173.588272) (xy 90.928968 -173.64376)
			(xy 90.907104 -173.696577) (xy 90.877607 -173.745542) (xy 90.841137 -173.78956) (xy 90.798509 -173.827646)
			(xy 90.750678 -173.858948) (xy 90.698712 -173.882766) (xy 90.671396 -173.891194) (xy 90.6399 -173.900084)
			(xy 84.610194 -179.929536) (xy 31.552896 -179.929536) (xy 31.538148 -179.931298) (xy 31.510015 -179.940802)
			(xy 31.484854 -179.95657) (xy 31.474156 -179.966874) (xy 31.099506 -180.341524) (xy 31.084004 -180.357698)
			(xy 31.058376 -180.394437) (xy 31.039586 -180.435101) (xy 31.028218 -180.47843) (xy 31.024623 -180.523081)
			(xy 31.028912 -180.56767) (xy 31.040954 -180.610817) (xy 31.060374 -180.651184) (xy 31.086572 -180.68752)
			(xy 31.1023 -180.703474) (xy 31.136256 -180.736037) (xy 31.198186 -180.806868) (xy 31.25273 -180.883531)
			(xy 31.299342 -180.96526) (xy 31.318962 -181.00802) (xy 31.335718 -181.046854) (xy 31.362996 -181.126919)
			(xy 31.382974 -181.209111) (xy 31.39549 -181.292764) (xy 31.400444 -181.377203) (xy 31.398681 -181.433486)
			(xy 34.599874 -181.433486) (xy 34.599874 -181.346586) (xy 34.607892 -181.260057) (xy 34.62386 -181.174637)
			(xy 34.647641 -181.091055) (xy 34.679033 -181.010023) (xy 34.717767 -180.932234) (xy 34.763514 -180.85835)
			(xy 34.815883 -180.789003) (xy 34.874427 -180.724783) (xy 34.938647 -180.666239) (xy 35.007994 -180.61387)
			(xy 35.081878 -180.568123) (xy 35.159667 -180.529389) (xy 35.240699 -180.497997) (xy 35.324281 -180.474216)
			(xy 35.409701 -180.458248) (xy 35.49623 -180.45023) (xy 35.58313 -180.45023) (xy 35.669659 -180.458248)
			(xy 35.755079 -180.474216) (xy 35.838661 -180.497997) (xy 35.919693 -180.529389) (xy 35.997482 -180.568123)
			(xy 36.071366 -180.61387) (xy 36.140713 -180.666239) (xy 36.204933 -180.724783) (xy 36.263477 -180.789003)
			(xy 36.315846 -180.85835) (xy 36.361593 -180.932234) (xy 36.400327 -181.010023) (xy 36.431719 -181.091055)
			(xy 36.4555 -181.174637) (xy 36.471468 -181.260057) (xy 36.479486 -181.346586) (xy 36.479988 -181.390036)
			(xy 36.479486 -181.433486) (xy 36.471468 -181.520015) (xy 36.4555 -181.605435) (xy 36.431719 -181.689017)
			(xy 36.400327 -181.770049) (xy 36.361593 -181.847838) (xy 36.315846 -181.921722) (xy 36.263477 -181.991069)
			(xy 36.204933 -182.055289) (xy 36.140713 -182.113833) (xy 36.071366 -182.166202) (xy 35.997482 -182.211949)
			(xy 35.919693 -182.250683) (xy 35.838661 -182.282075) (xy 35.755079 -182.305856) (xy 35.669659 -182.321824)
			(xy 35.58313 -182.329842) (xy 35.49623 -182.329842) (xy 35.409701 -182.321824) (xy 35.324281 -182.305856)
			(xy 35.240699 -182.282075) (xy 35.159667 -182.250683) (xy 35.081878 -182.211949) (xy 35.007994 -182.166202)
			(xy 34.938647 -182.113833) (xy 34.874427 -182.055289) (xy 34.815883 -181.991069) (xy 34.763514 -181.921722)
			(xy 34.717767 -181.847838) (xy 34.679033 -181.770049) (xy 34.647641 -181.689017) (xy 34.62386 -181.605435)
			(xy 34.607892 -181.520015) (xy 34.599874 -181.433486) (xy 31.398681 -181.433486) (xy 31.397796 -181.461746)
			(xy 31.387566 -181.54571) (xy 31.369838 -181.628416) (xy 31.344754 -181.709195) (xy 31.312518 -181.787396)
			(xy 31.27339 -181.862386) (xy 31.227686 -181.93356) (xy 31.175775 -182.000342) (xy 31.118077 -182.062192)
			(xy 31.055058 -182.118612) (xy 30.987227 -182.169144) (xy 30.951424 -182.19166) (xy 30.914189 -182.21392)
			(xy 30.836374 -182.252285) (xy 30.755357 -182.283319) (xy 30.671825 -182.306758) (xy 30.586489 -182.322401)
			(xy 30.500075 -182.330117) (xy 30.413318 -182.32984) (xy 30.326954 -182.321572) (xy 30.24172 -182.305383)
			(xy 30.15834 -182.281411) (xy 30.077522 -182.24986) (xy 29.999955 -182.210998) (xy 29.926298 -182.165156)
			(xy 29.857176 -182.112723) (xy 29.793179 -182.054146) (xy 29.73485 -181.989923) (xy 29.682685 -181.920599)
			(xy 29.637128 -181.846764) (xy 29.617416 -181.80812) (xy 29.597513 -181.766819) (xy 29.564911 -181.681125)
			(xy 29.540813 -181.592663) (xy 29.525446 -181.502274) (xy 29.521658 -181.456584) (xy 29.520602 -181.440476)
			(xy 29.51946 -181.408211) (xy 29.519372 -181.392068) (xy 29.518825 -181.369056) (xy 29.510441 -181.3238)
			(xy 29.494044 -181.280793) (xy 29.470169 -181.241443) (xy 29.439598 -181.207037) (xy 29.40333 -181.178698)
			(xy 29.362552 -181.157355) (xy 29.318596 -181.143705) (xy 29.272901 -181.138194) (xy 29.22696 -181.141003)
			(xy 29.182277 -181.15204) (xy 29.140312 -181.170943) (xy 29.102437 -181.197096) (xy 29.085794 -181.212998)
			(xy 28.090876 -182.207916) (xy 28.090876 -183.973486) (xy 29.519874 -183.973486) (xy 29.519874 -183.886586)
			(xy 29.527892 -183.800057) (xy 29.54386 -183.714637) (xy 29.567641 -183.631055) (xy 29.599033 -183.550023)
			(xy 29.637767 -183.472234) (xy 29.683514 -183.39835) (xy 29.735883 -183.329003) (xy 29.794427 -183.264783)
			(xy 29.858647 -183.206239) (xy 29.927994 -183.15387) (xy 30.001878 -183.108123) (xy 30.079667 -183.069389)
			(xy 30.160699 -183.037997) (xy 30.244281 -183.014216) (xy 30.329701 -182.998248) (xy 30.41623 -182.99023)
			(xy 30.50313 -182.99023) (xy 30.589659 -182.998248) (xy 30.675079 -183.014216) (xy 30.758661 -183.037997)
			(xy 30.839693 -183.069389) (xy 30.917482 -183.108123) (xy 30.991366 -183.15387) (xy 31.060713 -183.206239)
			(xy 31.124933 -183.264783) (xy 31.183477 -183.329003) (xy 31.235846 -183.39835) (xy 31.281593 -183.472234)
			(xy 31.320327 -183.550023) (xy 31.351719 -183.631055) (xy 31.3755 -183.714637) (xy 31.391468 -183.800057)
			(xy 31.399486 -183.886586) (xy 31.399988 -183.930036) (xy 31.399486 -183.973486) (xy 34.599874 -183.973486)
			(xy 34.599874 -183.886586) (xy 34.607892 -183.800057) (xy 34.62386 -183.714637) (xy 34.647641 -183.631055)
			(xy 34.679033 -183.550023) (xy 34.717767 -183.472234) (xy 34.763514 -183.39835) (xy 34.815883 -183.329003)
			(xy 34.874427 -183.264783) (xy 34.938647 -183.206239) (xy 35.007994 -183.15387) (xy 35.081878 -183.108123)
			(xy 35.159667 -183.069389) (xy 35.240699 -183.037997) (xy 35.324281 -183.014216) (xy 35.409701 -182.998248)
			(xy 35.49623 -182.99023) (xy 35.58313 -182.99023) (xy 35.669659 -182.998248) (xy 35.755079 -183.014216)
			(xy 35.838661 -183.037997) (xy 35.919693 -183.069389) (xy 35.997482 -183.108123) (xy 36.071366 -183.15387)
			(xy 36.140713 -183.206239) (xy 36.204933 -183.264783) (xy 36.263477 -183.329003) (xy 36.315846 -183.39835)
			(xy 36.361593 -183.472234) (xy 36.400327 -183.550023) (xy 36.431719 -183.631055) (xy 36.4555 -183.714637)
			(xy 36.471468 -183.800057) (xy 36.479486 -183.886586) (xy 36.479988 -183.930036) (xy 36.479486 -183.973486)
			(xy 36.471468 -184.060015) (xy 36.4555 -184.145435) (xy 36.431719 -184.229017) (xy 36.400327 -184.310049)
			(xy 36.361593 -184.387838) (xy 36.315846 -184.461722) (xy 36.263477 -184.531069) (xy 36.204933 -184.595289)
			(xy 36.140713 -184.653833) (xy 36.07398 -184.704228) (xy 39.818818 -184.704228) (xy 39.819523 -184.645605)
			(xy 39.828091 -184.528667) (xy 39.844787 -184.412611) (xy 39.86953 -184.298001) (xy 39.902199 -184.185393)
			(xy 39.942635 -184.075335) (xy 39.990642 -183.968363) (xy 40.045986 -183.864996) (xy 40.108399 -183.765737)
			(xy 40.177577 -183.671068) (xy 40.253183 -183.58145) (xy 40.334851 -183.497318) (xy 40.422182 -183.419081)
			(xy 40.514753 -183.34712) (xy 40.612113 -183.281784) (xy 40.713789 -183.223392) (xy 40.819288 -183.172226)
			(xy 40.928095 -183.128537) (xy 41.039682 -183.092535) (xy 41.153506 -183.064397) (xy 41.269014 -183.044259)
			(xy 41.385645 -183.032218) (xy 41.502832 -183.028334) (xy 41.620004 -183.032625) (xy 41.736593 -183.045071)
			(xy 41.85203 -183.065611) (xy 41.965756 -183.094144) (xy 42.077217 -183.130533) (xy 42.185872 -183.174601)
			(xy 42.291192 -183.226133) (xy 42.392665 -183.284878) (xy 42.489797 -183.350552) (xy 42.501941 -183.36006)
			(xy 63.647831 -183.36006) (xy 63.651866 -183.284356) (xy 63.663925 -183.209511) (xy 63.683871 -183.13637)
			(xy 63.711478 -183.065765) (xy 63.746434 -182.998494) (xy 63.788342 -182.935319) (xy 63.836728 -182.876957)
			(xy 63.891044 -182.824069) (xy 63.950673 -182.777254) (xy 64.014941 -182.737042) (xy 64.083118 -182.70389)
			(xy 64.154434 -182.678172) (xy 64.228079 -182.66018) (xy 64.303219 -182.650118) (xy 64.379003 -182.648099)
			(xy 64.454573 -182.654148) (xy 64.529071 -182.668195) (xy 64.601654 -182.690081) (xy 64.6715 -182.719558)
			(xy 64.737817 -182.756293) (xy 64.799853 -182.799868) (xy 64.856906 -182.84979) (xy 64.90833 -182.905494)
			(xy 64.953541 -182.966349) (xy 64.992028 -183.031664) (xy 65.023354 -183.1007) (xy 65.047164 -183.172675)
			(xy 65.063189 -183.246773) (xy 65.071248 -183.322154) (xy 65.071752 -183.36006) (xy 66.187831 -183.36006)
			(xy 66.191866 -183.284356) (xy 66.203925 -183.209511) (xy 66.223871 -183.13637) (xy 66.251478 -183.065765)
			(xy 66.286434 -182.998494) (xy 66.328342 -182.935319) (xy 66.376728 -182.876957) (xy 66.431044 -182.824069)
			(xy 66.490673 -182.777254) (xy 66.554941 -182.737042) (xy 66.623118 -182.70389) (xy 66.694434 -182.678172)
			(xy 66.768079 -182.66018) (xy 66.843219 -182.650118) (xy 66.919003 -182.648099) (xy 66.994573 -182.654148)
			(xy 67.069071 -182.668195) (xy 67.141654 -182.690081) (xy 67.2115 -182.719558) (xy 67.277817 -182.756293)
			(xy 67.339853 -182.799868) (xy 67.396906 -182.84979) (xy 67.44833 -182.905494) (xy 67.493541 -182.966349)
			(xy 67.532028 -183.031664) (xy 67.563354 -183.1007) (xy 67.587164 -183.172675) (xy 67.603189 -183.246773)
			(xy 67.611248 -183.322154) (xy 67.611752 -183.36006) (xy 68.727831 -183.36006) (xy 68.731866 -183.284356)
			(xy 68.743925 -183.209511) (xy 68.763871 -183.13637) (xy 68.791478 -183.065765) (xy 68.826434 -182.998494)
			(xy 68.868342 -182.935319) (xy 68.916728 -182.876957) (xy 68.971044 -182.824069) (xy 69.030673 -182.777254)
			(xy 69.094941 -182.737042) (xy 69.163118 -182.70389) (xy 69.234434 -182.678172) (xy 69.308079 -182.66018)
			(xy 69.383219 -182.650118) (xy 69.459003 -182.648099) (xy 69.534573 -182.654148) (xy 69.609071 -182.668195)
			(xy 69.681654 -182.690081) (xy 69.7515 -182.719558) (xy 69.817817 -182.756293) (xy 69.879853 -182.799868)
			(xy 69.936906 -182.84979) (xy 69.98833 -182.905494) (xy 70.033541 -182.966349) (xy 70.072028 -183.031664)
			(xy 70.103354 -183.1007) (xy 70.127164 -183.172675) (xy 70.143189 -183.246773) (xy 70.151248 -183.322154)
			(xy 70.151752 -183.36006) (xy 71.267831 -183.36006) (xy 71.271866 -183.284356) (xy 71.283925 -183.209511)
			(xy 71.303871 -183.13637) (xy 71.331478 -183.065765) (xy 71.366434 -182.998494) (xy 71.408342 -182.935319)
			(xy 71.456728 -182.876957) (xy 71.511044 -182.824069) (xy 71.570673 -182.777254) (xy 71.634941 -182.737042)
			(xy 71.703118 -182.70389) (xy 71.774434 -182.678172) (xy 71.848079 -182.66018) (xy 71.923219 -182.650118)
			(xy 71.999003 -182.648099) (xy 72.074573 -182.654148) (xy 72.149071 -182.668195) (xy 72.221654 -182.690081)
			(xy 72.2915 -182.719558) (xy 72.357817 -182.756293) (xy 72.419853 -182.799868) (xy 72.476906 -182.84979)
			(xy 72.52833 -182.905494) (xy 72.573541 -182.966349) (xy 72.612028 -183.031664) (xy 72.643354 -183.1007)
			(xy 72.667164 -183.172675) (xy 72.683189 -183.246773) (xy 72.691248 -183.322154) (xy 72.691752 -183.36006)
			(xy 73.807831 -183.36006) (xy 73.811866 -183.284356) (xy 73.823925 -183.209511) (xy 73.843871 -183.13637)
			(xy 73.871478 -183.065765) (xy 73.906434 -182.998494) (xy 73.948342 -182.935319) (xy 73.996728 -182.876957)
			(xy 74.051044 -182.824069) (xy 74.110673 -182.777254) (xy 74.174941 -182.737042) (xy 74.243118 -182.70389)
			(xy 74.314434 -182.678172) (xy 74.388079 -182.66018) (xy 74.463219 -182.650118) (xy 74.539003 -182.648099)
			(xy 74.614573 -182.654148) (xy 74.689071 -182.668195) (xy 74.761654 -182.690081) (xy 74.8315 -182.719558)
			(xy 74.897817 -182.756293) (xy 74.959853 -182.799868) (xy 75.016906 -182.84979) (xy 75.06833 -182.905494)
			(xy 75.113541 -182.966349) (xy 75.152028 -183.031664) (xy 75.183354 -183.1007) (xy 75.207164 -183.172675)
			(xy 75.223189 -183.246773) (xy 75.231248 -183.322154) (xy 75.231752 -183.36006) (xy 76.347831 -183.36006)
			(xy 76.351866 -183.284356) (xy 76.363925 -183.209511) (xy 76.383871 -183.13637) (xy 76.411478 -183.065765)
			(xy 76.446434 -182.998494) (xy 76.488342 -182.935319) (xy 76.536728 -182.876957) (xy 76.591044 -182.824069)
			(xy 76.650673 -182.777254) (xy 76.714941 -182.737042) (xy 76.783118 -182.70389) (xy 76.854434 -182.678172)
			(xy 76.928079 -182.66018) (xy 77.003219 -182.650118) (xy 77.079003 -182.648099) (xy 77.154573 -182.654148)
			(xy 77.229071 -182.668195) (xy 77.301654 -182.690081) (xy 77.3715 -182.719558) (xy 77.437817 -182.756293)
			(xy 77.499853 -182.799868) (xy 77.556906 -182.84979) (xy 77.60833 -182.905494) (xy 77.653541 -182.966349)
			(xy 77.692028 -183.031664) (xy 77.723354 -183.1007) (xy 77.747164 -183.172675) (xy 77.763189 -183.246773)
			(xy 77.771248 -183.322154) (xy 77.771752 -183.36006) (xy 78.887831 -183.36006) (xy 78.891866 -183.284356)
			(xy 78.903925 -183.209511) (xy 78.923871 -183.13637) (xy 78.951478 -183.065765) (xy 78.986434 -182.998494)
			(xy 79.028342 -182.935319) (xy 79.076728 -182.876957) (xy 79.131044 -182.824069) (xy 79.190673 -182.777254)
			(xy 79.254941 -182.737042) (xy 79.323118 -182.70389) (xy 79.394434 -182.678172) (xy 79.468079 -182.66018)
			(xy 79.543219 -182.650118) (xy 79.619003 -182.648099) (xy 79.694573 -182.654148) (xy 79.769071 -182.668195)
			(xy 79.841654 -182.690081) (xy 79.9115 -182.719558) (xy 79.977817 -182.756293) (xy 80.039853 -182.799868)
			(xy 80.096906 -182.84979) (xy 80.14833 -182.905494) (xy 80.193541 -182.966349) (xy 80.232028 -183.031664)
			(xy 80.263354 -183.1007) (xy 80.287164 -183.172675) (xy 80.303189 -183.246773) (xy 80.311248 -183.322154)
			(xy 80.311752 -183.36006) (xy 81.427831 -183.36006) (xy 81.431866 -183.284356) (xy 81.443925 -183.209511)
			(xy 81.463871 -183.13637) (xy 81.491478 -183.065765) (xy 81.526434 -182.998494) (xy 81.568342 -182.935319)
			(xy 81.616728 -182.876957) (xy 81.671044 -182.824069) (xy 81.730673 -182.777254) (xy 81.794941 -182.737042)
			(xy 81.863118 -182.70389) (xy 81.934434 -182.678172) (xy 82.008079 -182.66018) (xy 82.083219 -182.650118)
			(xy 82.159003 -182.648099) (xy 82.234573 -182.654148) (xy 82.309071 -182.668195) (xy 82.381654 -182.690081)
			(xy 82.4515 -182.719558) (xy 82.517817 -182.756293) (xy 82.579853 -182.799868) (xy 82.585798 -182.80507)
			(xy 86.197951 -182.80507) (xy 86.201986 -182.729366) (xy 86.214045 -182.654521) (xy 86.233991 -182.58138)
			(xy 86.261598 -182.510775) (xy 86.296554 -182.443504) (xy 86.338462 -182.380329) (xy 86.386848 -182.321967)
			(xy 86.441164 -182.269079) (xy 86.500793 -182.222264) (xy 86.565061 -182.182052) (xy 86.633238 -182.1489)
			(xy 86.704554 -182.123182) (xy 86.778199 -182.10519) (xy 86.853339 -182.095128) (xy 86.929123 -182.093109)
			(xy 87.004693 -182.099158) (xy 87.079191 -182.113205) (xy 87.151774 -182.135091) (xy 87.22162 -182.164568)
			(xy 87.287937 -182.201303) (xy 87.349973 -182.244878) (xy 87.407026 -182.2948) (xy 87.45845 -182.350504)
			(xy 87.503661 -182.411359) (xy 87.542148 -182.476674) (xy 87.573474 -182.54571) (xy 87.597284 -182.617685)
			(xy 87.613309 -182.691783) (xy 87.621368 -182.767164) (xy 87.621872 -182.80507) (xy 88.737951 -182.80507)
			(xy 88.741986 -182.729366) (xy 88.754045 -182.654521) (xy 88.773991 -182.58138) (xy 88.801598 -182.510775)
			(xy 88.836554 -182.443504) (xy 88.878462 -182.380329) (xy 88.926848 -182.321967) (xy 88.981164 -182.269079)
			(xy 89.040793 -182.222264) (xy 89.105061 -182.182052) (xy 89.173238 -182.1489) (xy 89.244554 -182.123182)
			(xy 89.318199 -182.10519) (xy 89.393339 -182.095128) (xy 89.469123 -182.093109) (xy 89.544693 -182.099158)
			(xy 89.619191 -182.113205) (xy 89.691774 -182.135091) (xy 89.76162 -182.164568) (xy 89.827937 -182.201303)
			(xy 89.889973 -182.244878) (xy 89.947026 -182.2948) (xy 89.99845 -182.350504) (xy 90.043661 -182.411359)
			(xy 90.082148 -182.476674) (xy 90.113474 -182.54571) (xy 90.137284 -182.617685) (xy 90.153309 -182.691783)
			(xy 90.161368 -182.767164) (xy 90.161872 -182.80507) (xy 91.277951 -182.80507) (xy 91.281986 -182.729366)
			(xy 91.294045 -182.654521) (xy 91.313991 -182.58138) (xy 91.341598 -182.510775) (xy 91.376554 -182.443504)
			(xy 91.418462 -182.380329) (xy 91.466848 -182.321967) (xy 91.521164 -182.269079) (xy 91.580793 -182.222264)
			(xy 91.645061 -182.182052) (xy 91.713238 -182.1489) (xy 91.784554 -182.123182) (xy 91.858199 -182.10519)
			(xy 91.933339 -182.095128) (xy 92.009123 -182.093109) (xy 92.084693 -182.099158) (xy 92.159191 -182.113205)
			(xy 92.231774 -182.135091) (xy 92.30162 -182.164568) (xy 92.367937 -182.201303) (xy 92.429973 -182.244878)
			(xy 92.487026 -182.2948) (xy 92.53845 -182.350504) (xy 92.583661 -182.411359) (xy 92.622148 -182.476674)
			(xy 92.653474 -182.54571) (xy 92.677284 -182.617685) (xy 92.693309 -182.691783) (xy 92.701368 -182.767164)
			(xy 92.701872 -182.80507) (xy 92.701368 -182.842976) (xy 92.693309 -182.918357) (xy 92.677284 -182.992455)
			(xy 92.653474 -183.06443) (xy 92.622148 -183.133466) (xy 92.583661 -183.198781) (xy 92.53845 -183.259636)
			(xy 92.487026 -183.31534) (xy 92.429973 -183.365262) (xy 92.367937 -183.408837) (xy 92.30162 -183.445572)
			(xy 92.231774 -183.475049) (xy 92.159191 -183.496935) (xy 92.084693 -183.510982) (xy 92.009123 -183.517031)
			(xy 91.933339 -183.515012) (xy 91.858199 -183.50495) (xy 91.784554 -183.486958) (xy 91.713238 -183.46124)
			(xy 91.645061 -183.428088) (xy 91.580793 -183.387876) (xy 91.521164 -183.341061) (xy 91.466848 -183.288173)
			(xy 91.418462 -183.229811) (xy 91.376554 -183.166636) (xy 91.341598 -183.099365) (xy 91.313991 -183.02876)
			(xy 91.294045 -182.955619) (xy 91.281986 -182.880774) (xy 91.277951 -182.80507) (xy 90.161872 -182.80507)
			(xy 90.161368 -182.842976) (xy 90.153309 -182.918357) (xy 90.137284 -182.992455) (xy 90.113474 -183.06443)
			(xy 90.082148 -183.133466) (xy 90.043661 -183.198781) (xy 89.99845 -183.259636) (xy 89.947026 -183.31534)
			(xy 89.889973 -183.365262) (xy 89.827937 -183.408837) (xy 89.76162 -183.445572) (xy 89.691774 -183.475049)
			(xy 89.619191 -183.496935) (xy 89.544693 -183.510982) (xy 89.469123 -183.517031) (xy 89.393339 -183.515012)
			(xy 89.318199 -183.50495) (xy 89.244554 -183.486958) (xy 89.173238 -183.46124) (xy 89.105061 -183.428088)
			(xy 89.040793 -183.387876) (xy 88.981164 -183.341061) (xy 88.926848 -183.288173) (xy 88.878462 -183.229811)
			(xy 88.836554 -183.166636) (xy 88.801598 -183.099365) (xy 88.773991 -183.02876) (xy 88.754045 -182.955619)
			(xy 88.741986 -182.880774) (xy 88.737951 -182.80507) (xy 87.621872 -182.80507) (xy 87.621368 -182.842976)
			(xy 87.613309 -182.918357) (xy 87.597284 -182.992455) (xy 87.573474 -183.06443) (xy 87.542148 -183.133466)
			(xy 87.503661 -183.198781) (xy 87.45845 -183.259636) (xy 87.407026 -183.31534) (xy 87.349973 -183.365262)
			(xy 87.287937 -183.408837) (xy 87.22162 -183.445572) (xy 87.151774 -183.475049) (xy 87.079191 -183.496935)
			(xy 87.004693 -183.510982) (xy 86.929123 -183.517031) (xy 86.853339 -183.515012) (xy 86.778199 -183.50495)
			(xy 86.704554 -183.486958) (xy 86.633238 -183.46124) (xy 86.565061 -183.428088) (xy 86.500793 -183.387876)
			(xy 86.441164 -183.341061) (xy 86.386848 -183.288173) (xy 86.338462 -183.229811) (xy 86.296554 -183.166636)
			(xy 86.261598 -183.099365) (xy 86.233991 -183.02876) (xy 86.214045 -182.955619) (xy 86.201986 -182.880774)
			(xy 86.197951 -182.80507) (xy 82.585798 -182.80507) (xy 82.636906 -182.84979) (xy 82.68833 -182.905494)
			(xy 82.733541 -182.966349) (xy 82.772028 -183.031664) (xy 82.803354 -183.1007) (xy 82.827164 -183.172675)
			(xy 82.843189 -183.246773) (xy 82.851248 -183.322154) (xy 82.851752 -183.36006) (xy 82.851248 -183.397966)
			(xy 82.843189 -183.473347) (xy 82.827164 -183.547445) (xy 82.803354 -183.61942) (xy 82.772028 -183.688456)
			(xy 82.733541 -183.753771) (xy 82.68833 -183.814626) (xy 82.636906 -183.87033) (xy 82.579853 -183.920252)
			(xy 82.517817 -183.963827) (xy 82.4515 -184.000562) (xy 82.381654 -184.030039) (xy 82.309071 -184.051925)
			(xy 82.234573 -184.065972) (xy 82.159003 -184.072021) (xy 82.083219 -184.070002) (xy 82.008079 -184.05994)
			(xy 81.934434 -184.041948) (xy 81.863118 -184.01623) (xy 81.794941 -183.983078) (xy 81.730673 -183.942866)
			(xy 81.671044 -183.896051) (xy 81.616728 -183.843163) (xy 81.568342 -183.784801) (xy 81.526434 -183.721626)
			(xy 81.491478 -183.654355) (xy 81.463871 -183.58375) (xy 81.443925 -183.510609) (xy 81.431866 -183.435764)
			(xy 81.427831 -183.36006) (xy 80.311752 -183.36006) (xy 80.311248 -183.397966) (xy 80.303189 -183.473347)
			(xy 80.287164 -183.547445) (xy 80.263354 -183.61942) (xy 80.232028 -183.688456) (xy 80.193541 -183.753771)
			(xy 80.14833 -183.814626) (xy 80.096906 -183.87033) (xy 80.039853 -183.920252) (xy 79.977817 -183.963827)
			(xy 79.9115 -184.000562) (xy 79.841654 -184.030039) (xy 79.769071 -184.051925) (xy 79.694573 -184.065972)
			(xy 79.619003 -184.072021) (xy 79.543219 -184.070002) (xy 79.468079 -184.05994) (xy 79.394434 -184.041948)
			(xy 79.323118 -184.01623) (xy 79.254941 -183.983078) (xy 79.190673 -183.942866) (xy 79.131044 -183.896051)
			(xy 79.076728 -183.843163) (xy 79.028342 -183.784801) (xy 78.986434 -183.721626) (xy 78.951478 -183.654355)
			(xy 78.923871 -183.58375) (xy 78.903925 -183.510609) (xy 78.891866 -183.435764) (xy 78.887831 -183.36006)
			(xy 77.771752 -183.36006) (xy 77.771248 -183.397966) (xy 77.763189 -183.473347) (xy 77.747164 -183.547445)
			(xy 77.723354 -183.61942) (xy 77.692028 -183.688456) (xy 77.653541 -183.753771) (xy 77.60833 -183.814626)
			(xy 77.556906 -183.87033) (xy 77.499853 -183.920252) (xy 77.437817 -183.963827) (xy 77.3715 -184.000562)
			(xy 77.301654 -184.030039) (xy 77.229071 -184.051925) (xy 77.154573 -184.065972) (xy 77.079003 -184.072021)
			(xy 77.003219 -184.070002) (xy 76.928079 -184.05994) (xy 76.854434 -184.041948) (xy 76.783118 -184.01623)
			(xy 76.714941 -183.983078) (xy 76.650673 -183.942866) (xy 76.591044 -183.896051) (xy 76.536728 -183.843163)
			(xy 76.488342 -183.784801) (xy 76.446434 -183.721626) (xy 76.411478 -183.654355) (xy 76.383871 -183.58375)
			(xy 76.363925 -183.510609) (xy 76.351866 -183.435764) (xy 76.347831 -183.36006) (xy 75.231752 -183.36006)
			(xy 75.231248 -183.397966) (xy 75.223189 -183.473347) (xy 75.207164 -183.547445) (xy 75.183354 -183.61942)
			(xy 75.152028 -183.688456) (xy 75.113541 -183.753771) (xy 75.06833 -183.814626) (xy 75.016906 -183.87033)
			(xy 74.959853 -183.920252) (xy 74.897817 -183.963827) (xy 74.8315 -184.000562) (xy 74.761654 -184.030039)
			(xy 74.689071 -184.051925) (xy 74.614573 -184.065972) (xy 74.539003 -184.072021) (xy 74.463219 -184.070002)
			(xy 74.388079 -184.05994) (xy 74.314434 -184.041948) (xy 74.243118 -184.01623) (xy 74.174941 -183.983078)
			(xy 74.110673 -183.942866) (xy 74.051044 -183.896051) (xy 73.996728 -183.843163) (xy 73.948342 -183.784801)
			(xy 73.906434 -183.721626) (xy 73.871478 -183.654355) (xy 73.843871 -183.58375) (xy 73.823925 -183.510609)
			(xy 73.811866 -183.435764) (xy 73.807831 -183.36006) (xy 72.691752 -183.36006) (xy 72.691248 -183.397966)
			(xy 72.683189 -183.473347) (xy 72.667164 -183.547445) (xy 72.643354 -183.61942) (xy 72.612028 -183.688456)
			(xy 72.573541 -183.753771) (xy 72.52833 -183.814626) (xy 72.476906 -183.87033) (xy 72.419853 -183.920252)
			(xy 72.357817 -183.963827) (xy 72.2915 -184.000562) (xy 72.221654 -184.030039) (xy 72.149071 -184.051925)
			(xy 72.074573 -184.065972) (xy 71.999003 -184.072021) (xy 71.923219 -184.070002) (xy 71.848079 -184.05994)
			(xy 71.774434 -184.041948) (xy 71.703118 -184.01623) (xy 71.634941 -183.983078) (xy 71.570673 -183.942866)
			(xy 71.511044 -183.896051) (xy 71.456728 -183.843163) (xy 71.408342 -183.784801) (xy 71.366434 -183.721626)
			(xy 71.331478 -183.654355) (xy 71.303871 -183.58375) (xy 71.283925 -183.510609) (xy 71.271866 -183.435764)
			(xy 71.267831 -183.36006) (xy 70.151752 -183.36006) (xy 70.151248 -183.397966) (xy 70.143189 -183.473347)
			(xy 70.127164 -183.547445) (xy 70.103354 -183.61942) (xy 70.072028 -183.688456) (xy 70.033541 -183.753771)
			(xy 69.98833 -183.814626) (xy 69.936906 -183.87033) (xy 69.879853 -183.920252) (xy 69.817817 -183.963827)
			(xy 69.7515 -184.000562) (xy 69.681654 -184.030039) (xy 69.609071 -184.051925) (xy 69.534573 -184.065972)
			(xy 69.459003 -184.072021) (xy 69.383219 -184.070002) (xy 69.308079 -184.05994) (xy 69.234434 -184.041948)
			(xy 69.163118 -184.01623) (xy 69.094941 -183.983078) (xy 69.030673 -183.942866) (xy 68.971044 -183.896051)
			(xy 68.916728 -183.843163) (xy 68.868342 -183.784801) (xy 68.826434 -183.721626) (xy 68.791478 -183.654355)
			(xy 68.763871 -183.58375) (xy 68.743925 -183.510609) (xy 68.731866 -183.435764) (xy 68.727831 -183.36006)
			(xy 67.611752 -183.36006) (xy 67.611248 -183.397966) (xy 67.603189 -183.473347) (xy 67.587164 -183.547445)
			(xy 67.563354 -183.61942) (xy 67.532028 -183.688456) (xy 67.493541 -183.753771) (xy 67.44833 -183.814626)
			(xy 67.396906 -183.87033) (xy 67.339853 -183.920252) (xy 67.277817 -183.963827) (xy 67.2115 -184.000562)
			(xy 67.141654 -184.030039) (xy 67.069071 -184.051925) (xy 66.994573 -184.065972) (xy 66.919003 -184.072021)
			(xy 66.843219 -184.070002) (xy 66.768079 -184.05994) (xy 66.694434 -184.041948) (xy 66.623118 -184.01623)
			(xy 66.554941 -183.983078) (xy 66.490673 -183.942866) (xy 66.431044 -183.896051) (xy 66.376728 -183.843163)
			(xy 66.328342 -183.784801) (xy 66.286434 -183.721626) (xy 66.251478 -183.654355) (xy 66.223871 -183.58375)
			(xy 66.203925 -183.510609) (xy 66.191866 -183.435764) (xy 66.187831 -183.36006) (xy 65.071752 -183.36006)
			(xy 65.071248 -183.397966) (xy 65.063189 -183.473347) (xy 65.047164 -183.547445) (xy 65.023354 -183.61942)
			(xy 64.992028 -183.688456) (xy 64.953541 -183.753771) (xy 64.90833 -183.814626) (xy 64.856906 -183.87033)
			(xy 64.799853 -183.920252) (xy 64.737817 -183.963827) (xy 64.6715 -184.000562) (xy 64.601654 -184.030039)
			(xy 64.529071 -184.051925) (xy 64.454573 -184.065972) (xy 64.379003 -184.072021) (xy 64.303219 -184.070002)
			(xy 64.228079 -184.05994) (xy 64.154434 -184.041948) (xy 64.083118 -184.01623) (xy 64.014941 -183.983078)
			(xy 63.950673 -183.942866) (xy 63.891044 -183.896051) (xy 63.836728 -183.843163) (xy 63.788342 -183.784801)
			(xy 63.746434 -183.721626) (xy 63.711478 -183.654355) (xy 63.683871 -183.58375) (xy 63.663925 -183.510609)
			(xy 63.651866 -183.435764) (xy 63.647831 -183.36006) (xy 42.501941 -183.36006) (xy 42.582117 -183.422834)
			(xy 42.669176 -183.501374) (xy 42.750551 -183.585789) (xy 42.825845 -183.675669) (xy 42.894694 -183.770578)
			(xy 42.956761 -183.870054) (xy 43.011746 -183.973612) (xy 43.059381 -184.080751) (xy 43.099434 -184.190948)
			(xy 43.131712 -184.303669) (xy 43.156056 -184.418365) (xy 43.172348 -184.534478) (xy 43.18051 -184.651445)
			(xy 43.181016 -184.71007) (xy 43.180861 -184.740833) (xy 43.178574 -184.802316) (xy 43.176444 -184.833006)
			(xy 43.175682 -184.842404) (xy 43.170622 -184.900806) (xy 43.153396 -185.016771) (xy 43.12813 -185.131253)
			(xy 43.094949 -185.243697) (xy 43.054014 -185.353555) (xy 43.005523 -185.460294) (xy 42.949712 -185.563395)
			(xy 42.886853 -185.662356) (xy 42.817252 -185.756696) (xy 42.741246 -185.845958) (xy 42.659204 -185.929706)
			(xy 42.571527 -186.007535) (xy 42.503292 -186.06008) (xy 63.647831 -186.06008) (xy 63.651866 -185.984376)
			(xy 63.663925 -185.909531) (xy 63.683871 -185.83639) (xy 63.711478 -185.765785) (xy 63.746434 -185.698514)
			(xy 63.788342 -185.635339) (xy 63.836728 -185.576977) (xy 63.891044 -185.524089) (xy 63.950673 -185.477274)
			(xy 64.014941 -185.437062) (xy 64.083118 -185.40391) (xy 64.154434 -185.378192) (xy 64.228079 -185.3602)
			(xy 64.303219 -185.350138) (xy 64.379003 -185.348119) (xy 64.454573 -185.354168) (xy 64.529071 -185.368215)
			(xy 64.601654 -185.390101) (xy 64.6715 -185.419578) (xy 64.737817 -185.456313) (xy 64.799853 -185.499888)
			(xy 64.856906 -185.54981) (xy 64.90833 -185.605514) (xy 64.953541 -185.666369) (xy 64.992028 -185.731684)
			(xy 65.023354 -185.80072) (xy 65.047164 -185.872695) (xy 65.063189 -185.946793) (xy 65.071248 -186.022174)
			(xy 65.071752 -186.06008) (xy 66.187831 -186.06008) (xy 66.191866 -185.984376) (xy 66.203925 -185.909531)
			(xy 66.223871 -185.83639) (xy 66.251478 -185.765785) (xy 66.286434 -185.698514) (xy 66.328342 -185.635339)
			(xy 66.376728 -185.576977) (xy 66.431044 -185.524089) (xy 66.490673 -185.477274) (xy 66.554941 -185.437062)
			(xy 66.623118 -185.40391) (xy 66.694434 -185.378192) (xy 66.768079 -185.3602) (xy 66.843219 -185.350138)
			(xy 66.919003 -185.348119) (xy 66.994573 -185.354168) (xy 67.069071 -185.368215) (xy 67.141654 -185.390101)
			(xy 67.2115 -185.419578) (xy 67.277817 -185.456313) (xy 67.339853 -185.499888) (xy 67.396906 -185.54981)
			(xy 67.44833 -185.605514) (xy 67.493541 -185.666369) (xy 67.532028 -185.731684) (xy 67.563354 -185.80072)
			(xy 67.587164 -185.872695) (xy 67.603189 -185.946793) (xy 67.611248 -186.022174) (xy 67.611752 -186.06008)
			(xy 68.727831 -186.06008) (xy 68.731866 -185.984376) (xy 68.743925 -185.909531) (xy 68.763871 -185.83639)
			(xy 68.791478 -185.765785) (xy 68.826434 -185.698514) (xy 68.868342 -185.635339) (xy 68.916728 -185.576977)
			(xy 68.971044 -185.524089) (xy 69.030673 -185.477274) (xy 69.094941 -185.437062) (xy 69.163118 -185.40391)
			(xy 69.234434 -185.378192) (xy 69.308079 -185.3602) (xy 69.383219 -185.350138) (xy 69.459003 -185.348119)
			(xy 69.534573 -185.354168) (xy 69.609071 -185.368215) (xy 69.681654 -185.390101) (xy 69.7515 -185.419578)
			(xy 69.817817 -185.456313) (xy 69.879853 -185.499888) (xy 69.936906 -185.54981) (xy 69.98833 -185.605514)
			(xy 70.033541 -185.666369) (xy 70.072028 -185.731684) (xy 70.103354 -185.80072) (xy 70.127164 -185.872695)
			(xy 70.143189 -185.946793) (xy 70.151248 -186.022174) (xy 70.151752 -186.06008) (xy 71.267831 -186.06008)
			(xy 71.271866 -185.984376) (xy 71.283925 -185.909531) (xy 71.303871 -185.83639) (xy 71.331478 -185.765785)
			(xy 71.366434 -185.698514) (xy 71.408342 -185.635339) (xy 71.456728 -185.576977) (xy 71.511044 -185.524089)
			(xy 71.570673 -185.477274) (xy 71.634941 -185.437062) (xy 71.703118 -185.40391) (xy 71.774434 -185.378192)
			(xy 71.848079 -185.3602) (xy 71.923219 -185.350138) (xy 71.999003 -185.348119) (xy 72.074573 -185.354168)
			(xy 72.149071 -185.368215) (xy 72.221654 -185.390101) (xy 72.2915 -185.419578) (xy 72.357817 -185.456313)
			(xy 72.419853 -185.499888) (xy 72.476906 -185.54981) (xy 72.52833 -185.605514) (xy 72.573541 -185.666369)
			(xy 72.612028 -185.731684) (xy 72.643354 -185.80072) (xy 72.667164 -185.872695) (xy 72.683189 -185.946793)
			(xy 72.691248 -186.022174) (xy 72.691752 -186.06008) (xy 73.807831 -186.06008) (xy 73.811866 -185.984376)
			(xy 73.823925 -185.909531) (xy 73.843871 -185.83639) (xy 73.871478 -185.765785) (xy 73.906434 -185.698514)
			(xy 73.948342 -185.635339) (xy 73.996728 -185.576977) (xy 74.051044 -185.524089) (xy 74.110673 -185.477274)
			(xy 74.174941 -185.437062) (xy 74.243118 -185.40391) (xy 74.314434 -185.378192) (xy 74.388079 -185.3602)
			(xy 74.463219 -185.350138) (xy 74.539003 -185.348119) (xy 74.614573 -185.354168) (xy 74.689071 -185.368215)
			(xy 74.761654 -185.390101) (xy 74.8315 -185.419578) (xy 74.897817 -185.456313) (xy 74.959853 -185.499888)
			(xy 75.016906 -185.54981) (xy 75.06833 -185.605514) (xy 75.113541 -185.666369) (xy 75.152028 -185.731684)
			(xy 75.183354 -185.80072) (xy 75.207164 -185.872695) (xy 75.223189 -185.946793) (xy 75.231248 -186.022174)
			(xy 75.231752 -186.06008) (xy 76.347831 -186.06008) (xy 76.351866 -185.984376) (xy 76.363925 -185.909531)
			(xy 76.383871 -185.83639) (xy 76.411478 -185.765785) (xy 76.446434 -185.698514) (xy 76.488342 -185.635339)
			(xy 76.536728 -185.576977) (xy 76.591044 -185.524089) (xy 76.650673 -185.477274) (xy 76.714941 -185.437062)
			(xy 76.783118 -185.40391) (xy 76.854434 -185.378192) (xy 76.928079 -185.3602) (xy 77.003219 -185.350138)
			(xy 77.079003 -185.348119) (xy 77.154573 -185.354168) (xy 77.229071 -185.368215) (xy 77.301654 -185.390101)
			(xy 77.3715 -185.419578) (xy 77.437817 -185.456313) (xy 77.499853 -185.499888) (xy 77.556906 -185.54981)
			(xy 77.60833 -185.605514) (xy 77.653541 -185.666369) (xy 77.692028 -185.731684) (xy 77.723354 -185.80072)
			(xy 77.747164 -185.872695) (xy 77.763189 -185.946793) (xy 77.771248 -186.022174) (xy 77.771752 -186.06008)
			(xy 78.887831 -186.06008) (xy 78.891866 -185.984376) (xy 78.903925 -185.909531) (xy 78.923871 -185.83639)
			(xy 78.951478 -185.765785) (xy 78.986434 -185.698514) (xy 79.028342 -185.635339) (xy 79.076728 -185.576977)
			(xy 79.131044 -185.524089) (xy 79.190673 -185.477274) (xy 79.254941 -185.437062) (xy 79.323118 -185.40391)
			(xy 79.394434 -185.378192) (xy 79.468079 -185.3602) (xy 79.543219 -185.350138) (xy 79.619003 -185.348119)
			(xy 79.694573 -185.354168) (xy 79.769071 -185.368215) (xy 79.841654 -185.390101) (xy 79.9115 -185.419578)
			(xy 79.977817 -185.456313) (xy 80.039853 -185.499888) (xy 80.096906 -185.54981) (xy 80.14833 -185.605514)
			(xy 80.193541 -185.666369) (xy 80.232028 -185.731684) (xy 80.263354 -185.80072) (xy 80.287164 -185.872695)
			(xy 80.303189 -185.946793) (xy 80.311248 -186.022174) (xy 80.311752 -186.06008) (xy 81.427831 -186.06008)
			(xy 81.431866 -185.984376) (xy 81.443925 -185.909531) (xy 81.463871 -185.83639) (xy 81.491478 -185.765785)
			(xy 81.526434 -185.698514) (xy 81.568342 -185.635339) (xy 81.616728 -185.576977) (xy 81.671044 -185.524089)
			(xy 81.730673 -185.477274) (xy 81.794941 -185.437062) (xy 81.863118 -185.40391) (xy 81.934434 -185.378192)
			(xy 82.008079 -185.3602) (xy 82.083219 -185.350138) (xy 82.159003 -185.348119) (xy 82.234573 -185.354168)
			(xy 82.309071 -185.368215) (xy 82.381654 -185.390101) (xy 82.4515 -185.419578) (xy 82.517817 -185.456313)
			(xy 82.579853 -185.499888) (xy 82.636906 -185.54981) (xy 82.68833 -185.605514) (xy 82.733541 -185.666369)
			(xy 82.772028 -185.731684) (xy 82.803354 -185.80072) (xy 82.827164 -185.872695) (xy 82.843189 -185.946793)
			(xy 82.851248 -186.022174) (xy 82.851752 -186.06008) (xy 82.851248 -186.097986) (xy 82.843189 -186.173367)
			(xy 82.827164 -186.247465) (xy 82.803354 -186.31944) (xy 82.772028 -186.388476) (xy 82.733541 -186.453791)
			(xy 82.68833 -186.514646) (xy 82.636906 -186.57035) (xy 82.579853 -186.620272) (xy 82.517817 -186.663847)
			(xy 82.4515 -186.700582) (xy 82.381654 -186.730059) (xy 82.309071 -186.751945) (xy 82.234573 -186.765992)
			(xy 82.159003 -186.772041) (xy 82.083219 -186.770022) (xy 82.008079 -186.75996) (xy 81.934434 -186.741968)
			(xy 81.863118 -186.71625) (xy 81.794941 -186.683098) (xy 81.730673 -186.642886) (xy 81.671044 -186.596071)
			(xy 81.616728 -186.543183) (xy 81.568342 -186.484821) (xy 81.526434 -186.421646) (xy 81.491478 -186.354375)
			(xy 81.463871 -186.28377) (xy 81.443925 -186.210629) (xy 81.431866 -186.135784) (xy 81.427831 -186.06008)
			(xy 80.311752 -186.06008) (xy 80.311248 -186.097986) (xy 80.303189 -186.173367) (xy 80.287164 -186.247465)
			(xy 80.263354 -186.31944) (xy 80.232028 -186.388476) (xy 80.193541 -186.453791) (xy 80.14833 -186.514646)
			(xy 80.096906 -186.57035) (xy 80.039853 -186.620272) (xy 79.977817 -186.663847) (xy 79.9115 -186.700582)
			(xy 79.841654 -186.730059) (xy 79.769071 -186.751945) (xy 79.694573 -186.765992) (xy 79.619003 -186.772041)
			(xy 79.543219 -186.770022) (xy 79.468079 -186.75996) (xy 79.394434 -186.741968) (xy 79.323118 -186.71625)
			(xy 79.254941 -186.683098) (xy 79.190673 -186.642886) (xy 79.131044 -186.596071) (xy 79.076728 -186.543183)
			(xy 79.028342 -186.484821) (xy 78.986434 -186.421646) (xy 78.951478 -186.354375) (xy 78.923871 -186.28377)
			(xy 78.903925 -186.210629) (xy 78.891866 -186.135784) (xy 78.887831 -186.06008) (xy 77.771752 -186.06008)
			(xy 77.771248 -186.097986) (xy 77.763189 -186.173367) (xy 77.747164 -186.247465) (xy 77.723354 -186.31944)
			(xy 77.692028 -186.388476) (xy 77.653541 -186.453791) (xy 77.60833 -186.514646) (xy 77.556906 -186.57035)
			(xy 77.499853 -186.620272) (xy 77.437817 -186.663847) (xy 77.3715 -186.700582) (xy 77.301654 -186.730059)
			(xy 77.229071 -186.751945) (xy 77.154573 -186.765992) (xy 77.079003 -186.772041) (xy 77.003219 -186.770022)
			(xy 76.928079 -186.75996) (xy 76.854434 -186.741968) (xy 76.783118 -186.71625) (xy 76.714941 -186.683098)
			(xy 76.650673 -186.642886) (xy 76.591044 -186.596071) (xy 76.536728 -186.543183) (xy 76.488342 -186.484821)
			(xy 76.446434 -186.421646) (xy 76.411478 -186.354375) (xy 76.383871 -186.28377) (xy 76.363925 -186.210629)
			(xy 76.351866 -186.135784) (xy 76.347831 -186.06008) (xy 75.231752 -186.06008) (xy 75.231248 -186.097986)
			(xy 75.223189 -186.173367) (xy 75.207164 -186.247465) (xy 75.183354 -186.31944) (xy 75.152028 -186.388476)
			(xy 75.113541 -186.453791) (xy 75.06833 -186.514646) (xy 75.016906 -186.57035) (xy 74.959853 -186.620272)
			(xy 74.897817 -186.663847) (xy 74.8315 -186.700582) (xy 74.761654 -186.730059) (xy 74.689071 -186.751945)
			(xy 74.614573 -186.765992) (xy 74.539003 -186.772041) (xy 74.463219 -186.770022) (xy 74.388079 -186.75996)
			(xy 74.314434 -186.741968) (xy 74.243118 -186.71625) (xy 74.174941 -186.683098) (xy 74.110673 -186.642886)
			(xy 74.051044 -186.596071) (xy 73.996728 -186.543183) (xy 73.948342 -186.484821) (xy 73.906434 -186.421646)
			(xy 73.871478 -186.354375) (xy 73.843871 -186.28377) (xy 73.823925 -186.210629) (xy 73.811866 -186.135784)
			(xy 73.807831 -186.06008) (xy 72.691752 -186.06008) (xy 72.691248 -186.097986) (xy 72.683189 -186.173367)
			(xy 72.667164 -186.247465) (xy 72.643354 -186.31944) (xy 72.612028 -186.388476) (xy 72.573541 -186.453791)
			(xy 72.52833 -186.514646) (xy 72.476906 -186.57035) (xy 72.419853 -186.620272) (xy 72.357817 -186.663847)
			(xy 72.2915 -186.700582) (xy 72.221654 -186.730059) (xy 72.149071 -186.751945) (xy 72.074573 -186.765992)
			(xy 71.999003 -186.772041) (xy 71.923219 -186.770022) (xy 71.848079 -186.75996) (xy 71.774434 -186.741968)
			(xy 71.703118 -186.71625) (xy 71.634941 -186.683098) (xy 71.570673 -186.642886) (xy 71.511044 -186.596071)
			(xy 71.456728 -186.543183) (xy 71.408342 -186.484821) (xy 71.366434 -186.421646) (xy 71.331478 -186.354375)
			(xy 71.303871 -186.28377) (xy 71.283925 -186.210629) (xy 71.271866 -186.135784) (xy 71.267831 -186.06008)
			(xy 70.151752 -186.06008) (xy 70.151248 -186.097986) (xy 70.143189 -186.173367) (xy 70.127164 -186.247465)
			(xy 70.103354 -186.31944) (xy 70.072028 -186.388476) (xy 70.033541 -186.453791) (xy 69.98833 -186.514646)
			(xy 69.936906 -186.57035) (xy 69.879853 -186.620272) (xy 69.817817 -186.663847) (xy 69.7515 -186.700582)
			(xy 69.681654 -186.730059) (xy 69.609071 -186.751945) (xy 69.534573 -186.765992) (xy 69.459003 -186.772041)
			(xy 69.383219 -186.770022) (xy 69.308079 -186.75996) (xy 69.234434 -186.741968) (xy 69.163118 -186.71625)
			(xy 69.094941 -186.683098) (xy 69.030673 -186.642886) (xy 68.971044 -186.596071) (xy 68.916728 -186.543183)
			(xy 68.868342 -186.484821) (xy 68.826434 -186.421646) (xy 68.791478 -186.354375) (xy 68.763871 -186.28377)
			(xy 68.743925 -186.210629) (xy 68.731866 -186.135784) (xy 68.727831 -186.06008) (xy 67.611752 -186.06008)
			(xy 67.611248 -186.097986) (xy 67.603189 -186.173367) (xy 67.587164 -186.247465) (xy 67.563354 -186.31944)
			(xy 67.532028 -186.388476) (xy 67.493541 -186.453791) (xy 67.44833 -186.514646) (xy 67.396906 -186.57035)
			(xy 67.339853 -186.620272) (xy 67.277817 -186.663847) (xy 67.2115 -186.700582) (xy 67.141654 -186.730059)
			(xy 67.069071 -186.751945) (xy 66.994573 -186.765992) (xy 66.919003 -186.772041) (xy 66.843219 -186.770022)
			(xy 66.768079 -186.75996) (xy 66.694434 -186.741968) (xy 66.623118 -186.71625) (xy 66.554941 -186.683098)
			(xy 66.490673 -186.642886) (xy 66.431044 -186.596071) (xy 66.376728 -186.543183) (xy 66.328342 -186.484821)
			(xy 66.286434 -186.421646) (xy 66.251478 -186.354375) (xy 66.223871 -186.28377) (xy 66.203925 -186.210629)
			(xy 66.191866 -186.135784) (xy 66.187831 -186.06008) (xy 65.071752 -186.06008) (xy 65.071248 -186.097986)
			(xy 65.063189 -186.173367) (xy 65.047164 -186.247465) (xy 65.023354 -186.31944) (xy 64.992028 -186.388476)
			(xy 64.953541 -186.453791) (xy 64.90833 -186.514646) (xy 64.856906 -186.57035) (xy 64.799853 -186.620272)
			(xy 64.737817 -186.663847) (xy 64.6715 -186.700582) (xy 64.601654 -186.730059) (xy 64.529071 -186.751945)
			(xy 64.454573 -186.765992) (xy 64.379003 -186.772041) (xy 64.303219 -186.770022) (xy 64.228079 -186.75996)
			(xy 64.154434 -186.741968) (xy 64.083118 -186.71625) (xy 64.014941 -186.683098) (xy 63.950673 -186.642886)
			(xy 63.891044 -186.596071) (xy 63.836728 -186.543183) (xy 63.788342 -186.484821) (xy 63.746434 -186.421646)
			(xy 63.711478 -186.354375) (xy 63.683871 -186.28377) (xy 63.663925 -186.210629) (xy 63.651866 -186.135784)
			(xy 63.647831 -186.06008) (xy 42.503292 -186.06008) (xy 42.47864 -186.079064) (xy 42.380994 -186.143948)
			(xy 42.279065 -186.20187) (xy 42.173347 -186.252549) (xy 42.064355 -186.295738) (xy 41.952619 -186.331228)
			(xy 41.838681 -186.358845) (xy 41.723096 -186.378457) (xy 41.606425 -186.389967) (xy 41.489236 -186.393319)
			(xy 41.372098 -186.388497) (xy 41.25558 -186.375525) (xy 41.14025 -186.354466) (xy 41.026668 -186.325421)
			(xy 40.915385 -186.288533) (xy 40.806943 -186.24398) (xy 40.70187 -186.19198) (xy 40.600675 -186.132784)
			(xy 40.50385 -186.066681) (xy 40.411868 -185.993992) (xy 40.325173 -185.91507) (xy 40.244189 -185.830299)
			(xy 40.169308 -185.740091) (xy 40.100895 -185.644885) (xy 40.039282 -185.545143) (xy 39.984769 -185.441351)
			(xy 39.937621 -185.334012) (xy 39.898066 -185.223649) (xy 39.866298 -185.110798) (xy 39.842471 -184.996008)
			(xy 39.826699 -184.879836) (xy 39.819061 -184.762848) (xy 39.818818 -184.704228) (xy 36.07398 -184.704228)
			(xy 36.071366 -184.706202) (xy 35.997482 -184.751949) (xy 35.919693 -184.790683) (xy 35.838661 -184.822075)
			(xy 35.755079 -184.845856) (xy 35.669659 -184.861824) (xy 35.58313 -184.869842) (xy 35.49623 -184.869842)
			(xy 35.409701 -184.861824) (xy 35.324281 -184.845856) (xy 35.240699 -184.822075) (xy 35.159667 -184.790683)
			(xy 35.081878 -184.751949) (xy 35.007994 -184.706202) (xy 34.938647 -184.653833) (xy 34.874427 -184.595289)
			(xy 34.815883 -184.531069) (xy 34.763514 -184.461722) (xy 34.717767 -184.387838) (xy 34.679033 -184.310049)
			(xy 34.647641 -184.229017) (xy 34.62386 -184.145435) (xy 34.607892 -184.060015) (xy 34.599874 -183.973486)
			(xy 31.399486 -183.973486) (xy 31.391468 -184.060015) (xy 31.3755 -184.145435) (xy 31.351719 -184.229017)
			(xy 31.320327 -184.310049) (xy 31.281593 -184.387838) (xy 31.235846 -184.461722) (xy 31.183477 -184.531069)
			(xy 31.124933 -184.595289) (xy 31.060713 -184.653833) (xy 30.991366 -184.706202) (xy 30.917482 -184.751949)
			(xy 30.839693 -184.790683) (xy 30.758661 -184.822075) (xy 30.675079 -184.845856) (xy 30.589659 -184.861824)
			(xy 30.50313 -184.869842) (xy 30.41623 -184.869842) (xy 30.329701 -184.861824) (xy 30.244281 -184.845856)
			(xy 30.160699 -184.822075) (xy 30.079667 -184.790683) (xy 30.001878 -184.751949) (xy 29.927994 -184.706202)
			(xy 29.858647 -184.653833) (xy 29.794427 -184.595289) (xy 29.735883 -184.531069) (xy 29.683514 -184.461722)
			(xy 29.637767 -184.387838) (xy 29.599033 -184.310049) (xy 29.567641 -184.229017) (xy 29.54386 -184.145435)
			(xy 29.527892 -184.060015) (xy 29.519874 -183.973486) (xy 28.090876 -183.973486) (xy 28.090876 -186.513486)
			(xy 29.519874 -186.513486) (xy 29.519874 -186.426586) (xy 29.527892 -186.340057) (xy 29.54386 -186.254637)
			(xy 29.567641 -186.171055) (xy 29.599033 -186.090023) (xy 29.637767 -186.012234) (xy 29.683514 -185.93835)
			(xy 29.735883 -185.869003) (xy 29.794427 -185.804783) (xy 29.858647 -185.746239) (xy 29.927994 -185.69387)
			(xy 30.001878 -185.648123) (xy 30.079667 -185.609389) (xy 30.160699 -185.577997) (xy 30.244281 -185.554216)
			(xy 30.329701 -185.538248) (xy 30.41623 -185.53023) (xy 30.50313 -185.53023) (xy 30.589659 -185.538248)
			(xy 30.675079 -185.554216) (xy 30.758661 -185.577997) (xy 30.839693 -185.609389) (xy 30.917482 -185.648123)
			(xy 30.991366 -185.69387) (xy 31.060713 -185.746239) (xy 31.124933 -185.804783) (xy 31.183477 -185.869003)
			(xy 31.235846 -185.93835) (xy 31.281593 -186.012234) (xy 31.320327 -186.090023) (xy 31.351719 -186.171055)
			(xy 31.3755 -186.254637) (xy 31.391468 -186.340057) (xy 31.399486 -186.426586) (xy 31.399988 -186.470036)
			(xy 31.399486 -186.513486) (xy 34.599874 -186.513486) (xy 34.599874 -186.426586) (xy 34.607892 -186.340057)
			(xy 34.62386 -186.254637) (xy 34.647641 -186.171055) (xy 34.679033 -186.090023) (xy 34.717767 -186.012234)
			(xy 34.763514 -185.93835) (xy 34.815883 -185.869003) (xy 34.874427 -185.804783) (xy 34.938647 -185.746239)
			(xy 35.007994 -185.69387) (xy 35.081878 -185.648123) (xy 35.159667 -185.609389) (xy 35.240699 -185.577997)
			(xy 35.324281 -185.554216) (xy 35.409701 -185.538248) (xy 35.49623 -185.53023) (xy 35.58313 -185.53023)
			(xy 35.669659 -185.538248) (xy 35.755079 -185.554216) (xy 35.838661 -185.577997) (xy 35.919693 -185.609389)
			(xy 35.997482 -185.648123) (xy 36.071366 -185.69387) (xy 36.140713 -185.746239) (xy 36.204933 -185.804783)
			(xy 36.263477 -185.869003) (xy 36.315846 -185.93835) (xy 36.361593 -186.012234) (xy 36.400327 -186.090023)
			(xy 36.431719 -186.171055) (xy 36.4555 -186.254637) (xy 36.471468 -186.340057) (xy 36.479486 -186.426586)
			(xy 36.479988 -186.470036) (xy 36.479486 -186.513486) (xy 36.471468 -186.600015) (xy 36.4555 -186.685435)
			(xy 36.431719 -186.769017) (xy 36.400327 -186.850049) (xy 36.361593 -186.927838) (xy 36.315846 -187.001722)
			(xy 36.263477 -187.071069) (xy 36.204933 -187.135289) (xy 36.140713 -187.193833) (xy 36.071366 -187.246202)
			(xy 35.997482 -187.291949) (xy 35.919693 -187.330683) (xy 35.838661 -187.362075) (xy 35.755079 -187.385856)
			(xy 35.669659 -187.401824) (xy 35.58313 -187.409842) (xy 35.49623 -187.409842) (xy 35.409701 -187.401824)
			(xy 35.324281 -187.385856) (xy 35.240699 -187.362075) (xy 35.159667 -187.330683) (xy 35.081878 -187.291949)
			(xy 35.007994 -187.246202) (xy 34.938647 -187.193833) (xy 34.874427 -187.135289) (xy 34.815883 -187.071069)
			(xy 34.763514 -187.001722) (xy 34.717767 -186.927838) (xy 34.679033 -186.850049) (xy 34.647641 -186.769017)
			(xy 34.62386 -186.685435) (xy 34.607892 -186.600015) (xy 34.599874 -186.513486) (xy 31.399486 -186.513486)
			(xy 31.391468 -186.600015) (xy 31.3755 -186.685435) (xy 31.351719 -186.769017) (xy 31.320327 -186.850049)
			(xy 31.281593 -186.927838) (xy 31.235846 -187.001722) (xy 31.183477 -187.071069) (xy 31.124933 -187.135289)
			(xy 31.060713 -187.193833) (xy 30.991366 -187.246202) (xy 30.917482 -187.291949) (xy 30.839693 -187.330683)
			(xy 30.758661 -187.362075) (xy 30.675079 -187.385856) (xy 30.589659 -187.401824) (xy 30.50313 -187.409842)
			(xy 30.41623 -187.409842) (xy 30.329701 -187.401824) (xy 30.244281 -187.385856) (xy 30.160699 -187.362075)
			(xy 30.079667 -187.330683) (xy 30.001878 -187.291949) (xy 29.927994 -187.246202) (xy 29.858647 -187.193833)
			(xy 29.794427 -187.135289) (xy 29.735883 -187.071069) (xy 29.683514 -187.001722) (xy 29.637767 -186.927838)
			(xy 29.599033 -186.850049) (xy 29.567641 -186.769017) (xy 29.54386 -186.685435) (xy 29.527892 -186.600015)
			(xy 29.519874 -186.513486) (xy 28.090876 -186.513486) (xy 28.090876 -189.053486) (xy 29.519874 -189.053486)
			(xy 29.519874 -188.966586) (xy 29.527892 -188.880057) (xy 29.54386 -188.794637) (xy 29.567641 -188.711055)
			(xy 29.599033 -188.630023) (xy 29.637767 -188.552234) (xy 29.683514 -188.47835) (xy 29.735883 -188.409003)
			(xy 29.794427 -188.344783) (xy 29.858647 -188.286239) (xy 29.927994 -188.23387) (xy 30.001878 -188.188123)
			(xy 30.079667 -188.149389) (xy 30.160699 -188.117997) (xy 30.244281 -188.094216) (xy 30.329701 -188.078248)
			(xy 30.41623 -188.07023) (xy 30.50313 -188.07023) (xy 30.589659 -188.078248) (xy 30.675079 -188.094216)
			(xy 30.758661 -188.117997) (xy 30.839693 -188.149389) (xy 30.917482 -188.188123) (xy 30.991366 -188.23387)
			(xy 31.060713 -188.286239) (xy 31.124933 -188.344783) (xy 31.183477 -188.409003) (xy 31.235846 -188.47835)
			(xy 31.281593 -188.552234) (xy 31.320327 -188.630023) (xy 31.351719 -188.711055) (xy 31.3755 -188.794637)
			(xy 31.391468 -188.880057) (xy 31.399486 -188.966586) (xy 31.399988 -189.010036) (xy 31.399486 -189.053486)
			(xy 34.599874 -189.053486) (xy 34.599874 -188.966586) (xy 34.607892 -188.880057) (xy 34.62386 -188.794637)
			(xy 34.647641 -188.711055) (xy 34.679033 -188.630023) (xy 34.717767 -188.552234) (xy 34.763514 -188.47835)
			(xy 34.815883 -188.409003) (xy 34.874427 -188.344783) (xy 34.938647 -188.286239) (xy 35.007994 -188.23387)
			(xy 35.081878 -188.188123) (xy 35.159667 -188.149389) (xy 35.240699 -188.117997) (xy 35.324281 -188.094216)
			(xy 35.409701 -188.078248) (xy 35.49623 -188.07023) (xy 35.58313 -188.07023) (xy 35.669659 -188.078248)
			(xy 35.755079 -188.094216) (xy 35.838661 -188.117997) (xy 35.919693 -188.149389) (xy 35.997482 -188.188123)
			(xy 36.071366 -188.23387) (xy 36.140713 -188.286239) (xy 36.204933 -188.344783) (xy 36.263477 -188.409003)
			(xy 36.315846 -188.47835) (xy 36.361593 -188.552234) (xy 36.400327 -188.630023) (xy 36.431719 -188.711055)
			(xy 36.4555 -188.794637) (xy 36.471468 -188.880057) (xy 36.479486 -188.966586) (xy 36.479988 -189.010036)
			(xy 36.479486 -189.053486) (xy 36.471468 -189.140015) (xy 36.4555 -189.225435) (xy 36.431719 -189.309017)
			(xy 36.400327 -189.390049) (xy 36.361593 -189.467838) (xy 36.315846 -189.541722) (xy 36.263477 -189.611069)
			(xy 36.204933 -189.675289) (xy 36.140713 -189.733833) (xy 36.071366 -189.786202) (xy 35.997482 -189.831949)
			(xy 35.919693 -189.870683) (xy 35.838661 -189.902075) (xy 35.755079 -189.925856) (xy 35.669659 -189.941824)
			(xy 35.58313 -189.949842) (xy 35.49623 -189.949842) (xy 35.409701 -189.941824) (xy 35.324281 -189.925856)
			(xy 35.240699 -189.902075) (xy 35.159667 -189.870683) (xy 35.081878 -189.831949) (xy 35.007994 -189.786202)
			(xy 34.938647 -189.733833) (xy 34.874427 -189.675289) (xy 34.815883 -189.611069) (xy 34.763514 -189.541722)
			(xy 34.717767 -189.467838) (xy 34.679033 -189.390049) (xy 34.647641 -189.309017) (xy 34.62386 -189.225435)
			(xy 34.607892 -189.140015) (xy 34.599874 -189.053486) (xy 31.399486 -189.053486) (xy 31.391468 -189.140015)
			(xy 31.3755 -189.225435) (xy 31.351719 -189.309017) (xy 31.320327 -189.390049) (xy 31.281593 -189.467838)
			(xy 31.235846 -189.541722) (xy 31.183477 -189.611069) (xy 31.124933 -189.675289) (xy 31.060713 -189.733833)
			(xy 30.991366 -189.786202) (xy 30.917482 -189.831949) (xy 30.839693 -189.870683) (xy 30.758661 -189.902075)
			(xy 30.675079 -189.925856) (xy 30.589659 -189.941824) (xy 30.50313 -189.949842) (xy 30.41623 -189.949842)
			(xy 30.329701 -189.941824) (xy 30.244281 -189.925856) (xy 30.160699 -189.902075) (xy 30.079667 -189.870683)
			(xy 30.001878 -189.831949) (xy 29.927994 -189.786202) (xy 29.858647 -189.733833) (xy 29.794427 -189.675289)
			(xy 29.735883 -189.611069) (xy 29.683514 -189.541722) (xy 29.637767 -189.467838) (xy 29.599033 -189.390049)
			(xy 29.567641 -189.309017) (xy 29.54386 -189.225435) (xy 29.527892 -189.140015) (xy 29.519874 -189.053486)
			(xy 28.090876 -189.053486) (xy 28.090876 -191.593486) (xy 29.519874 -191.593486) (xy 29.519874 -191.506586)
			(xy 29.527892 -191.420057) (xy 29.54386 -191.334637) (xy 29.567641 -191.251055) (xy 29.599033 -191.170023)
			(xy 29.637767 -191.092234) (xy 29.683514 -191.01835) (xy 29.735883 -190.949003) (xy 29.794427 -190.884783)
			(xy 29.858647 -190.826239) (xy 29.927994 -190.77387) (xy 30.001878 -190.728123) (xy 30.079667 -190.689389)
			(xy 30.160699 -190.657997) (xy 30.244281 -190.634216) (xy 30.329701 -190.618248) (xy 30.41623 -190.61023)
			(xy 30.50313 -190.61023) (xy 30.589659 -190.618248) (xy 30.675079 -190.634216) (xy 30.758661 -190.657997)
			(xy 30.839693 -190.689389) (xy 30.917482 -190.728123) (xy 30.991366 -190.77387) (xy 31.060713 -190.826239)
			(xy 31.124933 -190.884783) (xy 31.183477 -190.949003) (xy 31.235846 -191.01835) (xy 31.281593 -191.092234)
			(xy 31.320327 -191.170023) (xy 31.351719 -191.251055) (xy 31.3755 -191.334637) (xy 31.391468 -191.420057)
			(xy 31.399486 -191.506586) (xy 31.399988 -191.550036) (xy 31.399486 -191.593486) (xy 34.599874 -191.593486)
			(xy 34.599874 -191.506586) (xy 34.607892 -191.420057) (xy 34.62386 -191.334637) (xy 34.647641 -191.251055)
			(xy 34.679033 -191.170023) (xy 34.717767 -191.092234) (xy 34.763514 -191.01835) (xy 34.815883 -190.949003)
			(xy 34.874427 -190.884783) (xy 34.938647 -190.826239) (xy 35.007994 -190.77387) (xy 35.081878 -190.728123)
			(xy 35.159667 -190.689389) (xy 35.240699 -190.657997) (xy 35.324281 -190.634216) (xy 35.409701 -190.618248)
			(xy 35.49623 -190.61023) (xy 35.58313 -190.61023) (xy 35.669659 -190.618248) (xy 35.755079 -190.634216)
			(xy 35.838661 -190.657997) (xy 35.919693 -190.689389) (xy 35.997482 -190.728123) (xy 36.065119 -190.770002)
			(xy 39.396922 -190.770002) (xy 39.400993 -190.71438) (xy 39.413119 -190.659943) (xy 39.433042 -190.607852)
			(xy 39.460338 -190.559217) (xy 39.494424 -190.515074) (xy 39.534573 -190.476365) (xy 39.579931 -190.443914)
			(xy 39.629531 -190.418413) (xy 39.682315 -190.400406) (xy 39.737158 -190.390276) (xy 39.792892 -190.388239)
			(xy 39.848329 -190.394339) (xy 39.902286 -190.408445) (xy 39.953615 -190.430257) (xy 40.001221 -190.459311)
			(xy 40.044089 -190.494986) (xy 40.081306 -190.536523) (xy 40.112079 -190.583036) (xy 40.135751 -190.633533)
			(xy 40.151819 -190.68694) (xy 40.159939 -190.742116) (xy 40.160448 -190.770002) (xy 40.159939 -190.797888)
			(xy 40.151819 -190.853064) (xy 40.135751 -190.906471) (xy 40.112079 -190.956968) (xy 40.081306 -191.003481)
			(xy 40.044089 -191.045018) (xy 40.001221 -191.080693) (xy 39.953615 -191.109747) (xy 39.902286 -191.131559)
			(xy 39.848329 -191.145665) (xy 39.792892 -191.151765) (xy 39.737158 -191.149728) (xy 39.682315 -191.139598)
			(xy 39.629531 -191.121591) (xy 39.579931 -191.09609) (xy 39.534573 -191.063639) (xy 39.494424 -191.02493)
			(xy 39.460338 -190.980787) (xy 39.433042 -190.932152) (xy 39.413119 -190.880061) (xy 39.400993 -190.825624)
			(xy 39.396922 -190.770002) (xy 36.065119 -190.770002) (xy 36.071366 -190.77387) (xy 36.140713 -190.826239)
			(xy 36.204933 -190.884783) (xy 36.263477 -190.949003) (xy 36.315846 -191.01835) (xy 36.361593 -191.092234)
			(xy 36.400327 -191.170023) (xy 36.431719 -191.251055) (xy 36.432448 -191.253618) (xy 83.836254 -191.253618)
			(xy 83.840325 -191.197996) (xy 83.852451 -191.143559) (xy 83.872374 -191.091468) (xy 83.89967 -191.042833)
			(xy 83.933756 -190.99869) (xy 83.973905 -190.959981) (xy 84.019263 -190.92753) (xy 84.068863 -190.902029)
			(xy 84.121647 -190.884022) (xy 84.17649 -190.873892) (xy 84.232224 -190.871855) (xy 84.287661 -190.877955)
			(xy 84.341618 -190.892061) (xy 84.392947 -190.913873) (xy 84.440553 -190.942927) (xy 84.483421 -190.978602)
			(xy 84.520638 -191.020139) (xy 84.551411 -191.066652) (xy 84.575083 -191.117149) (xy 84.591151 -191.170556)
			(xy 84.599271 -191.225732) (xy 84.599279 -191.226186) (xy 85.72703 -191.226186) (xy 85.731101 -191.170564)
			(xy 85.743227 -191.116127) (xy 85.76315 -191.064036) (xy 85.790446 -191.015401) (xy 85.824532 -190.971258)
			(xy 85.864681 -190.932549) (xy 85.910039 -190.900098) (xy 85.959639 -190.874597) (xy 86.012423 -190.85659)
			(xy 86.067266 -190.84646) (xy 86.123 -190.844423) (xy 86.178437 -190.850523) (xy 86.232394 -190.864629)
			(xy 86.283723 -190.886441) (xy 86.331329 -190.915495) (xy 86.374197 -190.95117) (xy 86.381648 -190.959486)
			(xy 87.021668 -190.959486) (xy 87.025739 -190.903864) (xy 87.037865 -190.849427) (xy 87.057788 -190.797336)
			(xy 87.085084 -190.748701) (xy 87.11917 -190.704558) (xy 87.159319 -190.665849) (xy 87.204677 -190.633398)
			(xy 87.254277 -190.607897) (xy 87.307061 -190.58989) (xy 87.361904 -190.57976) (xy 87.417638 -190.577723)
			(xy 87.473075 -190.583823) (xy 87.527032 -190.597929) (xy 87.578361 -190.619741) (xy 87.625967 -190.648795)
			(xy 87.668835 -190.68447) (xy 87.706052 -190.726007) (xy 87.736825 -190.77252) (xy 87.760497 -190.823017)
			(xy 87.776565 -190.876424) (xy 87.784685 -190.9316) (xy 87.785194 -190.959486) (xy 87.784685 -190.987372)
			(xy 87.776565 -191.042548) (xy 87.760497 -191.095955) (xy 87.736825 -191.146452) (xy 87.706052 -191.192965)
			(xy 87.668835 -191.234502) (xy 87.625967 -191.270177) (xy 87.578361 -191.299231) (xy 87.527032 -191.321043)
			(xy 87.473075 -191.335149) (xy 87.417638 -191.341249) (xy 87.361904 -191.339212) (xy 87.307061 -191.329082)
			(xy 87.254277 -191.311075) (xy 87.204677 -191.285574) (xy 87.159319 -191.253123) (xy 87.11917 -191.214414)
			(xy 87.085084 -191.170271) (xy 87.057788 -191.121636) (xy 87.037865 -191.069545) (xy 87.025739 -191.015108)
			(xy 87.021668 -190.959486) (xy 86.381648 -190.959486) (xy 86.411414 -190.992707) (xy 86.442187 -191.03922)
			(xy 86.465859 -191.089717) (xy 86.481927 -191.143124) (xy 86.490047 -191.1983) (xy 86.490556 -191.226186)
			(xy 86.490047 -191.254072) (xy 86.481927 -191.309248) (xy 86.465859 -191.362655) (xy 86.442187 -191.413152)
			(xy 86.411414 -191.459665) (xy 86.374197 -191.501202) (xy 86.331329 -191.536877) (xy 86.283723 -191.565931)
			(xy 86.232394 -191.587743) (xy 86.178437 -191.601849) (xy 86.123 -191.607949) (xy 86.067266 -191.605912)
			(xy 86.012423 -191.595782) (xy 85.959639 -191.577775) (xy 85.910039 -191.552274) (xy 85.864681 -191.519823)
			(xy 85.824532 -191.481114) (xy 85.790446 -191.436971) (xy 85.76315 -191.388336) (xy 85.743227 -191.336245)
			(xy 85.731101 -191.281808) (xy 85.72703 -191.226186) (xy 84.599279 -191.226186) (xy 84.59978 -191.253618)
			(xy 84.599271 -191.281504) (xy 84.591151 -191.33668) (xy 84.575083 -191.390087) (xy 84.551411 -191.440584)
			(xy 84.520638 -191.487097) (xy 84.483421 -191.528634) (xy 84.440553 -191.564309) (xy 84.392947 -191.593363)
			(xy 84.341618 -191.615175) (xy 84.287661 -191.629281) (xy 84.232224 -191.635381) (xy 84.17649 -191.633344)
			(xy 84.121647 -191.623214) (xy 84.068863 -191.605207) (xy 84.019263 -191.579706) (xy 83.973905 -191.547255)
			(xy 83.933756 -191.508546) (xy 83.89967 -191.464403) (xy 83.872374 -191.415768) (xy 83.852451 -191.363677)
			(xy 83.840325 -191.30924) (xy 83.836254 -191.253618) (xy 36.432448 -191.253618) (xy 36.4555 -191.334637)
			(xy 36.471468 -191.420057) (xy 36.479486 -191.506586) (xy 36.479988 -191.550036) (xy 36.479486 -191.593486)
			(xy 36.471468 -191.680015) (xy 36.465006 -191.714583) (xy 59.057077 -191.714583) (xy 59.060968 -191.660225)
			(xy 59.072555 -191.606974) (xy 59.091604 -191.555914) (xy 59.117726 -191.508086) (xy 59.150389 -191.464462)
			(xy 59.188929 -191.425931) (xy 59.232561 -191.393278) (xy 59.280395 -191.367167) (xy 59.331459 -191.34813)
			(xy 59.384713 -191.336555) (xy 59.439072 -191.332677) (xy 59.49343 -191.336576) (xy 59.546679 -191.348171)
			(xy 59.597736 -191.367227) (xy 59.645561 -191.393356) (xy 59.667648 -191.40932) (xy 59.68666 -191.422916)
			(xy 59.728543 -191.443648) (xy 59.773511 -191.456374) (xy 59.820048 -191.460664) (xy 59.866585 -191.456374)
			(xy 59.911553 -191.443648) (xy 59.953436 -191.422916) (xy 59.972448 -191.40932) (xy 59.994509 -191.393326)
			(xy 60.042333 -191.36721) (xy 60.093387 -191.348165) (xy 60.146631 -191.33658) (xy 60.200982 -191.33269)
			(xy 60.255334 -191.336575) (xy 60.30858 -191.348155) (xy 60.359635 -191.367195) (xy 60.407462 -191.393307)
			(xy 60.451085 -191.42596) (xy 60.489617 -191.464489) (xy 60.522274 -191.508109) (xy 60.548391 -191.555933)
			(xy 60.567435 -191.606987) (xy 60.57902 -191.660232) (xy 60.58291 -191.714583) (xy 61.588994 -191.714583)
			(xy 61.592884 -191.660229) (xy 61.604471 -191.606982) (xy 61.623517 -191.555925) (xy 61.649637 -191.5081)
			(xy 61.682297 -191.464478) (xy 61.720834 -191.42595) (xy 61.764461 -191.393298) (xy 61.812292 -191.367187)
			(xy 61.863352 -191.34815) (xy 61.916601 -191.336574) (xy 61.970956 -191.332694) (xy 62.02531 -191.33659)
			(xy 62.078556 -191.348182) (xy 62.12961 -191.367234) (xy 62.177433 -191.393358) (xy 62.19952 -191.40932)
			(xy 62.218532 -191.422916) (xy 62.260415 -191.443648) (xy 62.305383 -191.456374) (xy 62.35192 -191.460664)
			(xy 62.398457 -191.456374) (xy 62.443425 -191.443648) (xy 62.485308 -191.422916) (xy 62.50432 -191.40932)
			(xy 62.526381 -191.393324) (xy 62.574207 -191.367203) (xy 62.625264 -191.348154) (xy 62.678511 -191.336565)
			(xy 62.732867 -191.332673) (xy 62.787222 -191.336556) (xy 62.840472 -191.348135) (xy 62.891532 -191.367175)
			(xy 62.939362 -191.393288) (xy 62.982989 -191.425942) (xy 63.021525 -191.464473) (xy 63.054185 -191.508095)
			(xy 63.080304 -191.555922) (xy 63.099351 -191.60698) (xy 63.110937 -191.660228) (xy 63.114827 -191.714583)
			(xy 64.393386 -191.714583) (xy 64.397276 -191.660227) (xy 64.408863 -191.606978) (xy 64.427911 -191.55592)
			(xy 64.454031 -191.508093) (xy 64.486693 -191.46447) (xy 64.525231 -191.42594) (xy 64.568861 -191.393288)
			(xy 64.616694 -191.367177) (xy 64.667756 -191.34814) (xy 64.721007 -191.336564) (xy 64.775364 -191.332686)
			(xy 64.82972 -191.336583) (xy 64.882968 -191.348176) (xy 64.934023 -191.36723) (xy 64.981847 -191.393357)
			(xy 65.003934 -191.40932) (xy 65.022946 -191.422916) (xy 65.064829 -191.443648) (xy 65.109797 -191.456374)
			(xy 65.156334 -191.460664) (xy 65.202871 -191.456374) (xy 65.247839 -191.443648) (xy 65.289722 -191.422916)
			(xy 65.308734 -191.40932) (xy 65.330795 -191.393325) (xy 65.37862 -191.367206) (xy 65.429675 -191.348159)
			(xy 65.482921 -191.336573) (xy 65.537274 -191.332681) (xy 65.591628 -191.336565) (xy 65.644876 -191.348145)
			(xy 65.695934 -191.367185) (xy 65.743762 -191.393298) (xy 65.787387 -191.425951) (xy 65.825921 -191.464481)
			(xy 65.85858 -191.508102) (xy 65.884697 -191.555928) (xy 65.903743 -191.606983) (xy 65.915329 -191.66023)
			(xy 65.919219 -191.714583) (xy 65.915333 -191.768937) (xy 65.903752 -191.822184) (xy 65.884711 -191.873242)
			(xy 65.858598 -191.921069) (xy 65.825943 -191.964694) (xy 65.787413 -192.003227) (xy 65.74379 -192.035884)
			(xy 65.695964 -192.062001) (xy 65.644908 -192.081045) (xy 65.591661 -192.09263) (xy 65.537308 -192.096519)
			(xy 65.482955 -192.092632) (xy 65.429707 -192.08105) (xy 65.378651 -192.062008) (xy 65.330823 -192.035893)
			(xy 65.308734 -192.019936) (xy 65.289722 -192.00634) (xy 65.247839 -191.985608) (xy 65.202871 -191.972882)
			(xy 65.156334 -191.968592) (xy 65.109797 -191.972882) (xy 65.064829 -191.985608) (xy 65.022946 -192.00634)
			(xy 65.003934 -192.019936) (xy 64.981819 -192.035861) (xy 64.933993 -192.061984) (xy 64.882935 -192.081033)
			(xy 64.829687 -192.092622) (xy 64.775331 -192.096514) (xy 64.720974 -192.092631) (xy 64.667723 -192.08105)
			(xy 64.616663 -192.062009) (xy 64.568833 -192.035894) (xy 64.525206 -192.003238) (xy 64.486671 -191.964704)
			(xy 64.454013 -191.921079) (xy 64.427897 -191.873249) (xy 64.408853 -191.82219) (xy 64.397271 -191.76894)
			(xy 64.393386 -191.714583) (xy 63.114827 -191.714583) (xy 63.110942 -191.768939) (xy 63.09936 -191.822188)
			(xy 63.080318 -191.873247) (xy 63.054203 -191.921076) (xy 63.021547 -191.964702) (xy 62.983015 -192.003236)
			(xy 62.939391 -192.035894) (xy 62.891562 -192.062011) (xy 62.840504 -192.081055) (xy 62.787256 -192.092639)
			(xy 62.7329 -192.096527) (xy 62.678545 -192.092639) (xy 62.625296 -192.081055) (xy 62.574238 -192.062011)
			(xy 62.52641 -192.035894) (xy 62.50432 -192.019936) (xy 62.485308 -192.00634) (xy 62.443425 -191.985608)
			(xy 62.398457 -191.972882) (xy 62.35192 -191.968592) (xy 62.305383 -191.972882) (xy 62.260415 -191.985608)
			(xy 62.218532 -192.00634) (xy 62.19952 -192.019936) (xy 62.177405 -192.03586) (xy 62.12958 -192.06198)
			(xy 62.078524 -192.081028) (xy 62.025277 -192.092615) (xy 61.970923 -192.096506) (xy 61.916568 -192.092622)
			(xy 61.863319 -192.081041) (xy 61.812261 -192.061999) (xy 61.764433 -192.035884) (xy 61.720808 -192.003228)
			(xy 61.682275 -191.964696) (xy 61.649619 -191.921072) (xy 61.623503 -191.873244) (xy 61.604461 -191.822186)
			(xy 61.592879 -191.768938) (xy 61.588994 -191.714583) (xy 60.58291 -191.714583) (xy 60.579025 -191.768935)
			(xy 60.567445 -191.822181) (xy 60.548405 -191.873236) (xy 60.522292 -191.921062) (xy 60.489639 -191.964686)
			(xy 60.45111 -192.003218) (xy 60.40749 -192.035874) (xy 60.359666 -192.061991) (xy 60.308612 -192.081036)
			(xy 60.255367 -192.092621) (xy 60.201016 -192.09651) (xy 60.146664 -192.092625) (xy 60.093419 -192.081045)
			(xy 60.042363 -192.062004) (xy 59.994537 -192.035892) (xy 59.972448 -192.019936) (xy 59.953436 -192.00634)
			(xy 59.911553 -191.985608) (xy 59.866585 -191.972882) (xy 59.820048 -191.968592) (xy 59.773511 -191.972882)
			(xy 59.728543 -191.985608) (xy 59.68666 -192.00634) (xy 59.667648 -192.019936) (xy 59.645532 -192.035862)
			(xy 59.597705 -192.061987) (xy 59.546647 -192.081039) (xy 59.493396 -192.092629) (xy 59.439039 -192.096523)
			(xy 59.38468 -192.09264) (xy 59.331427 -192.08106) (xy 59.280365 -192.062019) (xy 59.232532 -192.035904)
			(xy 59.188904 -192.003247) (xy 59.150367 -191.964713) (xy 59.117708 -191.921086) (xy 59.09159 -191.873255)
			(xy 59.072546 -191.822194) (xy 59.060963 -191.768942) (xy 59.057077 -191.714583) (xy 36.465006 -191.714583)
			(xy 36.4555 -191.765435) (xy 36.431719 -191.849017) (xy 36.400327 -191.930049) (xy 36.361593 -192.007838)
			(xy 36.315846 -192.081722) (xy 36.263477 -192.151069) (xy 36.204933 -192.215289) (xy 36.140713 -192.273833)
			(xy 36.071366 -192.326202) (xy 35.997482 -192.371949) (xy 35.919693 -192.410683) (xy 35.838661 -192.442075)
			(xy 35.755079 -192.465856) (xy 35.669659 -192.481824) (xy 35.58313 -192.489842) (xy 35.49623 -192.489842)
			(xy 35.409701 -192.481824) (xy 35.324281 -192.465856) (xy 35.240699 -192.442075) (xy 35.159667 -192.410683)
			(xy 35.081878 -192.371949) (xy 35.007994 -192.326202) (xy 34.938647 -192.273833) (xy 34.874427 -192.215289)
			(xy 34.815883 -192.151069) (xy 34.763514 -192.081722) (xy 34.717767 -192.007838) (xy 34.679033 -191.930049)
			(xy 34.647641 -191.849017) (xy 34.62386 -191.765435) (xy 34.607892 -191.680015) (xy 34.599874 -191.593486)
			(xy 31.399486 -191.593486) (xy 31.391468 -191.680015) (xy 31.3755 -191.765435) (xy 31.351719 -191.849017)
			(xy 31.320327 -191.930049) (xy 31.281593 -192.007838) (xy 31.235846 -192.081722) (xy 31.183477 -192.151069)
			(xy 31.124933 -192.215289) (xy 31.060713 -192.273833) (xy 30.991366 -192.326202) (xy 30.917482 -192.371949)
			(xy 30.839693 -192.410683) (xy 30.758661 -192.442075) (xy 30.675079 -192.465856) (xy 30.589659 -192.481824)
			(xy 30.50313 -192.489842) (xy 30.41623 -192.489842) (xy 30.329701 -192.481824) (xy 30.244281 -192.465856)
			(xy 30.160699 -192.442075) (xy 30.079667 -192.410683) (xy 30.001878 -192.371949) (xy 29.927994 -192.326202)
			(xy 29.858647 -192.273833) (xy 29.794427 -192.215289) (xy 29.735883 -192.151069) (xy 29.683514 -192.081722)
			(xy 29.637767 -192.007838) (xy 29.599033 -191.930049) (xy 29.567641 -191.849017) (xy 29.54386 -191.765435)
			(xy 29.527892 -191.680015) (xy 29.519874 -191.593486) (xy 28.090876 -191.593486) (xy 28.090876 -191.915796)
			(xy 27.469592 -192.53708) (xy 82.809078 -192.53708) (xy 82.813149 -192.481458) (xy 82.825275 -192.427021)
			(xy 82.845198 -192.37493) (xy 82.872494 -192.326295) (xy 82.90658 -192.282152) (xy 82.946729 -192.243443)
			(xy 82.992087 -192.210992) (xy 83.041687 -192.185491) (xy 83.094471 -192.167484) (xy 83.149314 -192.157354)
			(xy 83.205048 -192.155317) (xy 83.260485 -192.161417) (xy 83.314442 -192.175523) (xy 83.365771 -192.197335)
			(xy 83.413377 -192.226389) (xy 83.456245 -192.262064) (xy 83.493462 -192.303601) (xy 83.524235 -192.350114)
			(xy 83.547907 -192.400611) (xy 83.563975 -192.454018) (xy 83.572095 -192.509194) (xy 83.572604 -192.53708)
			(xy 83.572095 -192.564966) (xy 83.563975 -192.620142) (xy 83.547907 -192.673549) (xy 83.544249 -192.681352)
			(xy 84.456522 -192.681352) (xy 84.460593 -192.62573) (xy 84.472719 -192.571293) (xy 84.492642 -192.519202)
			(xy 84.519938 -192.470567) (xy 84.554024 -192.426424) (xy 84.594173 -192.387715) (xy 84.639531 -192.355264)
			(xy 84.689131 -192.329763) (xy 84.741915 -192.311756) (xy 84.796758 -192.301626) (xy 84.852492 -192.299589)
			(xy 84.907929 -192.305689) (xy 84.961886 -192.319795) (xy 85.013215 -192.341607) (xy 85.060821 -192.370661)
			(xy 85.103689 -192.406336) (xy 85.140906 -192.447873) (xy 85.171679 -192.494386) (xy 85.195351 -192.544883)
			(xy 85.211419 -192.59829) (xy 85.219539 -192.653466) (xy 85.220048 -192.681352) (xy 85.219539 -192.709238)
			(xy 85.211419 -192.764414) (xy 85.195351 -192.817821) (xy 85.171679 -192.868318) (xy 85.140906 -192.914831)
			(xy 85.103689 -192.956368) (xy 85.060821 -192.992043) (xy 85.013215 -193.021097) (xy 84.961886 -193.042909)
			(xy 84.907929 -193.057015) (xy 84.852492 -193.063115) (xy 84.796758 -193.061078) (xy 84.741915 -193.050948)
			(xy 84.689131 -193.032941) (xy 84.639531 -193.00744) (xy 84.594173 -192.974989) (xy 84.554024 -192.93628)
			(xy 84.519938 -192.892137) (xy 84.492642 -192.843502) (xy 84.472719 -192.791411) (xy 84.460593 -192.736974)
			(xy 84.456522 -192.681352) (xy 83.544249 -192.681352) (xy 83.524235 -192.724046) (xy 83.493462 -192.770559)
			(xy 83.456245 -192.812096) (xy 83.413377 -192.847771) (xy 83.365771 -192.876825) (xy 83.314442 -192.898637)
			(xy 83.260485 -192.912743) (xy 83.205048 -192.918843) (xy 83.149314 -192.916806) (xy 83.094471 -192.906676)
			(xy 83.041687 -192.888669) (xy 82.992087 -192.863168) (xy 82.946729 -192.830717) (xy 82.90658 -192.792008)
			(xy 82.872494 -192.747865) (xy 82.845198 -192.69923) (xy 82.825275 -192.647139) (xy 82.813149 -192.592702)
			(xy 82.809078 -192.53708) (xy 27.469592 -192.53708) (xy 26.931112 -193.07556) (xy 26.931112 -195.388622)
			(xy 28.177725 -195.388622) (xy 28.177725 -195.325358) (xy 28.185983 -195.262634) (xy 28.202357 -195.201525)
			(xy 28.226568 -195.143076) (xy 28.2582 -195.088287) (xy 28.296714 -195.038096) (xy 28.341449 -194.993361)
			(xy 28.39164 -194.954848) (xy 28.446429 -194.923216) (xy 28.504879 -194.899006) (xy 28.565988 -194.882632)
			(xy 28.628712 -194.874375) (xy 28.660344 -194.87388) (xy 29.389324 -194.87388) (xy 29.41277 -194.873352)
			(xy 29.458864 -194.864727) (xy 29.502593 -194.847793) (xy 29.542473 -194.823125) (xy 29.577152 -194.79156)
			(xy 29.605452 -194.754169) (xy 29.626413 -194.712222) (xy 29.639323 -194.667141) (xy 29.643745 -194.620456)
			(xy 29.639527 -194.573753) (xy 29.626814 -194.528616) (xy 29.616908 -194.507358) (xy 29.598093 -194.468236)
			(xy 29.566902 -194.387215) (xy 29.543312 -194.303665) (xy 29.527523 -194.218296) (xy 29.519669 -194.131835)
			(xy 29.519818 -194.045018) (xy 29.527968 -193.958584) (xy 29.544049 -193.873269) (xy 29.567925 -193.7898)
			(xy 29.599393 -193.708887) (xy 29.638185 -193.631218) (xy 29.68397 -193.557456) (xy 29.736359 -193.488227)
			(xy 29.794905 -193.424122) (xy 29.859111 -193.365685) (xy 29.928429 -193.313415) (xy 30.00227 -193.267756)
			(xy 30.080005 -193.229098) (xy 30.160972 -193.197769) (xy 30.244482 -193.174035) (xy 30.329824 -193.1581)
			(xy 30.416271 -193.150098) (xy 30.503089 -193.150098) (xy 30.589536 -193.1581) (xy 30.674878 -193.174035)
			(xy 30.758388 -193.197769) (xy 30.839355 -193.229098) (xy 30.91709 -193.267756) (xy 30.990931 -193.313415)
			(xy 31.060249 -193.365685) (xy 31.124455 -193.424122) (xy 31.183001 -193.488227) (xy 31.23539 -193.557456)
			(xy 31.281175 -193.631218) (xy 31.319967 -193.708887) (xy 31.351435 -193.7898) (xy 31.375311 -193.873269)
			(xy 31.391392 -193.958584) (xy 31.399542 -194.045018) (xy 31.399691 -194.131835) (xy 31.399541 -194.133486)
			(xy 34.599874 -194.133486) (xy 34.599874 -194.046586) (xy 34.607892 -193.960057) (xy 34.62386 -193.874637)
			(xy 34.647641 -193.791055) (xy 34.679033 -193.710023) (xy 34.717767 -193.632234) (xy 34.763514 -193.55835)
			(xy 34.815883 -193.489003) (xy 34.874427 -193.424783) (xy 34.938647 -193.366239) (xy 35.007994 -193.31387)
			(xy 35.081878 -193.268123) (xy 35.159667 -193.229389) (xy 35.240699 -193.197997) (xy 35.324281 -193.174216)
			(xy 35.409701 -193.158248) (xy 35.49623 -193.15023) (xy 35.58313 -193.15023) (xy 35.669659 -193.158248)
			(xy 35.755079 -193.174216) (xy 35.838661 -193.197997) (xy 35.919693 -193.229389) (xy 35.997482 -193.268123)
			(xy 36.071366 -193.31387) (xy 36.140713 -193.366239) (xy 36.204933 -193.424783) (xy 36.263477 -193.489003)
			(xy 36.315846 -193.55835) (xy 36.361593 -193.632234) (xy 36.384121 -193.677476) (xy 59.057087 -193.677476)
			(xy 59.060978 -193.623119) (xy 59.072566 -193.56987) (xy 59.091616 -193.518812) (xy 59.117738 -193.470985)
			(xy 59.150401 -193.427363) (xy 59.188941 -193.388834) (xy 59.232572 -193.356182) (xy 59.280406 -193.330073)
			(xy 59.331469 -193.311037) (xy 59.384722 -193.299463) (xy 59.439079 -193.295587) (xy 59.493435 -193.299486)
			(xy 59.546683 -193.311082) (xy 59.597738 -193.330139) (xy 59.645562 -193.356268) (xy 59.667648 -193.372232)
			(xy 59.68666 -193.385828) (xy 59.728543 -193.40656) (xy 59.773511 -193.419286) (xy 59.820048 -193.423576)
			(xy 59.866585 -193.419286) (xy 59.911553 -193.40656) (xy 59.953436 -193.385828) (xy 59.972448 -193.372232)
			(xy 59.994498 -193.356222) (xy 60.042322 -193.330104) (xy 60.093377 -193.311058) (xy 60.146623 -193.299471)
			(xy 60.200975 -193.29558) (xy 60.255328 -193.299464) (xy 60.308576 -193.311044) (xy 60.359633 -193.330083)
			(xy 60.407461 -193.356195) (xy 60.451086 -193.388848) (xy 60.48962 -193.427377) (xy 60.522278 -193.470998)
			(xy 60.548396 -193.518823) (xy 60.567443 -193.569878) (xy 60.579029 -193.623123) (xy 60.58292 -193.677476)
			(xy 61.589004 -193.677476) (xy 61.592895 -193.623123) (xy 61.604482 -193.569877) (xy 61.623529 -193.518823)
			(xy 61.649649 -193.470999) (xy 61.682309 -193.427379) (xy 61.720845 -193.388852) (xy 61.764472 -193.356202)
			(xy 61.812302 -193.330093) (xy 61.863361 -193.311057) (xy 61.91661 -193.299482) (xy 61.970963 -193.295604)
			(xy 62.025316 -193.2995) (xy 62.07856 -193.311093) (xy 62.129613 -193.330146) (xy 62.177434 -193.35627)
			(xy 62.19952 -193.372232) (xy 62.218532 -193.385828) (xy 62.260415 -193.40656) (xy 62.305383 -193.419286)
			(xy 62.35192 -193.423576) (xy 62.398457 -193.419286) (xy 62.443425 -193.40656) (xy 62.485308 -193.385828)
			(xy 62.50432 -193.372232) (xy 62.52637 -193.35622) (xy 62.574197 -193.330097) (xy 62.625254 -193.311047)
			(xy 62.678503 -193.299457) (xy 62.732859 -193.295563) (xy 62.787216 -193.299445) (xy 62.840468 -193.311024)
			(xy 62.891529 -193.330063) (xy 62.939361 -193.356176) (xy 62.98299 -193.38883) (xy 63.021528 -193.427361)
			(xy 63.054189 -193.470984) (xy 63.08031 -193.518812) (xy 63.099358 -193.56987) (xy 63.110945 -193.623119)
			(xy 63.114837 -193.677476) (xy 64.393395 -193.677476) (xy 64.397286 -193.623121) (xy 64.408874 -193.569874)
			(xy 64.427922 -193.518817) (xy 64.454043 -193.470992) (xy 64.486705 -193.427371) (xy 64.525243 -193.388843)
			(xy 64.568872 -193.356192) (xy 64.616704 -193.330083) (xy 64.667765 -193.311047) (xy 64.721016 -193.299473)
			(xy 64.775371 -193.295595) (xy 64.829726 -193.299493) (xy 64.882972 -193.311087) (xy 64.934026 -193.330142)
			(xy 64.981848 -193.356269) (xy 65.003934 -193.372232) (xy 65.022946 -193.385828) (xy 65.064829 -193.40656)
			(xy 65.109797 -193.419286) (xy 65.156334 -193.423576) (xy 65.202871 -193.419286) (xy 65.247839 -193.40656)
			(xy 65.289722 -193.385828) (xy 65.308734 -193.372232) (xy 65.330784 -193.356221) (xy 65.378609 -193.3301)
			(xy 65.429665 -193.311052) (xy 65.482913 -193.299464) (xy 65.537267 -193.295572) (xy 65.591622 -193.299455)
			(xy 65.644872 -193.311034) (xy 65.695931 -193.330073) (xy 65.743761 -193.356186) (xy 65.787388 -193.388839)
			(xy 65.825924 -193.427369) (xy 65.858584 -193.470991) (xy 65.884703 -193.518817) (xy 65.90375 -193.569874)
			(xy 65.915337 -193.623121) (xy 65.919228 -193.677476) (xy 65.915902 -193.724022) (xy 83.269326 -193.724022)
			(xy 83.273397 -193.6684) (xy 83.285523 -193.613963) (xy 83.305446 -193.561872) (xy 83.332742 -193.513237)
			(xy 83.366828 -193.469094) (xy 83.406977 -193.430385) (xy 83.452335 -193.397934) (xy 83.501935 -193.372433)
			(xy 83.554719 -193.354426) (xy 83.609562 -193.344296) (xy 83.665296 -193.342259) (xy 83.720733 -193.348359)
			(xy 83.77469 -193.362465) (xy 83.826019 -193.384277) (xy 83.873625 -193.413331) (xy 83.916493 -193.449006)
			(xy 83.95371 -193.490543) (xy 83.984483 -193.537056) (xy 84.008155 -193.587553) (xy 84.024223 -193.64096)
			(xy 84.032343 -193.696136) (xy 84.032852 -193.724022) (xy 84.032343 -193.751908) (xy 84.024223 -193.807084)
			(xy 84.008155 -193.860491) (xy 83.984483 -193.910988) (xy 83.95371 -193.957501) (xy 83.916493 -193.999038)
			(xy 83.873625 -194.034713) (xy 83.826019 -194.063767) (xy 83.77469 -194.085579) (xy 83.720733 -194.099685)
			(xy 83.665296 -194.105785) (xy 83.609562 -194.103748) (xy 83.554719 -194.093618) (xy 83.501935 -194.075611)
			(xy 83.452335 -194.05011) (xy 83.406977 -194.017659) (xy 83.366828 -193.97895) (xy 83.332742 -193.934807)
			(xy 83.305446 -193.886172) (xy 83.285523 -193.834081) (xy 83.273397 -193.779644) (xy 83.269326 -193.724022)
			(xy 65.915902 -193.724022) (xy 65.915344 -193.731831) (xy 65.903764 -193.78508) (xy 65.884723 -193.836139)
			(xy 65.85861 -193.883968) (xy 65.825955 -193.927595) (xy 65.787424 -193.966129) (xy 65.743801 -193.998788)
			(xy 65.695975 -194.024907) (xy 65.644918 -194.043953) (xy 65.59167 -194.055538) (xy 65.537315 -194.059428)
			(xy 65.48296 -194.055543) (xy 65.429712 -194.043961) (xy 65.378653 -194.024919) (xy 65.330824 -193.998805)
			(xy 65.308734 -193.982848) (xy 65.289722 -193.969252) (xy 65.247839 -193.94852) (xy 65.202871 -193.935794)
			(xy 65.156334 -193.931504) (xy 65.109797 -193.935794) (xy 65.064829 -193.94852) (xy 65.022946 -193.969252)
			(xy 65.003934 -193.982848) (xy 64.981808 -193.998757) (xy 64.933982 -194.024878) (xy 64.882926 -194.043926)
			(xy 64.829678 -194.055514) (xy 64.775323 -194.059405) (xy 64.720968 -194.05552) (xy 64.667719 -194.043939)
			(xy 64.61666 -194.024897) (xy 64.568832 -193.998782) (xy 64.525207 -193.966126) (xy 64.486674 -193.927593)
			(xy 64.454018 -193.883968) (xy 64.427902 -193.836139) (xy 64.408861 -193.78508) (xy 64.39728 -193.731831)
			(xy 64.393395 -193.677476) (xy 63.114837 -193.677476) (xy 63.110952 -193.731833) (xy 63.099371 -193.785084)
			(xy 63.08033 -193.836144) (xy 63.054215 -193.883975) (xy 63.021559 -193.927603) (xy 62.983027 -193.966139)
			(xy 62.939402 -193.998798) (xy 62.891573 -194.024917) (xy 62.840514 -194.043963) (xy 62.787264 -194.055548)
			(xy 62.732907 -194.059437) (xy 62.678551 -194.05555) (xy 62.6253 -194.043967) (xy 62.57424 -194.024923)
			(xy 62.526411 -193.998806) (xy 62.50432 -193.982848) (xy 62.485308 -193.969252) (xy 62.443425 -193.94852)
			(xy 62.398457 -193.935794) (xy 62.35192 -193.931504) (xy 62.305383 -193.935794) (xy 62.260415 -193.94852)
			(xy 62.218532 -193.969252) (xy 62.19952 -193.982848) (xy 62.177394 -193.998756) (xy 62.129569 -194.024874)
			(xy 62.078514 -194.043921) (xy 62.025268 -194.055507) (xy 61.970915 -194.059396) (xy 61.916562 -194.055511)
			(xy 61.863315 -194.043929) (xy 61.812259 -194.024887) (xy 61.764432 -193.998772) (xy 61.720809 -193.966116)
			(xy 61.682278 -193.927584) (xy 61.649623 -193.883961) (xy 61.623509 -193.836133) (xy 61.604468 -193.785077)
			(xy 61.592888 -193.731829) (xy 61.589004 -193.677476) (xy 60.58292 -193.677476) (xy 60.579036 -193.731829)
			(xy 60.567456 -193.785076) (xy 60.548416 -193.836134) (xy 60.522304 -193.883961) (xy 60.489651 -193.927586)
			(xy 60.451122 -193.96612) (xy 60.407501 -193.998779) (xy 60.359677 -194.024897) (xy 60.308622 -194.043943)
			(xy 60.255376 -194.055529) (xy 60.201023 -194.05942) (xy 60.14667 -194.055536) (xy 60.093423 -194.043956)
			(xy 60.042366 -194.024916) (xy 59.994538 -193.998804) (xy 59.972448 -193.982848) (xy 59.953436 -193.969252)
			(xy 59.911553 -193.94852) (xy 59.866585 -193.935794) (xy 59.820048 -193.931504) (xy 59.773511 -193.935794)
			(xy 59.728543 -193.94852) (xy 59.68666 -193.969252) (xy 59.667648 -193.982848) (xy 59.645521 -193.998758)
			(xy 59.597695 -194.024881) (xy 59.546637 -194.043931) (xy 59.493388 -194.055521) (xy 59.439031 -194.059413)
			(xy 59.384674 -194.05553) (xy 59.331423 -194.043949) (xy 59.280362 -194.024907) (xy 59.232532 -193.998792)
			(xy 59.188905 -193.966135) (xy 59.15037 -193.927601) (xy 59.117712 -193.883975) (xy 59.091596 -193.836144)
			(xy 59.072553 -193.785084) (xy 59.060971 -193.731833) (xy 59.057087 -193.677476) (xy 36.384121 -193.677476)
			(xy 36.400327 -193.710023) (xy 36.431719 -193.791055) (xy 36.4555 -193.874637) (xy 36.471468 -193.960057)
			(xy 36.479486 -194.046586) (xy 36.479988 -194.090036) (xy 36.479486 -194.133486) (xy 36.471468 -194.220015)
			(xy 36.4555 -194.305435) (xy 36.431719 -194.389017) (xy 36.400327 -194.470049) (xy 36.361593 -194.547838)
			(xy 36.315846 -194.621722) (xy 36.263477 -194.691069) (xy 36.204933 -194.755289) (xy 36.140713 -194.813833)
			(xy 36.071366 -194.866202) (xy 35.997482 -194.911949) (xy 35.919693 -194.950683) (xy 35.838661 -194.982075)
			(xy 35.755079 -195.005856) (xy 35.669659 -195.021824) (xy 35.58313 -195.029842) (xy 35.49623 -195.029842)
			(xy 35.409701 -195.021824) (xy 35.324281 -195.005856) (xy 35.240699 -194.982075) (xy 35.159667 -194.950683)
			(xy 35.081878 -194.911949) (xy 35.007994 -194.866202) (xy 34.938647 -194.813833) (xy 34.874427 -194.755289)
			(xy 34.815883 -194.691069) (xy 34.763514 -194.621722) (xy 34.717767 -194.547838) (xy 34.679033 -194.470049)
			(xy 34.647641 -194.389017) (xy 34.62386 -194.305435) (xy 34.607892 -194.220015) (xy 34.599874 -194.133486)
			(xy 31.399541 -194.133486) (xy 31.391837 -194.218296) (xy 31.376048 -194.303665) (xy 31.352458 -194.387215)
			(xy 31.321267 -194.468236) (xy 31.302452 -194.507358) (xy 31.292551 -194.528623) (xy 31.279813 -194.57376)
			(xy 31.275576 -194.620468) (xy 31.279985 -194.66716) (xy 31.292889 -194.71225) (xy 31.313851 -194.754205)
			(xy 31.342157 -194.7916) (xy 31.376846 -194.823164) (xy 31.41674 -194.847824) (xy 31.460482 -194.864742)
			(xy 31.506586 -194.873344) (xy 31.530036 -194.87388) (xy 32.616902 -194.87388) (xy 34.214562 -196.471794)
			(xy 34.230336 -196.48701) (xy 34.266188 -196.512218) (xy 34.305833 -196.530902) (xy 34.348096 -196.542506)
			(xy 34.391723 -196.546688) (xy 34.43542 -196.543322) (xy 34.477892 -196.532509) (xy 34.517879 -196.51457)
			(xy 34.554196 -196.490036) (xy 34.585764 -196.459635) (xy 34.611649 -196.424268) (xy 34.631082 -196.384985)
			(xy 34.637726 -196.364098) (xy 34.650401 -196.3229) (xy 34.682272 -196.242806) (xy 34.72134 -196.165965)
			(xy 34.767277 -196.093022) (xy 34.819697 -196.02459) (xy 34.878161 -195.961244) (xy 34.942177 -195.903514)
			(xy 35.011208 -195.851886) (xy 35.084676 -195.806793) (xy 35.161962 -195.768613) (xy 35.242418 -195.737667)
			(xy 35.325368 -195.714216) (xy 35.410118 -195.698455) (xy 35.495953 -195.690517) (xy 35.582156 -195.690469)
			(xy 35.668 -195.698311) (xy 35.752767 -195.713977) (xy 35.835744 -195.737336) (xy 35.916235 -195.768191)
			(xy 35.993563 -195.806284) (xy 36.017553 -195.820972) (xy 59.057092 -195.820972) (xy 59.060983 -195.766616)
			(xy 59.072572 -195.713368) (xy 59.091622 -195.662311) (xy 59.117744 -195.614485) (xy 59.150407 -195.570863)
			(xy 59.188947 -195.532335) (xy 59.232578 -195.499684) (xy 59.280411 -195.473576) (xy 59.331474 -195.454541)
			(xy 59.384726 -195.442968) (xy 59.439083 -195.439092) (xy 59.493438 -195.442991) (xy 59.546685 -195.454588)
			(xy 59.59774 -195.473645) (xy 59.645562 -195.499774) (xy 59.667648 -195.515738) (xy 59.68666 -195.529334)
			(xy 59.728543 -195.550066) (xy 59.773511 -195.562792) (xy 59.820048 -195.567082) (xy 59.866585 -195.562792)
			(xy 59.911553 -195.550066) (xy 59.953436 -195.529334) (xy 59.972448 -195.515738) (xy 59.994492 -195.49972)
			(xy 60.042317 -195.473601) (xy 60.093372 -195.454554) (xy 60.146618 -195.442967) (xy 60.200972 -195.439075)
			(xy 60.255326 -195.442959) (xy 60.308574 -195.454538) (xy 60.359632 -195.473577) (xy 60.40746 -195.499689)
			(xy 60.451086 -195.532342) (xy 60.489621 -195.570871) (xy 60.52228 -195.614493) (xy 60.548399 -195.662318)
			(xy 60.567446 -195.713373) (xy 60.579033 -195.766619) (xy 60.582925 -195.820972) (xy 61.589008 -195.820972)
			(xy 61.5929 -195.76662) (xy 61.604487 -195.713375) (xy 61.623535 -195.662322) (xy 61.649655 -195.614498)
			(xy 61.682315 -195.57088) (xy 61.720851 -195.532353) (xy 61.764478 -195.499704) (xy 61.812308 -195.473596)
			(xy 61.863366 -195.454561) (xy 61.916614 -195.442986) (xy 61.970967 -195.439108) (xy 62.025319 -195.443005)
			(xy 62.078563 -195.454599) (xy 62.129614 -195.473651) (xy 62.177435 -195.499776) (xy 62.19952 -195.515738)
			(xy 62.218532 -195.529334) (xy 62.260415 -195.550066) (xy 62.305383 -195.562792) (xy 62.35192 -195.567082)
			(xy 62.398457 -195.562792) (xy 62.443425 -195.550066) (xy 62.485308 -195.529334) (xy 62.50432 -195.515738)
			(xy 62.526365 -195.499718) (xy 62.574191 -195.473594) (xy 62.625249 -195.454543) (xy 62.678499 -195.442953)
			(xy 62.732856 -195.439059) (xy 62.787214 -195.44294) (xy 62.840466 -195.454518) (xy 62.891528 -195.473557)
			(xy 62.939361 -195.49967) (xy 62.982991 -195.532324) (xy 63.021529 -195.570855) (xy 63.054191 -195.614479)
			(xy 63.080313 -195.662307) (xy 63.099361 -195.713365) (xy 63.11095 -195.766615) (xy 63.114841 -195.820972)
			(xy 64.3934 -195.820972) (xy 64.397292 -195.766618) (xy 64.40888 -195.713372) (xy 64.427928 -195.662316)
			(xy 64.454049 -195.614492) (xy 64.486711 -195.570871) (xy 64.525249 -195.532344) (xy 64.568878 -195.499694)
			(xy 64.616709 -195.473586) (xy 64.66777 -195.454551) (xy 64.72102 -195.442977) (xy 64.775375 -195.4391)
			(xy 64.829729 -195.442998) (xy 64.882974 -195.454593) (xy 64.934027 -195.473648) (xy 64.981848 -195.499775)
			(xy 65.003934 -195.515738) (xy 65.022946 -195.529334) (xy 65.064829 -195.550066) (xy 65.109797 -195.562792)
			(xy 65.156334 -195.567082) (xy 65.202871 -195.562792) (xy 65.247839 -195.550066) (xy 65.289722 -195.529334)
			(xy 65.308734 -195.515738) (xy 65.330778 -195.499719) (xy 65.378604 -195.473598) (xy 65.429661 -195.454549)
			(xy 65.482909 -195.44296) (xy 65.537264 -195.439067) (xy 65.59162 -195.44295) (xy 65.64487 -195.454528)
			(xy 65.69593 -195.473567) (xy 65.743761 -195.49968) (xy 65.787388 -195.532333) (xy 65.825925 -195.570863)
			(xy 65.858586 -195.614486) (xy 65.884706 -195.662312) (xy 65.903754 -195.713369) (xy 65.915341 -195.766617)
			(xy 65.919233 -195.820972) (xy 65.915349 -195.875328) (xy 65.903769 -195.928578) (xy 65.884729 -195.979638)
			(xy 65.858616 -196.027468) (xy 65.825961 -196.071095) (xy 65.78743 -196.109631) (xy 65.743807 -196.142291)
			(xy 65.69598 -196.16841) (xy 65.644923 -196.187456) (xy 65.591674 -196.199043) (xy 65.537319 -196.202933)
			(xy 65.482963 -196.199048) (xy 65.429714 -196.187467) (xy 65.378654 -196.168425) (xy 65.330825 -196.142311)
			(xy 65.308734 -196.126354) (xy 65.289722 -196.112758) (xy 65.247839 -196.092026) (xy 65.202871 -196.0793)
			(xy 65.156334 -196.07501) (xy 65.109797 -196.0793) (xy 65.064829 -196.092026) (xy 65.022946 -196.112758)
			(xy 65.003934 -196.126354) (xy 64.981802 -196.142255) (xy 64.933977 -196.168375) (xy 64.882921 -196.187422)
			(xy 64.829674 -196.199009) (xy 64.77532 -196.2029) (xy 64.720965 -196.199015) (xy 64.667717 -196.187434)
			(xy 64.616659 -196.168391) (xy 64.568831 -196.142276) (xy 64.525207 -196.10962) (xy 64.486675 -196.071087)
			(xy 64.45402 -196.027462) (xy 64.427905 -195.979634) (xy 64.408864 -195.928575) (xy 64.397284 -195.875327)
			(xy 64.3934 -195.820972) (xy 63.114841 -195.820972) (xy 63.110957 -195.87533) (xy 63.099377 -195.928582)
			(xy 63.080336 -195.979643) (xy 63.054221 -196.027475) (xy 63.021565 -196.071103) (xy 62.983032 -196.10964)
			(xy 62.939407 -196.1423) (xy 62.891578 -196.16842) (xy 62.840519 -196.187466) (xy 62.787268 -196.199052)
			(xy 62.732911 -196.202941) (xy 62.678553 -196.199055) (xy 62.625302 -196.187472) (xy 62.574242 -196.168429)
			(xy 62.526411 -196.142312) (xy 62.50432 -196.126354) (xy 62.485308 -196.112758) (xy 62.443425 -196.092026)
			(xy 62.398457 -196.0793) (xy 62.35192 -196.07501) (xy 62.305383 -196.0793) (xy 62.260415 -196.092026)
			(xy 62.218532 -196.112758) (xy 62.19952 -196.126354) (xy 62.177388 -196.142254) (xy 62.129564 -196.168372)
			(xy 62.07851 -196.187417) (xy 62.025264 -196.199002) (xy 61.970912 -196.202892) (xy 61.916559 -196.199006)
			(xy 61.863313 -196.187424) (xy 61.812257 -196.168381) (xy 61.764432 -196.142266) (xy 61.72081 -196.10961)
			(xy 61.682279 -196.071079) (xy 61.649625 -196.027455) (xy 61.623512 -195.979628) (xy 61.604472 -195.928572)
			(xy 61.592892 -195.875325) (xy 61.589008 -195.820972) (xy 60.582925 -195.820972) (xy 60.579041 -195.875326)
			(xy 60.567462 -195.928574) (xy 60.548422 -195.979632) (xy 60.52231 -196.027461) (xy 60.489657 -196.071087)
			(xy 60.451128 -196.109622) (xy 60.407507 -196.142281) (xy 60.359682 -196.1684) (xy 60.308626 -196.187446)
			(xy 60.25538 -196.199033) (xy 60.201027 -196.202925) (xy 60.146673 -196.199041) (xy 60.093425 -196.187461)
			(xy 60.042367 -196.168422) (xy 59.994538 -196.14231) (xy 59.972448 -196.126354) (xy 59.953436 -196.112758)
			(xy 59.911553 -196.092026) (xy 59.866585 -196.0793) (xy 59.820048 -196.07501) (xy 59.773511 -196.0793)
			(xy 59.728543 -196.092026) (xy 59.68666 -196.112758) (xy 59.667648 -196.126354) (xy 59.645516 -196.142256)
			(xy 59.597689 -196.168378) (xy 59.546632 -196.187428) (xy 59.493384 -196.199017) (xy 59.439028 -196.202908)
			(xy 59.384671 -196.199024) (xy 59.331421 -196.187443) (xy 59.280361 -196.168401) (xy 59.232531 -196.142286)
			(xy 59.188905 -196.109629) (xy 59.150371 -196.071095) (xy 59.117714 -196.027469) (xy 59.091599 -195.979639)
			(xy 59.072557 -195.928579) (xy 59.060976 -195.875329) (xy 59.057092 -195.820972) (xy 36.017553 -195.820972)
			(xy 36.067081 -195.851295) (xy 36.13617 -195.902846) (xy 36.200251 -195.960505) (xy 36.258785 -196.023786)
			(xy 36.311282 -196.092159) (xy 36.3573 -196.16505) (xy 36.396454 -196.241847) (xy 36.428414 -196.321906)
			(xy 36.452913 -196.404554) (xy 36.469744 -196.489097) (xy 36.478766 -196.574825) (xy 36.479904 -196.66102)
			(xy 36.473148 -196.746957) (xy 36.469163 -196.770159) (xy 47.903374 -196.770159) (xy 47.903374 -196.689049)
			(xy 47.911324 -196.60833) (xy 47.927147 -196.528779) (xy 47.950692 -196.451163) (xy 47.981731 -196.376227)
			(xy 48.019966 -196.304695) (xy 48.065028 -196.237255) (xy 48.116483 -196.174556) (xy 48.173836 -196.117203)
			(xy 48.236535 -196.065748) (xy 48.303975 -196.020686) (xy 48.375507 -195.982451) (xy 48.450443 -195.951412)
			(xy 48.528059 -195.927867) (xy 48.60761 -195.912044) (xy 48.688329 -195.904094) (xy 48.769439 -195.904094)
			(xy 48.850158 -195.912044) (xy 48.929709 -195.927867) (xy 49.007325 -195.951412) (xy 49.082261 -195.982451)
			(xy 49.153793 -196.020686) (xy 49.221233 -196.065748) (xy 49.283932 -196.117203) (xy 49.341285 -196.174556)
			(xy 49.39274 -196.237255) (xy 49.437802 -196.304695) (xy 49.476037 -196.376227) (xy 49.507076 -196.451163)
			(xy 49.530621 -196.528779) (xy 49.546444 -196.60833) (xy 49.554394 -196.689049) (xy 49.554892 -196.729604)
			(xy 49.554394 -196.770159) (xy 51.403494 -196.770159) (xy 51.403494 -196.689049) (xy 51.411444 -196.60833)
			(xy 51.427267 -196.528779) (xy 51.450812 -196.451163) (xy 51.481851 -196.376227) (xy 51.520086 -196.304695)
			(xy 51.565148 -196.237255) (xy 51.616603 -196.174556) (xy 51.673956 -196.117203) (xy 51.736655 -196.065748)
			(xy 51.804095 -196.020686) (xy 51.875627 -195.982451) (xy 51.950563 -195.951412) (xy 52.028179 -195.927867)
			(xy 52.10773 -195.912044) (xy 52.188449 -195.904094) (xy 52.269559 -195.904094) (xy 52.350278 -195.912044)
			(xy 52.429829 -195.927867) (xy 52.507445 -195.951412) (xy 52.582381 -195.982451) (xy 52.653913 -196.020686)
			(xy 52.721353 -196.065748) (xy 52.784052 -196.117203) (xy 52.841405 -196.174556) (xy 52.89286 -196.237255)
			(xy 52.937922 -196.304695) (xy 52.976157 -196.376227) (xy 53.007196 -196.451163) (xy 53.030741 -196.528779)
			(xy 53.046564 -196.60833) (xy 53.054514 -196.689049) (xy 53.055012 -196.729604) (xy 53.054514 -196.770159)
			(xy 53.046564 -196.850878) (xy 53.030741 -196.930429) (xy 53.007196 -197.008045) (xy 52.976157 -197.082981)
			(xy 52.937922 -197.154513) (xy 52.89286 -197.221953) (xy 52.841405 -197.284652) (xy 52.784052 -197.342005)
			(xy 52.721353 -197.39346) (xy 52.653913 -197.438522) (xy 52.582381 -197.476757) (xy 52.507445 -197.507796)
			(xy 52.429829 -197.531341) (xy 52.350278 -197.547164) (xy 52.269559 -197.555114) (xy 52.188449 -197.555114)
			(xy 52.10773 -197.547164) (xy 52.028179 -197.531341) (xy 51.950563 -197.507796) (xy 51.875627 -197.476757)
			(xy 51.804095 -197.438522) (xy 51.736655 -197.39346) (xy 51.673956 -197.342005) (xy 51.616603 -197.284652)
			(xy 51.565148 -197.221953) (xy 51.520086 -197.154513) (xy 51.481851 -197.082981) (xy 51.450812 -197.008045)
			(xy 51.427267 -196.930429) (xy 51.411444 -196.850878) (xy 51.403494 -196.770159) (xy 49.554394 -196.770159)
			(xy 49.546444 -196.850878) (xy 49.530621 -196.930429) (xy 49.507076 -197.008045) (xy 49.476037 -197.082981)
			(xy 49.437802 -197.154513) (xy 49.39274 -197.221953) (xy 49.341285 -197.284652) (xy 49.283932 -197.342005)
			(xy 49.221233 -197.39346) (xy 49.153793 -197.438522) (xy 49.082261 -197.476757) (xy 49.007325 -197.507796)
			(xy 48.929709 -197.531341) (xy 48.850158 -197.547164) (xy 48.769439 -197.555114) (xy 48.688329 -197.555114)
			(xy 48.60761 -197.547164) (xy 48.528059 -197.531341) (xy 48.450443 -197.507796) (xy 48.375507 -197.476757)
			(xy 48.303975 -197.438522) (xy 48.236535 -197.39346) (xy 48.173836 -197.342005) (xy 48.116483 -197.284652)
			(xy 48.065028 -197.221953) (xy 48.019966 -197.154513) (xy 47.981731 -197.082981) (xy 47.950692 -197.008045)
			(xy 47.927147 -196.930429) (xy 47.911324 -196.850878) (xy 47.903374 -196.770159) (xy 36.469163 -196.770159)
			(xy 36.458555 -196.831915) (xy 36.436247 -196.91518) (xy 36.406412 -196.996055) (xy 36.388294 -197.035166)
			(xy 36.378736 -197.056407) (xy 36.366689 -197.101396) (xy 36.363037 -197.147827) (xy 36.367901 -197.194146)
			(xy 36.381118 -197.238805) (xy 36.402247 -197.28031) (xy 36.430581 -197.317274) (xy 36.465173 -197.34846)
			(xy 36.504865 -197.372826) (xy 36.54833 -197.389555) (xy 36.594116 -197.39809) (xy 36.617402 -197.39864)
			(xy 37.76853 -197.39864) (xy 38.13683 -197.03034) (xy 45.234098 -197.03034) (xy 46.013878 -197.81012)
			(xy 86.877404 -197.81012) (xy 86.881424 -197.619469) (xy 86.893478 -197.429156) (xy 86.913544 -197.239521)
			(xy 86.941587 -197.0509) (xy 86.977556 -196.86363) (xy 87.021388 -196.678042) (xy 87.073005 -196.494467)
			(xy 87.132315 -196.313231) (xy 87.199213 -196.134656) (xy 87.273579 -195.959061) (xy 87.355281 -195.786756)
			(xy 87.444175 -195.618049) (xy 87.540101 -195.453239) (xy 87.64289 -195.29262) (xy 87.752359 -195.136477)
			(xy 87.868313 -194.985088) (xy 87.990547 -194.838721) (xy 88.118841 -194.697637) (xy 88.252969 -194.562088)
			(xy 88.392693 -194.432313) (xy 88.537763 -194.308543) (xy 88.687921 -194.191) (xy 88.842902 -194.079891)
			(xy 89.002429 -193.975414) (xy 89.166218 -193.877755) (xy 89.333978 -193.787088) (xy 89.505412 -193.703574)
			(xy 89.680214 -193.627361) (xy 89.858073 -193.558585) (xy 90.038674 -193.497367) (xy 90.221694 -193.443818)
			(xy 90.40681 -193.398032) (xy 90.593691 -193.36009) (xy 90.782006 -193.330061) (xy 90.971419 -193.307996)
			(xy 91.161593 -193.293937) (xy 91.352192 -193.287907) (xy 91.542875 -193.289917) (xy 91.733304 -193.299964)
			(xy 91.92314 -193.31803) (xy 92.112046 -193.344083) (xy 92.299685 -193.378076) (xy 92.485725 -193.419949)
			(xy 92.669834 -193.469628) (xy 92.851685 -193.527024) (xy 93.030955 -193.592035) (xy 93.207325 -193.664546)
			(xy 93.380481 -193.744427) (xy 93.550116 -193.831537) (xy 93.715928 -193.925721) (xy 93.877622 -194.026812)
			(xy 94.03491 -194.134628) (xy 94.187513 -194.24898) (xy 94.335161 -194.369663) (xy 94.477589 -194.496464)
			(xy 94.614545 -194.629155) (xy 94.745786 -194.767503) (xy 94.871078 -194.91126) (xy 94.990198 -195.060171)
			(xy 95.102934 -195.213972) (xy 95.209087 -195.372388) (xy 95.308467 -195.535139) (xy 95.400897 -195.701934)
			(xy 95.486214 -195.872478) (xy 95.564266 -196.046466) (xy 95.634913 -196.223591) (xy 95.698031 -196.403536)
			(xy 95.753507 -196.585982) (xy 95.801242 -196.770605) (xy 95.841152 -196.957075) (xy 95.873165 -197.145063)
			(xy 95.897225 -197.334233) (xy 95.913288 -197.524249) (xy 95.921327 -197.714773) (xy 95.92183 -197.81012)
			(xy 95.921327 -197.905467) (xy 95.913288 -198.095991) (xy 95.897225 -198.286007) (xy 95.873165 -198.475177)
			(xy 95.841152 -198.663165) (xy 95.801242 -198.849635) (xy 95.753507 -199.034258) (xy 95.698031 -199.216704)
			(xy 95.634913 -199.396649) (xy 95.564266 -199.573774) (xy 95.486214 -199.747762) (xy 95.400897 -199.918306)
			(xy 95.308467 -200.085101) (xy 95.209087 -200.247852) (xy 95.102934 -200.406268) (xy 94.990198 -200.560069)
			(xy 94.871078 -200.70898) (xy 94.745786 -200.852737) (xy 94.614545 -200.991085) (xy 94.477589 -201.123776)
			(xy 94.335161 -201.250577) (xy 94.187513 -201.37126) (xy 94.03491 -201.485612) (xy 93.877622 -201.593428)
			(xy 93.715928 -201.694519) (xy 93.550116 -201.788703) (xy 93.380481 -201.875813) (xy 93.207325 -201.955694)
			(xy 93.030955 -202.028205) (xy 92.851685 -202.093216) (xy 92.669834 -202.150612) (xy 92.485725 -202.200291)
			(xy 92.299685 -202.242164) (xy 92.112046 -202.276157) (xy 91.92314 -202.30221) (xy 91.733304 -202.320276)
			(xy 91.542875 -202.330323) (xy 91.352192 -202.332333) (xy 91.161593 -202.326303) (xy 90.971419 -202.312244)
			(xy 90.782006 -202.290179) (xy 90.593691 -202.26015) (xy 90.40681 -202.222208) (xy 90.221694 -202.176422)
			(xy 90.038674 -202.122873) (xy 89.858073 -202.061655) (xy 89.680214 -201.992879) (xy 89.505412 -201.916666)
			(xy 89.333978 -201.833152) (xy 89.166218 -201.742485) (xy 89.002429 -201.644826) (xy 88.842902 -201.540349)
			(xy 88.687921 -201.42924) (xy 88.537763 -201.311697) (xy 88.392693 -201.187927) (xy 88.252969 -201.058152)
			(xy 88.118841 -200.922603) (xy 87.990547 -200.781519) (xy 87.868313 -200.635152) (xy 87.752359 -200.483763)
			(xy 87.64289 -200.32762) (xy 87.540101 -200.167001) (xy 87.444175 -200.002191) (xy 87.355281 -199.833484)
			(xy 87.273579 -199.661179) (xy 87.199213 -199.485584) (xy 87.132315 -199.307009) (xy 87.073005 -199.125773)
			(xy 87.021388 -198.942198) (xy 86.977556 -198.75661) (xy 86.941587 -198.56934) (xy 86.913544 -198.380719)
			(xy 86.893478 -198.191084) (xy 86.881424 -198.000771) (xy 86.877404 -197.81012) (xy 46.013878 -197.81012)
			(xy 49.503838 -201.30008) (xy 55.00116 -201.30008) (xy 60.23737 -206.536036) (xy 64.02197 -206.536036)
			(xy 64.602868 -205.955138) (xy 64.625601 -205.933136) (xy 64.675793 -205.894623) (xy 64.730582 -205.86299)
			(xy 64.789032 -205.838779) (xy 64.850141 -205.822405) (xy 64.912865 -205.814147) (xy 64.976131 -205.814147)
			(xy 65.038855 -205.822405) (xy 65.099964 -205.838779) (xy 65.158414 -205.86299) (xy 65.213203 -205.894623)
			(xy 65.263395 -205.933136) (xy 65.30813 -205.977871) (xy 65.346643 -206.028063) (xy 65.378276 -206.082852)
			(xy 65.402487 -206.141302) (xy 65.418861 -206.202411) (xy 65.427119 -206.265135) (xy 65.427119 -206.328401)
			(xy 65.418861 -206.391125) (xy 65.402487 -206.452234) (xy 65.378276 -206.510684) (xy 65.346643 -206.565473)
			(xy 65.30813 -206.615665) (xy 65.286128 -206.638398) (xy 64.422274 -207.502252) (xy 60.298838 -207.502252)
			(xy 60.282196 -207.502688) (xy 60.250047 -207.511312) (xy 60.221222 -207.527956) (xy 60.197682 -207.551489)
			(xy 60.181028 -207.580308) (xy 60.172394 -207.612454) (xy 60.172367 -207.645739) (xy 60.180948 -207.677899)
			(xy 60.197555 -207.706746) (xy 60.208922 -207.718914) (xy 60.457842 -207.96758) (xy 64.432434 -207.96758)
			(xy 65.324228 -208.859374) (xy 65.34623 -208.882107) (xy 65.384743 -208.932299) (xy 65.416376 -208.987088)
			(xy 65.440587 -209.045538) (xy 65.456961 -209.106647) (xy 65.465219 -209.169371) (xy 65.465219 -209.232637)
			(xy 65.456961 -209.295361) (xy 65.440587 -209.35647) (xy 65.416376 -209.41492) (xy 65.384743 -209.469709)
			(xy 65.34623 -209.519901) (xy 65.301495 -209.564636) (xy 65.251303 -209.603149) (xy 65.196514 -209.634782)
			(xy 65.138064 -209.658993) (xy 65.076955 -209.675367) (xy 65.014231 -209.683625) (xy 64.950965 -209.683625)
			(xy 64.888241 -209.675367) (xy 64.827132 -209.658993) (xy 64.768682 -209.634782) (xy 64.713893 -209.603149)
			(xy 64.663701 -209.564636) (xy 64.640968 -209.542634) (xy 64.03213 -208.933796) (xy 60.057538 -208.933796)
			(xy 54.335426 -203.211684) (xy 48.62576 -203.211684) (xy 44.266612 -198.852536) (xy 41.647872 -198.852536)
			(xy 41.62424 -198.853029) (xy 41.577788 -198.861753) (xy 41.53375 -198.878914) (xy 41.493643 -198.90392)
			(xy 41.45885 -198.93591) (xy 41.430571 -198.973781) (xy 41.40978 -199.016226) (xy 41.397194 -199.061784)
			(xy 41.393247 -199.108882) (xy 41.395142 -199.132444) (xy 41.397497 -199.159013) (xy 41.395556 -199.212317)
			(xy 41.38621 -199.264831) (xy 41.36964 -199.315531) (xy 41.34617 -199.36343) (xy 41.316257 -199.407592)
			(xy 41.280484 -199.447157) (xy 41.23955 -199.481354) (xy 41.194251 -199.509516) (xy 41.145471 -199.531094)
			(xy 41.094161 -199.545667) (xy 41.041321 -199.552951) (xy 41.01465 -199.553322) (xy 40.991381 -199.553793)
			(xy 40.945604 -199.562166) (xy 40.902117 -199.578735) (xy 40.862374 -199.602944) (xy 40.827703 -199.633984)
			(xy 40.799263 -199.670819) (xy 40.778004 -199.712216) (xy 40.764638 -199.756791) (xy 40.759612 -199.803055)
			(xy 40.763093 -199.849461) (xy 40.768524 -199.872092) (xy 40.77508 -199.899225) (xy 40.781253 -199.954698)
			(xy 40.779277 -200.010479) (xy 40.769194 -200.065377) (xy 40.751219 -200.118219) (xy 40.725736 -200.167878)
			(xy 40.693289 -200.213294) (xy 40.65457 -200.253497) (xy 40.610407 -200.287629) (xy 40.561742 -200.314962)
			(xy 40.509613 -200.334911) (xy 40.455133 -200.347052) (xy 40.399466 -200.351124) (xy 40.3438 -200.347042)
			(xy 40.289322 -200.334892) (xy 40.237197 -200.314933) (xy 40.188536 -200.287592) (xy 40.144379 -200.253452)
			(xy 40.105668 -200.213242) (xy 40.073229 -200.16782) (xy 40.047755 -200.118156) (xy 40.029789 -200.065311)
			(xy 40.019716 -200.010412) (xy 40.01775 -199.95463) (xy 40.023933 -199.899158) (xy 40.038133 -199.845179)
			(xy 40.060047 -199.793845) (xy 40.089208 -199.746252) (xy 40.124992 -199.703416) (xy 40.166636 -199.666252)
			(xy 40.213251 -199.635553) (xy 40.263842 -199.611974) (xy 40.317328 -199.596018) (xy 40.372569 -199.588026)
			(xy 40.400478 -199.587612) (xy 40.423745 -199.587124) (xy 40.469518 -199.578747) (xy 40.513001 -199.562177)
			(xy 40.55274 -199.537968) (xy 40.587409 -199.50693) (xy 40.615848 -199.470099) (xy 40.637107 -199.428706)
			(xy 40.650475 -199.384135) (xy 40.655506 -199.337875) (xy 40.652032 -199.291472) (xy 40.646604 -199.268842)
			(xy 40.638577 -199.235371) (xy 40.633344 -199.166746) (xy 40.63619 -199.132444) (xy 40.638032 -199.108884)
			(xy 40.63407 -199.061799) (xy 40.621477 -199.016256) (xy 40.600686 -198.973825) (xy 40.572414 -198.935965)
			(xy 40.537634 -198.903981) (xy 40.497542 -198.878973) (xy 40.453521 -198.861803) (xy 40.407086 -198.853062)
			(xy 40.38346 -198.852536) (xy 40.374824 -198.852536) (xy 40.342605 -198.851979) (xy 40.278739 -198.843424)
			(xy 40.216577 -198.82645) (xy 40.157227 -198.801358) (xy 40.101741 -198.768594) (xy 40.051106 -198.72874)
			(xy 40.006223 -198.682506) (xy 39.967888 -198.630712) (xy 39.936784 -198.574279) (xy 39.913463 -198.51421)
			(xy 39.898339 -198.451573) (xy 39.891682 -198.387481) (xy 39.893609 -198.323073) (xy 39.89832 -198.291196)
			(xy 39.901406 -198.269378) (xy 39.900928 -198.22532) (xy 39.892859 -198.182004) (xy 39.877441 -198.140729)
			(xy 39.855137 -198.102731) (xy 39.826614 -198.069149) (xy 39.792726 -198.040989) (xy 39.754491 -198.019095)
			(xy 39.713052 -198.004122) (xy 39.669652 -197.99652) (xy 39.647622 -197.996048) (xy 38.537134 -197.996048)
			(xy 38.168834 -198.364348) (xy 36.599114 -198.364348) (xy 36.577387 -198.364706) (xy 36.534566 -198.372095)
			(xy 36.493626 -198.386661) (xy 36.45576 -198.407979) (xy 36.422072 -198.435427) (xy 36.393544 -198.468206)
			(xy 36.371008 -198.505359) (xy 36.355121 -198.545805) (xy 36.346345 -198.588364) (xy 36.344936 -198.631795)
			(xy 36.350936 -198.674833) (xy 36.364169 -198.716223) (xy 36.373816 -198.735696) (xy 36.393229 -198.774008)
			(xy 36.425786 -198.853493) (xy 36.450959 -198.935616) (xy 36.468537 -199.019692) (xy 36.478375 -199.105022)
			(xy 36.480389 -199.190892) (xy 36.474564 -199.276589) (xy 36.460948 -199.361397) (xy 36.439653 -199.44461)
			(xy 36.410859 -199.525534) (xy 36.374805 -199.603495) (xy 36.33179 -199.677843) (xy 36.282175 -199.747958)
			(xy 36.226372 -199.813256) (xy 36.164846 -199.873193) (xy 36.098111 -199.927269) (xy 36.026722 -199.975033)
			(xy 35.951274 -200.016088) (xy 35.872397 -200.050091) (xy 35.790747 -200.076759) (xy 35.707006 -200.095869)
			(xy 35.62187 -200.107262) (xy 35.536051 -200.110844) (xy 35.450262 -200.106584) (xy 35.365219 -200.094518)
			(xy 35.281632 -200.074746) (xy 35.200195 -200.047434) (xy 35.121589 -200.012808) (xy 35.046469 -199.971158)
			(xy 34.97546 -199.922831) (xy 34.909154 -199.868229) (xy 34.848104 -199.807808) (xy 34.792819 -199.742071)
			(xy 34.743759 -199.671565) (xy 34.701334 -199.59688) (xy 34.665897 -199.518636) (xy 34.637744 -199.437487)
			(xy 34.617108 -199.354108) (xy 34.604163 -199.269195) (xy 34.599015 -199.183455) (xy 34.601708 -199.097603)
			(xy 34.61222 -199.012354) (xy 34.630463 -198.928419) (xy 34.656284 -198.846498) (xy 34.689469 -198.767273)
			(xy 34.729741 -198.691405) (xy 34.776764 -198.619525) (xy 34.80308 -198.585582) (xy 34.803334 -198.585328)
			(xy 34.812614 -198.572993) (xy 34.825382 -198.544895) (xy 34.831022 -198.514552) (xy 34.829204 -198.483743)
			(xy 34.820035 -198.454274) (xy 34.804052 -198.427872) (xy 34.793428 -198.416672) (xy 32.216598 -195.840096)
			(xy 31.526988 -195.840096) (xy 31.50347 -195.840611) (xy 31.457237 -195.849266) (xy 31.413386 -195.866279)
			(xy 31.373413 -195.891069) (xy 31.338683 -195.92279) (xy 31.310382 -195.960358) (xy 31.289475 -196.002492)
			(xy 31.276676 -196.047753) (xy 31.272422 -196.094596) (xy 31.276858 -196.141422) (xy 31.289833 -196.186633)
			(xy 31.299912 -196.207888) (xy 31.319016 -196.247002) (xy 31.350741 -196.328071) (xy 31.374837 -196.411725)
			(xy 31.391098 -196.497248) (xy 31.399384 -196.583908) (xy 31.399625 -196.670962) (xy 31.391819 -196.757667)
			(xy 31.376031 -196.843278) (xy 31.352399 -196.927064) (xy 31.321122 -197.008307) (xy 31.282471 -197.086311)
			(xy 31.236775 -197.160409) (xy 31.184426 -197.229966) (xy 31.125871 -197.294386) (xy 31.061613 -197.353119)
			(xy 30.992202 -197.40566) (xy 30.918231 -197.451561) (xy 30.840334 -197.490428) (xy 30.759178 -197.521929)
			(xy 30.675458 -197.545794) (xy 30.58989 -197.561818) (xy 30.503208 -197.569864) (xy 30.416152 -197.569864)
			(xy 30.32947 -197.561818) (xy 30.243902 -197.545794) (xy 30.160182 -197.521929) (xy 30.079026 -197.490428)
			(xy 30.001129 -197.451561) (xy 29.927158 -197.40566) (xy 29.857747 -197.353119) (xy 29.793489 -197.294386)
			(xy 29.734934 -197.229966) (xy 29.682585 -197.160409) (xy 29.636889 -197.086311) (xy 29.598238 -197.008307)
			(xy 29.566961 -196.927064) (xy 29.543329 -196.843278) (xy 29.527541 -196.757667) (xy 29.519735 -196.670962)
			(xy 29.519976 -196.583908) (xy 29.528262 -196.497248) (xy 29.544523 -196.411725) (xy 29.568619 -196.328071)
			(xy 29.600344 -196.247002) (xy 29.619448 -196.207888) (xy 29.629564 -196.186648) (xy 29.642543 -196.141433)
			(xy 29.646981 -196.094601) (xy 29.642727 -196.047752) (xy 29.629926 -196.002486) (xy 29.609015 -195.960347)
			(xy 29.580708 -195.922776) (xy 29.545971 -195.891054) (xy 29.505991 -195.866265) (xy 29.462132 -195.849255)
			(xy 29.415893 -195.840605) (xy 29.392372 -195.840096) (xy 28.660344 -195.840096) (xy 28.628712 -195.839605)
			(xy 28.565988 -195.831348) (xy 28.504879 -195.814974) (xy 28.446429 -195.790764) (xy 28.39164 -195.759132)
			(xy 28.341449 -195.720619) (xy 28.296714 -195.675884) (xy 28.2582 -195.625693) (xy 28.226568 -195.570904)
			(xy 28.202357 -195.512455) (xy 28.185983 -195.451346) (xy 28.177725 -195.388622) (xy 26.931112 -195.388622)
			(xy 26.931112 -198.709026) (xy 27.435572 -199.213486) (xy 29.519874 -199.213486) (xy 29.519874 -199.126586)
			(xy 29.527892 -199.040057) (xy 29.54386 -198.954637) (xy 29.567641 -198.871055) (xy 29.599033 -198.790023)
			(xy 29.637767 -198.712234) (xy 29.683514 -198.63835) (xy 29.735883 -198.569003) (xy 29.794427 -198.504783)
			(xy 29.858647 -198.446239) (xy 29.927994 -198.39387) (xy 30.001878 -198.348123) (xy 30.079667 -198.309389)
			(xy 30.160699 -198.277997) (xy 30.244281 -198.254216) (xy 30.329701 -198.238248) (xy 30.41623 -198.23023)
			(xy 30.50313 -198.23023) (xy 30.589659 -198.238248) (xy 30.675079 -198.254216) (xy 30.758661 -198.277997)
			(xy 30.839693 -198.309389) (xy 30.917482 -198.348123) (xy 30.991366 -198.39387) (xy 31.060713 -198.446239)
			(xy 31.124933 -198.504783) (xy 31.183477 -198.569003) (xy 31.235846 -198.63835) (xy 31.281593 -198.712234)
			(xy 31.320327 -198.790023) (xy 31.351719 -198.871055) (xy 31.3755 -198.954637) (xy 31.391468 -199.040057)
			(xy 31.399486 -199.126586) (xy 31.399988 -199.170036) (xy 31.399486 -199.213486) (xy 31.391468 -199.300015)
			(xy 31.3755 -199.385435) (xy 31.351719 -199.469017) (xy 31.320327 -199.550049) (xy 31.281593 -199.627838)
			(xy 31.235846 -199.701722) (xy 31.183477 -199.771069) (xy 31.124933 -199.835289) (xy 31.060713 -199.893833)
			(xy 30.991366 -199.946202) (xy 30.917482 -199.991949) (xy 30.839693 -200.030683) (xy 30.758661 -200.062075)
			(xy 30.675079 -200.085856) (xy 30.589659 -200.101824) (xy 30.50313 -200.109842) (xy 30.41623 -200.109842)
			(xy 30.329701 -200.101824) (xy 30.244281 -200.085856) (xy 30.160699 -200.062075) (xy 30.079667 -200.030683)
			(xy 30.001878 -199.991949) (xy 29.927994 -199.946202) (xy 29.858647 -199.893833) (xy 29.794427 -199.835289)
			(xy 29.735883 -199.771069) (xy 29.683514 -199.701722) (xy 29.637767 -199.627838) (xy 29.599033 -199.550049)
			(xy 29.567641 -199.469017) (xy 29.54386 -199.385435) (xy 29.527892 -199.300015) (xy 29.519874 -199.213486)
			(xy 27.435572 -199.213486) (xy 28.13558 -199.913494) (xy 28.13558 -201.362818) (xy 28.136073 -201.385851)
			(xy 28.144363 -201.431164) (xy 28.160687 -201.474241) (xy 28.18451 -201.513668) (xy 28.21505 -201.548155)
			(xy 28.251308 -201.57657) (xy 28.292094 -201.597983) (xy 28.336073 -201.611692) (xy 28.381802 -201.617248)
			(xy 28.40482 -201.61631) (xy 28.432337 -201.61428) (xy 28.487433 -201.617217) (xy 28.541532 -201.628059)
			(xy 28.593505 -201.646579) (xy 28.642269 -201.672391) (xy 28.686808 -201.704958) (xy 28.726191 -201.743599)
			(xy 28.759598 -201.78751) (xy 28.786333 -201.835775) (xy 28.805837 -201.887387) (xy 28.817705 -201.94127)
			(xy 28.821689 -201.996301) (xy 28.817705 -202.051331) (xy 28.805837 -202.105214) (xy 28.786332 -202.156826)
			(xy 28.759598 -202.205091) (xy 28.72619 -202.249001) (xy 28.686807 -202.287643) (xy 28.642269 -202.32021)
			(xy 28.593504 -202.346022) (xy 28.541531 -202.364542) (xy 28.487432 -202.375383) (xy 28.432336 -202.37832)
			(xy 28.40482 -202.376278) (xy 28.381802 -202.375397) (xy 28.336082 -202.380966) (xy 28.292113 -202.394679)
			(xy 28.251333 -202.41609) (xy 28.215078 -202.444496) (xy 28.184533 -202.478969) (xy 28.160699 -202.51838)
			(xy 28.144354 -202.561441) (xy 28.136033 -202.606741) (xy 28.13558 -202.62977) (xy 28.13558 -210.099656)
			(xy 72.868035 -210.099656) (xy 72.872042 -209.896906) (xy 72.884055 -209.694472) (xy 72.904056 -209.492671)
			(xy 72.932015 -209.291817) (xy 72.967886 -209.092225) (xy 73.011615 -208.894206) (xy 73.063133 -208.698069)
			(xy 73.122359 -208.504121) (xy 73.189201 -208.312663) (xy 73.263555 -208.123996) (xy 73.345304 -207.938414)
			(xy 73.434322 -207.756206) (xy 73.530468 -207.577657) (xy 73.633593 -207.403046) (xy 73.743536 -207.232646)
			(xy 73.860125 -207.066722) (xy 73.983178 -206.905533) (xy 74.112503 -206.749332) (xy 74.247898 -206.598362)
			(xy 74.389151 -206.452858) (xy 74.536043 -206.313049) (xy 74.688343 -206.179152) (xy 74.845814 -206.051377)
			(xy 75.008211 -205.929922) (xy 75.175278 -205.814978) (xy 75.346757 -205.706724) (xy 75.522378 -205.605329)
			(xy 75.701868 -205.510951) (xy 75.884946 -205.423739) (xy 76.071327 -205.343827) (xy 76.26072 -205.27134)
			(xy 76.452828 -205.206393) (xy 76.647352 -205.149085) (xy 76.843988 -205.099508) (xy 77.04243 -205.057737)
			(xy 77.242367 -205.023839) (xy 77.443486 -204.997867) (xy 77.645475 -204.97986) (xy 77.848018 -204.969847)
			(xy 78.050798 -204.967843) (xy 78.253499 -204.973853) (xy 78.455804 -204.987865) (xy 78.657398 -205.00986)
			(xy 78.857965 -205.039801) (xy 79.057193 -205.077642) (xy 79.254771 -205.123325) (xy 79.450389 -205.176778)
			(xy 79.643743 -205.237917) (xy 79.834531 -205.306648) (xy 80.022454 -205.382862) (xy 80.20722 -205.466441)
			(xy 80.388539 -205.557254) (xy 80.56613 -205.655159) (xy 80.739713 -205.760004) (xy 80.909019 -205.871625)
			(xy 81.073784 -205.989847) (xy 81.233749 -206.114487) (xy 81.388665 -206.245348) (xy 81.53829 -206.382228)
			(xy 81.68239 -206.524912) (xy 81.820742 -206.673178) (xy 81.953127 -206.826794) (xy 82.079341 -206.985519)
			(xy 82.199185 -207.149108) (xy 82.312473 -207.317303) (xy 82.419028 -207.489842) (xy 82.518683 -207.666457)
			(xy 82.611283 -207.84687) (xy 82.696683 -208.030801) (xy 82.77475 -208.217962) (xy 82.845362 -208.408062)
			(xy 82.908408 -208.600802) (xy 82.963791 -208.795883) (xy 83.011423 -208.993) (xy 83.051231 -209.191844)
			(xy 83.083153 -209.392106) (xy 83.107137 -209.593472) (xy 83.123148 -209.795629) (xy 83.131159 -209.998261)
			(xy 83.13166 -210.099656) (xy 83.131159 -210.201051) (xy 83.123148 -210.403683) (xy 83.107137 -210.60584)
			(xy 83.083153 -210.807206) (xy 83.051231 -211.007468) (xy 83.011423 -211.206312) (xy 82.963791 -211.403429)
			(xy 82.908408 -211.59851) (xy 82.845362 -211.79125) (xy 82.77475 -211.98135) (xy 82.696683 -212.168511)
			(xy 82.611283 -212.352442) (xy 82.518683 -212.532855) (xy 82.419028 -212.70947) (xy 82.312473 -212.882009)
			(xy 82.199185 -213.050204) (xy 82.079341 -213.213793) (xy 81.953127 -213.372518) (xy 81.820742 -213.526134)
			(xy 81.68239 -213.6744) (xy 81.53829 -213.817084) (xy 81.388665 -213.953964) (xy 81.233749 -214.084825)
			(xy 81.073784 -214.209465) (xy 80.909019 -214.327687) (xy 80.739713 -214.439308) (xy 80.56613 -214.544153)
			(xy 80.388539 -214.642058) (xy 80.20722 -214.732871) (xy 80.022454 -214.81645) (xy 79.834531 -214.892664)
			(xy 79.643743 -214.961395) (xy 79.450389 -215.022534) (xy 79.254771 -215.075987) (xy 79.057193 -215.12167)
			(xy 78.857965 -215.159511) (xy 78.657398 -215.189452) (xy 78.455804 -215.211447) (xy 78.253499 -215.225459)
			(xy 78.050798 -215.231469) (xy 77.848018 -215.229465) (xy 77.645475 -215.219452) (xy 77.443486 -215.201445)
			(xy 77.242367 -215.175473) (xy 77.04243 -215.141575) (xy 76.843988 -215.099804) (xy 76.647352 -215.050227)
			(xy 76.452828 -214.992919) (xy 76.26072 -214.927972) (xy 76.071327 -214.855485) (xy 75.884946 -214.775573)
			(xy 75.701868 -214.688361) (xy 75.522378 -214.593983) (xy 75.346757 -214.492588) (xy 75.175278 -214.384334)
			(xy 75.008211 -214.26939) (xy 74.845814 -214.147935) (xy 74.688343 -214.02016) (xy 74.536043 -213.886263)
			(xy 74.389151 -213.746454) (xy 74.247898 -213.60095) (xy 74.112503 -213.44998) (xy 73.983178 -213.293779)
			(xy 73.860125 -213.13259) (xy 73.743536 -212.966666) (xy 73.633593 -212.796266) (xy 73.530468 -212.621655)
			(xy 73.434322 -212.443106) (xy 73.345304 -212.260898) (xy 73.263555 -212.075316) (xy 73.189201 -211.886649)
			(xy 73.122359 -211.695191) (xy 73.063133 -211.501243) (xy 73.011615 -211.305106) (xy 72.967886 -211.107087)
			(xy 72.932015 -210.907495) (xy 72.904056 -210.706641) (xy 72.884055 -210.50484) (xy 72.872042 -210.302406)
			(xy 72.868035 -210.099656) (xy 28.13558 -210.099656) (xy 28.13558 -215.70696) (xy 28.863288 -215.70696)
			(xy 28.867359 -215.651338) (xy 28.879485 -215.596901) (xy 28.899408 -215.54481) (xy 28.926704 -215.496175)
			(xy 28.96079 -215.452032) (xy 29.000939 -215.413323) (xy 29.046297 -215.380872) (xy 29.095897 -215.355371)
			(xy 29.148681 -215.337364) (xy 29.203524 -215.327234) (xy 29.259258 -215.325197) (xy 29.314695 -215.331297)
			(xy 29.368652 -215.345403) (xy 29.419981 -215.367215) (xy 29.467587 -215.396269) (xy 29.510455 -215.431944)
			(xy 29.547672 -215.473481) (xy 29.578445 -215.519994) (xy 29.602117 -215.570491) (xy 29.618185 -215.623898)
			(xy 29.626305 -215.679074) (xy 29.626814 -215.70696) (xy 29.626305 -215.734846) (xy 29.618185 -215.790022)
			(xy 29.602117 -215.843429) (xy 29.578445 -215.893926) (xy 29.547672 -215.940439) (xy 29.510455 -215.981976)
			(xy 29.467587 -216.017651) (xy 29.419981 -216.046705) (xy 29.368652 -216.068517) (xy 29.314695 -216.082623)
			(xy 29.259258 -216.088723) (xy 29.203524 -216.086686) (xy 29.148681 -216.076556) (xy 29.095897 -216.058549)
			(xy 29.046297 -216.033048) (xy 29.000939 -216.000597) (xy 28.96079 -215.961888) (xy 28.926704 -215.917745)
			(xy 28.899408 -215.86911) (xy 28.879485 -215.817019) (xy 28.867359 -215.762582) (xy 28.863288 -215.70696)
			(xy 28.13558 -215.70696) (xy 28.13558 -217.526531) (xy 47.842414 -217.526531) (xy 47.842414 -217.445421)
			(xy 47.850364 -217.364702) (xy 47.866187 -217.285151) (xy 47.889732 -217.207535) (xy 47.920771 -217.132599)
			(xy 47.959006 -217.061067) (xy 48.004068 -216.993627) (xy 48.055523 -216.930928) (xy 48.112876 -216.873575)
			(xy 48.175575 -216.82212) (xy 48.243015 -216.777058) (xy 48.314547 -216.738823) (xy 48.389483 -216.707784)
			(xy 48.467099 -216.684239) (xy 48.54665 -216.668416) (xy 48.627369 -216.660466) (xy 48.708479 -216.660466)
			(xy 48.789198 -216.668416) (xy 48.868749 -216.684239) (xy 48.946365 -216.707784) (xy 49.021301 -216.738823)
			(xy 49.092833 -216.777058) (xy 49.160273 -216.82212) (xy 49.222972 -216.873575) (xy 49.280325 -216.930928)
			(xy 49.33178 -216.993627) (xy 49.376842 -217.061067) (xy 49.415077 -217.132599) (xy 49.446116 -217.207535)
			(xy 49.469661 -217.285151) (xy 49.485484 -217.364702) (xy 49.493434 -217.445421) (xy 49.493932 -217.485976)
			(xy 49.493434 -217.526531) (xy 51.342534 -217.526531) (xy 51.342534 -217.445421) (xy 51.350484 -217.364702)
			(xy 51.366307 -217.285151) (xy 51.389852 -217.207535) (xy 51.420891 -217.132599) (xy 51.459126 -217.061067)
			(xy 51.504188 -216.993627) (xy 51.555643 -216.930928) (xy 51.612996 -216.873575) (xy 51.675695 -216.82212)
			(xy 51.743135 -216.777058) (xy 51.814667 -216.738823) (xy 51.889603 -216.707784) (xy 51.967219 -216.684239)
			(xy 52.04677 -216.668416) (xy 52.127489 -216.660466) (xy 52.208599 -216.660466) (xy 52.289318 -216.668416)
			(xy 52.368869 -216.684239) (xy 52.446485 -216.707784) (xy 52.521421 -216.738823) (xy 52.592953 -216.777058)
			(xy 52.660393 -216.82212) (xy 52.723092 -216.873575) (xy 52.780445 -216.930928) (xy 52.8319 -216.993627)
			(xy 52.876962 -217.061067) (xy 52.915197 -217.132599) (xy 52.946236 -217.207535) (xy 52.947108 -217.210408)
			(xy 60.170682 -217.210408) (xy 60.174568 -217.156054) (xy 60.186151 -217.102806) (xy 60.205194 -217.051748)
			(xy 60.231309 -217.003921) (xy 60.263966 -216.960297) (xy 60.302498 -216.921764) (xy 60.346123 -216.889108)
			(xy 60.39395 -216.862993) (xy 60.445008 -216.84395) (xy 60.498256 -216.832368) (xy 60.552611 -216.828482)
			(xy 60.606965 -216.832371) (xy 60.660212 -216.843956) (xy 60.711269 -216.863002) (xy 60.759095 -216.889119)
			(xy 60.781184 -216.905078) (xy 60.800196 -216.918674) (xy 60.842079 -216.939406) (xy 60.887047 -216.952132)
			(xy 60.933584 -216.956422) (xy 60.980121 -216.952132) (xy 61.025089 -216.939406) (xy 61.066972 -216.918674)
			(xy 61.085984 -216.905078) (xy 61.108086 -216.889136) (xy 61.155911 -216.863014) (xy 61.206968 -216.843965)
			(xy 61.260216 -216.832377) (xy 61.314571 -216.828485) (xy 61.368927 -216.832369) (xy 61.422177 -216.843949)
			(xy 61.473236 -216.86299) (xy 61.521066 -216.889105) (xy 61.564692 -216.92176) (xy 61.603226 -216.960293)
			(xy 61.635885 -217.003917) (xy 61.662001 -217.051745) (xy 61.681045 -217.102804) (xy 61.692628 -217.156053)
			(xy 61.696515 -217.210408) (xy 63.162275 -217.210408) (xy 63.166161 -217.156052) (xy 63.177744 -217.102803)
			(xy 63.196788 -217.051744) (xy 63.222904 -217.003915) (xy 63.255562 -216.96029) (xy 63.294096 -216.921756)
			(xy 63.337722 -216.8891) (xy 63.385552 -216.862984) (xy 63.436611 -216.843942) (xy 63.489861 -216.83236)
			(xy 63.544217 -216.828475) (xy 63.598573 -216.832365) (xy 63.651822 -216.843952) (xy 63.70288 -216.862999)
			(xy 63.750707 -216.889118) (xy 63.772796 -216.905078) (xy 63.791808 -216.918674) (xy 63.833691 -216.939406)
			(xy 63.878659 -216.952132) (xy 63.925196 -216.956422) (xy 63.971733 -216.952132) (xy 64.016701 -216.939406)
			(xy 64.058584 -216.918674) (xy 64.077596 -216.905078) (xy 64.099697 -216.889137) (xy 64.147522 -216.863017)
			(xy 64.198578 -216.84397) (xy 64.251824 -216.832383) (xy 64.306178 -216.828492) (xy 64.360532 -216.832377)
			(xy 64.41378 -216.843958) (xy 64.464838 -216.862999) (xy 64.512666 -216.889113) (xy 64.55629 -216.921768)
			(xy 64.594823 -216.9603) (xy 64.62748 -217.003923) (xy 64.653596 -217.05175) (xy 64.672639 -217.102807)
			(xy 64.684221 -217.156054) (xy 64.688108 -217.210408) (xy 64.684219 -217.264762) (xy 64.672634 -217.318009)
			(xy 64.653589 -217.369065) (xy 64.627471 -217.416891) (xy 64.594812 -217.460513) (xy 64.556278 -217.499043)
			(xy 64.512652 -217.531696) (xy 64.464822 -217.557808) (xy 64.413764 -217.576847) (xy 64.360516 -217.588426)
			(xy 64.306161 -217.592308) (xy 64.251808 -217.588415) (xy 64.198562 -217.576825) (xy 64.147507 -217.557776)
			(xy 64.099683 -217.531654) (xy 64.077596 -217.515694) (xy 64.058584 -217.502098) (xy 64.016701 -217.481366)
			(xy 63.971733 -217.46864) (xy 63.925196 -217.46435) (xy 63.878659 -217.46864) (xy 63.833691 -217.481366)
			(xy 63.791808 -217.502098) (xy 63.772796 -217.515694) (xy 63.750721 -217.531672) (xy 63.702895 -217.557794)
			(xy 63.651838 -217.576844) (xy 63.59859 -217.588433) (xy 63.544234 -217.592325) (xy 63.489878 -217.588442)
			(xy 63.436627 -217.576863) (xy 63.385567 -217.557823) (xy 63.337736 -217.531709) (xy 63.294109 -217.499055)
			(xy 63.255573 -217.460523) (xy 63.222914 -217.416899) (xy 63.196795 -217.369072) (xy 63.177749 -217.318013)
			(xy 63.166164 -217.264764) (xy 63.162275 -217.210408) (xy 61.696515 -217.210408) (xy 61.692626 -217.264764)
			(xy 61.68104 -217.318012) (xy 61.661994 -217.36907) (xy 61.635875 -217.416897) (xy 61.603215 -217.46052)
			(xy 61.564679 -217.499051) (xy 61.521052 -217.531705) (xy 61.473221 -217.557817) (xy 61.422161 -217.576856)
			(xy 61.36891 -217.588434) (xy 61.314554 -217.592315) (xy 61.260199 -217.588421) (xy 61.206952 -217.57683)
			(xy 61.155896 -217.557779) (xy 61.108072 -217.531655) (xy 61.085984 -217.515694) (xy 61.066972 -217.502098)
			(xy 61.025089 -217.481366) (xy 60.980121 -217.46864) (xy 60.933584 -217.46435) (xy 60.887047 -217.46864)
			(xy 60.842079 -217.481366) (xy 60.800196 -217.502098) (xy 60.781184 -217.515694) (xy 60.759109 -217.531671)
			(xy 60.711284 -217.557791) (xy 60.660228 -217.576839) (xy 60.606981 -217.588427) (xy 60.552627 -217.592318)
			(xy 60.498273 -217.588434) (xy 60.445024 -217.576855) (xy 60.393966 -217.557814) (xy 60.346137 -217.531701)
			(xy 60.302511 -217.499047) (xy 60.263977 -217.460516) (xy 60.231318 -217.416893) (xy 60.205201 -217.369067)
			(xy 60.186156 -217.31801) (xy 60.174571 -217.264763) (xy 60.170682 -217.210408) (xy 52.947108 -217.210408)
			(xy 52.969781 -217.285151) (xy 52.985604 -217.364702) (xy 52.993554 -217.445421) (xy 52.994052 -217.485976)
			(xy 52.993554 -217.526531) (xy 52.985604 -217.60725) (xy 52.969781 -217.686801) (xy 52.946236 -217.764417)
			(xy 52.915197 -217.839353) (xy 52.876962 -217.910885) (xy 52.8319 -217.978325) (xy 52.780445 -218.041024)
			(xy 52.723092 -218.098377) (xy 52.660393 -218.149832) (xy 52.592953 -218.194894) (xy 52.521421 -218.233129)
			(xy 52.446485 -218.264168) (xy 52.368869 -218.287713) (xy 52.289318 -218.303536) (xy 52.208599 -218.311486)
			(xy 52.127489 -218.311486) (xy 52.04677 -218.303536) (xy 51.967219 -218.287713) (xy 51.889603 -218.264168)
			(xy 51.814667 -218.233129) (xy 51.743135 -218.194894) (xy 51.675695 -218.149832) (xy 51.612996 -218.098377)
			(xy 51.555643 -218.041024) (xy 51.504188 -217.978325) (xy 51.459126 -217.910885) (xy 51.420891 -217.839353)
			(xy 51.389852 -217.764417) (xy 51.366307 -217.686801) (xy 51.350484 -217.60725) (xy 51.342534 -217.526531)
			(xy 49.493434 -217.526531) (xy 49.485484 -217.60725) (xy 49.469661 -217.686801) (xy 49.446116 -217.764417)
			(xy 49.415077 -217.839353) (xy 49.376842 -217.910885) (xy 49.33178 -217.978325) (xy 49.280325 -218.041024)
			(xy 49.222972 -218.098377) (xy 49.160273 -218.149832) (xy 49.092833 -218.194894) (xy 49.021301 -218.233129)
			(xy 48.946365 -218.264168) (xy 48.868749 -218.287713) (xy 48.789198 -218.303536) (xy 48.708479 -218.311486)
			(xy 48.627369 -218.311486) (xy 48.54665 -218.303536) (xy 48.467099 -218.287713) (xy 48.389483 -218.264168)
			(xy 48.314547 -218.233129) (xy 48.243015 -218.194894) (xy 48.175575 -218.149832) (xy 48.112876 -218.098377)
			(xy 48.055523 -218.041024) (xy 48.004068 -217.978325) (xy 47.959006 -217.910885) (xy 47.920771 -217.839353)
			(xy 47.889732 -217.764417) (xy 47.866187 -217.686801) (xy 47.850364 -217.60725) (xy 47.842414 -217.526531)
			(xy 28.13558 -217.526531) (xy 28.13558 -218.90609) (xy 27.868369 -219.173301) (xy 60.170691 -219.173301)
			(xy 60.174579 -219.118948) (xy 60.186162 -219.065702) (xy 60.205205 -219.014646) (xy 60.231321 -218.96682)
			(xy 60.263978 -218.923197) (xy 60.30251 -218.884667) (xy 60.346134 -218.852012) (xy 60.393961 -218.825899)
			(xy 60.445018 -218.806857) (xy 60.498265 -218.795276) (xy 60.552618 -218.791391) (xy 60.606971 -218.795282)
			(xy 60.660216 -218.806867) (xy 60.711271 -218.825913) (xy 60.759096 -218.852031) (xy 60.781184 -218.86799)
			(xy 60.800196 -218.881586) (xy 60.842079 -218.902318) (xy 60.887047 -218.915044) (xy 60.933584 -218.919334)
			(xy 60.980121 -218.915044) (xy 61.025089 -218.902318) (xy 61.066972 -218.881586) (xy 61.085984 -218.86799)
			(xy 61.108074 -218.852031) (xy 61.155901 -218.825908) (xy 61.206958 -218.806858) (xy 61.260208 -218.795269)
			(xy 61.314564 -218.791375) (xy 61.368921 -218.795258) (xy 61.422173 -218.806838) (xy 61.473234 -218.825879)
			(xy 61.521065 -218.851993) (xy 61.564693 -218.884648) (xy 61.603229 -218.923181) (xy 61.635889 -218.966806)
			(xy 61.662007 -219.014635) (xy 61.681052 -219.065694) (xy 61.692637 -219.118944) (xy 61.696525 -219.173301)
			(xy 63.162284 -219.173301) (xy 63.166172 -219.118947) (xy 63.177756 -219.065699) (xy 63.1968 -219.014641)
			(xy 63.222916 -218.966814) (xy 63.255574 -218.92319) (xy 63.294108 -218.884659) (xy 63.337734 -218.852004)
			(xy 63.385562 -218.82589) (xy 63.436621 -218.806849) (xy 63.48987 -218.795268) (xy 63.544225 -218.791384)
			(xy 63.598579 -218.795275) (xy 63.651826 -218.806863) (xy 63.702882 -218.82591) (xy 63.750708 -218.85203)
			(xy 63.772796 -218.86799) (xy 63.791808 -218.881586) (xy 63.833691 -218.902318) (xy 63.878659 -218.915044)
			(xy 63.925196 -218.919334) (xy 63.971733 -218.915044) (xy 64.016701 -218.902318) (xy 64.058584 -218.881586)
			(xy 64.077596 -218.86799) (xy 64.099686 -218.852032) (xy 64.147512 -218.825911) (xy 64.198568 -218.806863)
			(xy 64.251816 -218.795275) (xy 64.306171 -218.791383) (xy 64.360526 -218.795266) (xy 64.413776 -218.806846)
			(xy 64.464835 -218.825887) (xy 64.512665 -218.852001) (xy 64.556291 -218.884656) (xy 64.594826 -218.923188)
			(xy 64.627484 -218.966812) (xy 64.653601 -219.014639) (xy 64.672646 -219.065697) (xy 64.68423 -219.118946)
			(xy 64.688117 -219.173301) (xy 64.684229 -219.227656) (xy 64.672645 -219.280905) (xy 64.6536 -219.331963)
			(xy 64.627483 -219.37979) (xy 64.594824 -219.423414) (xy 64.556289 -219.461945) (xy 64.512663 -219.4946)
			(xy 64.464833 -219.520714) (xy 64.413774 -219.539754) (xy 64.360524 -219.551334) (xy 64.306168 -219.555217)
			(xy 64.251814 -219.551325) (xy 64.198566 -219.539737) (xy 64.14751 -219.520688) (xy 64.099684 -219.494566)
			(xy 64.077596 -219.478606) (xy 64.058584 -219.46501) (xy 64.016701 -219.444278) (xy 63.971733 -219.431552)
			(xy 63.925196 -219.427262) (xy 63.878659 -219.431552) (xy 63.833691 -219.444278) (xy 63.791808 -219.46501)
			(xy 63.772796 -219.478606) (xy 63.75071 -219.494568) (xy 63.702884 -219.520689) (xy 63.651828 -219.539737)
			(xy 63.598581 -219.551324) (xy 63.544227 -219.555216) (xy 63.489872 -219.551332) (xy 63.436623 -219.539752)
			(xy 63.385565 -219.520711) (xy 63.337736 -219.494597) (xy 63.29411 -219.461943) (xy 63.255576 -219.423411)
			(xy 63.222918 -219.379788) (xy 63.196801 -219.331961) (xy 63.177756 -219.280904) (xy 63.166172 -219.227656)
			(xy 63.162284 -219.173301) (xy 61.696525 -219.173301) (xy 61.692636 -219.227658) (xy 61.681052 -219.280908)
			(xy 61.662006 -219.331967) (xy 61.635887 -219.379796) (xy 61.603227 -219.423421) (xy 61.564691 -219.461953)
			(xy 61.521063 -219.494609) (xy 61.473232 -219.520722) (xy 61.42217 -219.539763) (xy 61.368919 -219.551342)
			(xy 61.314562 -219.555225) (xy 61.260205 -219.551331) (xy 61.206956 -219.539741) (xy 61.155899 -219.520691)
			(xy 61.108072 -219.494567) (xy 61.085984 -219.478606) (xy 61.066972 -219.46501) (xy 61.025089 -219.444278)
			(xy 60.980121 -219.431552) (xy 60.933584 -219.427262) (xy 60.887047 -219.431552) (xy 60.842079 -219.444278)
			(xy 60.800196 -219.46501) (xy 60.781184 -219.478606) (xy 60.759098 -219.494567) (xy 60.711274 -219.520686)
			(xy 60.660219 -219.539732) (xy 60.606973 -219.551318) (xy 60.55262 -219.555209) (xy 60.498267 -219.551324)
			(xy 60.44502 -219.539743) (xy 60.393963 -219.520702) (xy 60.346136 -219.494589) (xy 60.302512 -219.461935)
			(xy 60.263979 -219.423404) (xy 60.231322 -219.379782) (xy 60.205206 -219.331956) (xy 60.186163 -219.280901)
			(xy 60.174579 -219.227654) (xy 60.170691 -219.173301) (xy 27.868369 -219.173301) (xy 27.442922 -219.598748)
			(xy 27.432058 -219.610172) (xy 27.415813 -219.637176) (xy 27.406733 -219.667354) (xy 27.405584 -219.683076)
			(xy 27.405584 -221.316798) (xy 60.170696 -221.316798) (xy 60.174584 -221.262445) (xy 60.186168 -221.2092)
			(xy 60.205211 -221.158145) (xy 60.231327 -221.110319) (xy 60.263984 -221.066698) (xy 60.302516 -221.028168)
			(xy 60.346139 -220.995514) (xy 60.393966 -220.969401) (xy 60.445022 -220.950361) (xy 60.498269 -220.938781)
			(xy 60.552621 -220.934896) (xy 60.606973 -220.938787) (xy 60.660218 -220.950373) (xy 60.711273 -220.969419)
			(xy 60.759096 -220.995537) (xy 60.781184 -221.011496) (xy 60.800196 -221.025092) (xy 60.842079 -221.045824)
			(xy 60.887047 -221.05855) (xy 60.933584 -221.06284) (xy 60.980121 -221.05855) (xy 61.025089 -221.045824)
			(xy 61.066972 -221.025092) (xy 61.085984 -221.011496) (xy 61.108069 -220.995529) (xy 61.155896 -220.969406)
			(xy 61.206954 -220.950355) (xy 61.260203 -220.938764) (xy 61.31456 -220.934871) (xy 61.368918 -220.938753)
			(xy 61.42217 -220.950332) (xy 61.473232 -220.969373) (xy 61.521065 -220.995487) (xy 61.564693 -221.028142)
			(xy 61.60323 -221.066675) (xy 61.635891 -221.1103) (xy 61.66201 -221.158129) (xy 61.681056 -221.209189)
			(xy 61.692641 -221.26244) (xy 61.696529 -221.316798) (xy 63.162289 -221.316798) (xy 63.166177 -221.262444)
			(xy 63.177761 -221.209196) (xy 63.196806 -221.15814) (xy 63.222922 -221.110313) (xy 63.25558 -221.066691)
			(xy 63.294114 -221.02816) (xy 63.337739 -220.995506) (xy 63.385568 -220.969393) (xy 63.436626 -220.950353)
			(xy 63.489874 -220.938773) (xy 63.544228 -220.934889) (xy 63.598582 -220.938781) (xy 63.651828 -220.950368)
			(xy 63.702884 -220.969416) (xy 63.750708 -220.995536) (xy 63.772796 -221.011496) (xy 63.791808 -221.025092)
			(xy 63.833691 -221.045824) (xy 63.878659 -221.05855) (xy 63.925196 -221.06284) (xy 63.971733 -221.05855)
			(xy 64.016701 -221.045824) (xy 64.058584 -221.025092) (xy 64.077596 -221.011496) (xy 64.099681 -220.99553)
			(xy 64.147507 -220.969408) (xy 64.198563 -220.950359) (xy 64.251812 -220.93877) (xy 64.306167 -220.934878)
			(xy 64.360524 -220.938761) (xy 64.413774 -220.950341) (xy 64.464834 -220.969381) (xy 64.512664 -220.995495)
			(xy 64.556291 -221.02815) (xy 64.594827 -221.066682) (xy 64.627486 -221.110306) (xy 64.653604 -221.158134)
			(xy 64.672649 -221.209193) (xy 64.684234 -221.262442) (xy 64.688122 -221.316798) (xy 64.684235 -221.371154)
			(xy 64.672651 -221.424403) (xy 64.653606 -221.475462) (xy 64.627489 -221.52329) (xy 64.59483 -221.566914)
			(xy 64.556295 -221.605447) (xy 64.512668 -221.638102) (xy 64.464838 -221.664217) (xy 64.413778 -221.683258)
			(xy 64.360528 -221.694838) (xy 64.306172 -221.698722) (xy 64.251816 -221.69483) (xy 64.198568 -221.683242)
			(xy 64.147511 -221.664194) (xy 64.099685 -221.638072) (xy 64.077596 -221.622112) (xy 64.058584 -221.608516)
			(xy 64.016701 -221.587784) (xy 63.971733 -221.575058) (xy 63.925196 -221.570768) (xy 63.878659 -221.575058)
			(xy 63.833691 -221.587784) (xy 63.791808 -221.608516) (xy 63.772796 -221.622112) (xy 63.750704 -221.638066)
			(xy 63.702879 -221.664186) (xy 63.651824 -221.683233) (xy 63.598577 -221.69482) (xy 63.544223 -221.698711)
			(xy 63.489869 -221.694827) (xy 63.436621 -221.683246) (xy 63.385563 -221.664205) (xy 63.337735 -221.638091)
			(xy 63.29411 -221.605437) (xy 63.255577 -221.566906) (xy 63.22292 -221.523282) (xy 63.196804 -221.475456)
			(xy 63.17776 -221.424399) (xy 63.166176 -221.371152) (xy 63.162289 -221.316798) (xy 61.696529 -221.316798)
			(xy 61.692642 -221.371155) (xy 61.681057 -221.424406) (xy 61.662012 -221.475466) (xy 61.635893 -221.523296)
			(xy 61.603233 -221.566921) (xy 61.564697 -221.605455) (xy 61.521069 -221.638111) (xy 61.473237 -221.664225)
			(xy 61.422175 -221.683266) (xy 61.368923 -221.694846) (xy 61.314565 -221.698729) (xy 61.260208 -221.694836)
			(xy 61.206958 -221.683247) (xy 61.1559 -221.664196) (xy 61.108073 -221.638073) (xy 61.085984 -221.622112)
			(xy 61.066972 -221.608516) (xy 61.025089 -221.587784) (xy 60.980121 -221.575058) (xy 60.933584 -221.570768)
			(xy 60.887047 -221.575058) (xy 60.842079 -221.587784) (xy 60.800196 -221.608516) (xy 60.781184 -221.622112)
			(xy 60.759092 -221.638065) (xy 60.711268 -221.664183) (xy 60.660214 -221.683228) (xy 60.606969 -221.694814)
			(xy 60.552617 -221.698704) (xy 60.498264 -221.694819) (xy 60.445018 -221.683238) (xy 60.393962 -221.664197)
			(xy 60.346135 -221.638083) (xy 60.302512 -221.605429) (xy 60.26398 -221.566898) (xy 60.231325 -221.523277)
			(xy 60.205209 -221.475451) (xy 60.186166 -221.424396) (xy 60.174583 -221.37115) (xy 60.170696 -221.316798)
			(xy 27.405584 -221.316798) (xy 27.405584 -229.16007) (xy 39.818564 -229.16007) (xy 39.819058 -229.102661)
			(xy 39.826902 -228.988113) (xy 39.842544 -228.874366) (xy 39.865911 -228.761952) (xy 39.896896 -228.651394)
			(xy 39.935352 -228.543209) (xy 39.981101 -228.4379) (xy 40.03393 -228.335958) (xy 40.093592 -228.237859)
			(xy 40.159809 -228.14406) (xy 40.232272 -228.054998) (xy 40.310645 -227.971089) (xy 40.39456 -227.892723)
			(xy 40.483627 -227.820266) (xy 40.577431 -227.754056) (xy 40.675535 -227.694402) (xy 40.777481 -227.641581)
			(xy 40.882793 -227.595839) (xy 40.990981 -227.557391) (xy 41.101541 -227.526415) (xy 41.213957 -227.503056)
			(xy 41.327705 -227.487423) (xy 41.442254 -227.479588) (xy 41.557072 -227.479588) (xy 41.671621 -227.487423)
			(xy 41.785369 -227.503056) (xy 41.897785 -227.526415) (xy 42.008345 -227.557391) (xy 42.116533 -227.595839)
			(xy 42.221845 -227.641581) (xy 42.323791 -227.694402) (xy 42.421895 -227.754056) (xy 42.501239 -227.81006)
			(xy 63.647577 -227.81006) (xy 63.651612 -227.734356) (xy 63.663671 -227.659511) (xy 63.683617 -227.58637)
			(xy 63.711224 -227.515765) (xy 63.74618 -227.448494) (xy 63.788088 -227.385319) (xy 63.836474 -227.326957)
			(xy 63.89079 -227.274069) (xy 63.950419 -227.227254) (xy 64.014687 -227.187042) (xy 64.082864 -227.15389)
			(xy 64.15418 -227.128172) (xy 64.227825 -227.11018) (xy 64.302965 -227.100118) (xy 64.378749 -227.098099)
			(xy 64.454319 -227.104148) (xy 64.528817 -227.118195) (xy 64.6014 -227.140081) (xy 64.671246 -227.169558)
			(xy 64.737563 -227.206293) (xy 64.799599 -227.249868) (xy 64.856652 -227.29979) (xy 64.908076 -227.355494)
			(xy 64.953287 -227.416349) (xy 64.991774 -227.481664) (xy 65.0231 -227.5507) (xy 65.04691 -227.622675)
			(xy 65.062935 -227.696773) (xy 65.070994 -227.772154) (xy 65.071498 -227.81006) (xy 66.187577 -227.81006)
			(xy 66.191612 -227.734356) (xy 66.203671 -227.659511) (xy 66.223617 -227.58637) (xy 66.251224 -227.515765)
			(xy 66.28618 -227.448494) (xy 66.328088 -227.385319) (xy 66.376474 -227.326957) (xy 66.43079 -227.274069)
			(xy 66.490419 -227.227254) (xy 66.554687 -227.187042) (xy 66.622864 -227.15389) (xy 66.69418 -227.128172)
			(xy 66.767825 -227.11018) (xy 66.842965 -227.100118) (xy 66.918749 -227.098099) (xy 66.994319 -227.104148)
			(xy 67.068817 -227.118195) (xy 67.1414 -227.140081) (xy 67.211246 -227.169558) (xy 67.277563 -227.206293)
			(xy 67.339599 -227.249868) (xy 67.396652 -227.29979) (xy 67.448076 -227.355494) (xy 67.493287 -227.416349)
			(xy 67.531774 -227.481664) (xy 67.5631 -227.5507) (xy 67.58691 -227.622675) (xy 67.602935 -227.696773)
			(xy 67.610994 -227.772154) (xy 67.611498 -227.81006) (xy 68.727577 -227.81006) (xy 68.731612 -227.734356)
			(xy 68.743671 -227.659511) (xy 68.763617 -227.58637) (xy 68.791224 -227.515765) (xy 68.82618 -227.448494)
			(xy 68.868088 -227.385319) (xy 68.916474 -227.326957) (xy 68.97079 -227.274069) (xy 69.030419 -227.227254)
			(xy 69.094687 -227.187042) (xy 69.162864 -227.15389) (xy 69.23418 -227.128172) (xy 69.307825 -227.11018)
			(xy 69.382965 -227.100118) (xy 69.458749 -227.098099) (xy 69.534319 -227.104148) (xy 69.608817 -227.118195)
			(xy 69.6814 -227.140081) (xy 69.751246 -227.169558) (xy 69.817563 -227.206293) (xy 69.879599 -227.249868)
			(xy 69.936652 -227.29979) (xy 69.988076 -227.355494) (xy 70.033287 -227.416349) (xy 70.071774 -227.481664)
			(xy 70.1031 -227.5507) (xy 70.12691 -227.622675) (xy 70.142935 -227.696773) (xy 70.150994 -227.772154)
			(xy 70.151498 -227.81006) (xy 71.267577 -227.81006) (xy 71.271612 -227.734356) (xy 71.283671 -227.659511)
			(xy 71.303617 -227.58637) (xy 71.331224 -227.515765) (xy 71.36618 -227.448494) (xy 71.408088 -227.385319)
			(xy 71.456474 -227.326957) (xy 71.51079 -227.274069) (xy 71.570419 -227.227254) (xy 71.634687 -227.187042)
			(xy 71.702864 -227.15389) (xy 71.77418 -227.128172) (xy 71.847825 -227.11018) (xy 71.922965 -227.100118)
			(xy 71.998749 -227.098099) (xy 72.074319 -227.104148) (xy 72.148817 -227.118195) (xy 72.2214 -227.140081)
			(xy 72.291246 -227.169558) (xy 72.357563 -227.206293) (xy 72.419599 -227.249868) (xy 72.476652 -227.29979)
			(xy 72.528076 -227.355494) (xy 72.573287 -227.416349) (xy 72.611774 -227.481664) (xy 72.6431 -227.5507)
			(xy 72.66691 -227.622675) (xy 72.682935 -227.696773) (xy 72.690994 -227.772154) (xy 72.691498 -227.81006)
			(xy 73.807577 -227.81006) (xy 73.811612 -227.734356) (xy 73.823671 -227.659511) (xy 73.843617 -227.58637)
			(xy 73.871224 -227.515765) (xy 73.90618 -227.448494) (xy 73.948088 -227.385319) (xy 73.996474 -227.326957)
			(xy 74.05079 -227.274069) (xy 74.110419 -227.227254) (xy 74.174687 -227.187042) (xy 74.242864 -227.15389)
			(xy 74.31418 -227.128172) (xy 74.387825 -227.11018) (xy 74.462965 -227.100118) (xy 74.538749 -227.098099)
			(xy 74.614319 -227.104148) (xy 74.688817 -227.118195) (xy 74.7614 -227.140081) (xy 74.831246 -227.169558)
			(xy 74.897563 -227.206293) (xy 74.959599 -227.249868) (xy 75.016652 -227.29979) (xy 75.068076 -227.355494)
			(xy 75.113287 -227.416349) (xy 75.151774 -227.481664) (xy 75.1831 -227.5507) (xy 75.20691 -227.622675)
			(xy 75.222935 -227.696773) (xy 75.230994 -227.772154) (xy 75.231498 -227.81006) (xy 76.347577 -227.81006)
			(xy 76.351612 -227.734356) (xy 76.363671 -227.659511) (xy 76.383617 -227.58637) (xy 76.411224 -227.515765)
			(xy 76.44618 -227.448494) (xy 76.488088 -227.385319) (xy 76.536474 -227.326957) (xy 76.59079 -227.274069)
			(xy 76.650419 -227.227254) (xy 76.714687 -227.187042) (xy 76.782864 -227.15389) (xy 76.85418 -227.128172)
			(xy 76.927825 -227.11018) (xy 77.002965 -227.100118) (xy 77.078749 -227.098099) (xy 77.154319 -227.104148)
			(xy 77.228817 -227.118195) (xy 77.3014 -227.140081) (xy 77.371246 -227.169558) (xy 77.437563 -227.206293)
			(xy 77.499599 -227.249868) (xy 77.556652 -227.29979) (xy 77.608076 -227.355494) (xy 77.653287 -227.416349)
			(xy 77.691774 -227.481664) (xy 77.7231 -227.5507) (xy 77.74691 -227.622675) (xy 77.762935 -227.696773)
			(xy 77.770994 -227.772154) (xy 77.771498 -227.81006) (xy 78.887577 -227.81006) (xy 78.891612 -227.734356)
			(xy 78.903671 -227.659511) (xy 78.923617 -227.58637) (xy 78.951224 -227.515765) (xy 78.98618 -227.448494)
			(xy 79.028088 -227.385319) (xy 79.076474 -227.326957) (xy 79.13079 -227.274069) (xy 79.190419 -227.227254)
			(xy 79.254687 -227.187042) (xy 79.322864 -227.15389) (xy 79.39418 -227.128172) (xy 79.467825 -227.11018)
			(xy 79.542965 -227.100118) (xy 79.618749 -227.098099) (xy 79.694319 -227.104148) (xy 79.768817 -227.118195)
			(xy 79.8414 -227.140081) (xy 79.911246 -227.169558) (xy 79.977563 -227.206293) (xy 80.039599 -227.249868)
			(xy 80.096652 -227.29979) (xy 80.148076 -227.355494) (xy 80.193287 -227.416349) (xy 80.231774 -227.481664)
			(xy 80.2631 -227.5507) (xy 80.28691 -227.622675) (xy 80.302935 -227.696773) (xy 80.310994 -227.772154)
			(xy 80.311498 -227.81006) (xy 81.427577 -227.81006) (xy 81.431612 -227.734356) (xy 81.443671 -227.659511)
			(xy 81.463617 -227.58637) (xy 81.491224 -227.515765) (xy 81.52618 -227.448494) (xy 81.568088 -227.385319)
			(xy 81.616474 -227.326957) (xy 81.67079 -227.274069) (xy 81.730419 -227.227254) (xy 81.794687 -227.187042)
			(xy 81.862864 -227.15389) (xy 81.93418 -227.128172) (xy 82.007825 -227.11018) (xy 82.082965 -227.100118)
			(xy 82.158749 -227.098099) (xy 82.234319 -227.104148) (xy 82.308817 -227.118195) (xy 82.3814 -227.140081)
			(xy 82.451246 -227.169558) (xy 82.517563 -227.206293) (xy 82.579599 -227.249868) (xy 82.636652 -227.29979)
			(xy 82.688076 -227.355494) (xy 82.733287 -227.416349) (xy 82.771774 -227.481664) (xy 82.8031 -227.5507)
			(xy 82.82691 -227.622675) (xy 82.842935 -227.696773) (xy 82.850994 -227.772154) (xy 82.851498 -227.81006)
			(xy 82.850994 -227.847966) (xy 82.842935 -227.923347) (xy 82.82691 -227.997445) (xy 82.8031 -228.06942)
			(xy 82.771774 -228.138456) (xy 82.733287 -228.203771) (xy 82.688076 -228.264626) (xy 82.636652 -228.32033)
			(xy 82.579599 -228.370252) (xy 82.517563 -228.413827) (xy 82.451246 -228.450562) (xy 82.3814 -228.480039)
			(xy 82.308817 -228.501925) (xy 82.234319 -228.515972) (xy 82.158749 -228.522021) (xy 82.082965 -228.520002)
			(xy 82.007825 -228.50994) (xy 81.93418 -228.491948) (xy 81.862864 -228.46623) (xy 81.794687 -228.433078)
			(xy 81.730419 -228.392866) (xy 81.67079 -228.346051) (xy 81.616474 -228.293163) (xy 81.568088 -228.234801)
			(xy 81.52618 -228.171626) (xy 81.491224 -228.104355) (xy 81.463617 -228.03375) (xy 81.443671 -227.960609)
			(xy 81.431612 -227.885764) (xy 81.427577 -227.81006) (xy 80.311498 -227.81006) (xy 80.310994 -227.847966)
			(xy 80.302935 -227.923347) (xy 80.28691 -227.997445) (xy 80.2631 -228.06942) (xy 80.231774 -228.138456)
			(xy 80.193287 -228.203771) (xy 80.148076 -228.264626) (xy 80.096652 -228.32033) (xy 80.039599 -228.370252)
			(xy 79.977563 -228.413827) (xy 79.911246 -228.450562) (xy 79.8414 -228.480039) (xy 79.768817 -228.501925)
			(xy 79.694319 -228.515972) (xy 79.618749 -228.522021) (xy 79.542965 -228.520002) (xy 79.467825 -228.50994)
			(xy 79.39418 -228.491948) (xy 79.322864 -228.46623) (xy 79.254687 -228.433078) (xy 79.190419 -228.392866)
			(xy 79.13079 -228.346051) (xy 79.076474 -228.293163) (xy 79.028088 -228.234801) (xy 78.98618 -228.171626)
			(xy 78.951224 -228.104355) (xy 78.923617 -228.03375) (xy 78.903671 -227.960609) (xy 78.891612 -227.885764)
			(xy 78.887577 -227.81006) (xy 77.771498 -227.81006) (xy 77.770994 -227.847966) (xy 77.762935 -227.923347)
			(xy 77.74691 -227.997445) (xy 77.7231 -228.06942) (xy 77.691774 -228.138456) (xy 77.653287 -228.203771)
			(xy 77.608076 -228.264626) (xy 77.556652 -228.32033) (xy 77.499599 -228.370252) (xy 77.437563 -228.413827)
			(xy 77.371246 -228.450562) (xy 77.3014 -228.480039) (xy 77.228817 -228.501925) (xy 77.154319 -228.515972)
			(xy 77.078749 -228.522021) (xy 77.002965 -228.520002) (xy 76.927825 -228.50994) (xy 76.85418 -228.491948)
			(xy 76.782864 -228.46623) (xy 76.714687 -228.433078) (xy 76.650419 -228.392866) (xy 76.59079 -228.346051)
			(xy 76.536474 -228.293163) (xy 76.488088 -228.234801) (xy 76.44618 -228.171626) (xy 76.411224 -228.104355)
			(xy 76.383617 -228.03375) (xy 76.363671 -227.960609) (xy 76.351612 -227.885764) (xy 76.347577 -227.81006)
			(xy 75.231498 -227.81006) (xy 75.230994 -227.847966) (xy 75.222935 -227.923347) (xy 75.20691 -227.997445)
			(xy 75.1831 -228.06942) (xy 75.151774 -228.138456) (xy 75.113287 -228.203771) (xy 75.068076 -228.264626)
			(xy 75.016652 -228.32033) (xy 74.959599 -228.370252) (xy 74.897563 -228.413827) (xy 74.831246 -228.450562)
			(xy 74.7614 -228.480039) (xy 74.688817 -228.501925) (xy 74.614319 -228.515972) (xy 74.538749 -228.522021)
			(xy 74.462965 -228.520002) (xy 74.387825 -228.50994) (xy 74.31418 -228.491948) (xy 74.242864 -228.46623)
			(xy 74.174687 -228.433078) (xy 74.110419 -228.392866) (xy 74.05079 -228.346051) (xy 73.996474 -228.293163)
			(xy 73.948088 -228.234801) (xy 73.90618 -228.171626) (xy 73.871224 -228.104355) (xy 73.843617 -228.03375)
			(xy 73.823671 -227.960609) (xy 73.811612 -227.885764) (xy 73.807577 -227.81006) (xy 72.691498 -227.81006)
			(xy 72.690994 -227.847966) (xy 72.682935 -227.923347) (xy 72.66691 -227.997445) (xy 72.6431 -228.06942)
			(xy 72.611774 -228.138456) (xy 72.573287 -228.203771) (xy 72.528076 -228.264626) (xy 72.476652 -228.32033)
			(xy 72.419599 -228.370252) (xy 72.357563 -228.413827) (xy 72.291246 -228.450562) (xy 72.2214 -228.480039)
			(xy 72.148817 -228.501925) (xy 72.074319 -228.515972) (xy 71.998749 -228.522021) (xy 71.922965 -228.520002)
			(xy 71.847825 -228.50994) (xy 71.77418 -228.491948) (xy 71.702864 -228.46623) (xy 71.634687 -228.433078)
			(xy 71.570419 -228.392866) (xy 71.51079 -228.346051) (xy 71.456474 -228.293163) (xy 71.408088 -228.234801)
			(xy 71.36618 -228.171626) (xy 71.331224 -228.104355) (xy 71.303617 -228.03375) (xy 71.283671 -227.960609)
			(xy 71.271612 -227.885764) (xy 71.267577 -227.81006) (xy 70.151498 -227.81006) (xy 70.150994 -227.847966)
			(xy 70.142935 -227.923347) (xy 70.12691 -227.997445) (xy 70.1031 -228.06942) (xy 70.071774 -228.138456)
			(xy 70.033287 -228.203771) (xy 69.988076 -228.264626) (xy 69.936652 -228.32033) (xy 69.879599 -228.370252)
			(xy 69.817563 -228.413827) (xy 69.751246 -228.450562) (xy 69.6814 -228.480039) (xy 69.608817 -228.501925)
			(xy 69.534319 -228.515972) (xy 69.458749 -228.522021) (xy 69.382965 -228.520002) (xy 69.307825 -228.50994)
			(xy 69.23418 -228.491948) (xy 69.162864 -228.46623) (xy 69.094687 -228.433078) (xy 69.030419 -228.392866)
			(xy 68.97079 -228.346051) (xy 68.916474 -228.293163) (xy 68.868088 -228.234801) (xy 68.82618 -228.171626)
			(xy 68.791224 -228.104355) (xy 68.763617 -228.03375) (xy 68.743671 -227.960609) (xy 68.731612 -227.885764)
			(xy 68.727577 -227.81006) (xy 67.611498 -227.81006) (xy 67.610994 -227.847966) (xy 67.602935 -227.923347)
			(xy 67.58691 -227.997445) (xy 67.5631 -228.06942) (xy 67.531774 -228.138456) (xy 67.493287 -228.203771)
			(xy 67.448076 -228.264626) (xy 67.396652 -228.32033) (xy 67.339599 -228.370252) (xy 67.277563 -228.413827)
			(xy 67.211246 -228.450562) (xy 67.1414 -228.480039) (xy 67.068817 -228.501925) (xy 66.994319 -228.515972)
			(xy 66.918749 -228.522021) (xy 66.842965 -228.520002) (xy 66.767825 -228.50994) (xy 66.69418 -228.491948)
			(xy 66.622864 -228.46623) (xy 66.554687 -228.433078) (xy 66.490419 -228.392866) (xy 66.43079 -228.346051)
			(xy 66.376474 -228.293163) (xy 66.328088 -228.234801) (xy 66.28618 -228.171626) (xy 66.251224 -228.104355)
			(xy 66.223617 -228.03375) (xy 66.203671 -227.960609) (xy 66.191612 -227.885764) (xy 66.187577 -227.81006)
			(xy 65.071498 -227.81006) (xy 65.070994 -227.847966) (xy 65.062935 -227.923347) (xy 65.04691 -227.997445)
			(xy 65.0231 -228.06942) (xy 64.991774 -228.138456) (xy 64.953287 -228.203771) (xy 64.908076 -228.264626)
			(xy 64.856652 -228.32033) (xy 64.799599 -228.370252) (xy 64.737563 -228.413827) (xy 64.671246 -228.450562)
			(xy 64.6014 -228.480039) (xy 64.528817 -228.501925) (xy 64.454319 -228.515972) (xy 64.378749 -228.522021)
			(xy 64.302965 -228.520002) (xy 64.227825 -228.50994) (xy 64.15418 -228.491948) (xy 64.082864 -228.46623)
			(xy 64.014687 -228.433078) (xy 63.950419 -228.392866) (xy 63.89079 -228.346051) (xy 63.836474 -228.293163)
			(xy 63.788088 -228.234801) (xy 63.74618 -228.171626) (xy 63.711224 -228.104355) (xy 63.683617 -228.03375)
			(xy 63.663671 -227.960609) (xy 63.651612 -227.885764) (xy 63.647577 -227.81006) (xy 42.501239 -227.81006)
			(xy 42.515699 -227.820266) (xy 42.604766 -227.892723) (xy 42.688681 -227.971089) (xy 42.767054 -228.054998)
			(xy 42.839517 -228.14406) (xy 42.905734 -228.237859) (xy 42.965396 -228.335958) (xy 43.018225 -228.4379)
			(xy 43.063974 -228.543209) (xy 43.10243 -228.651394) (xy 43.133415 -228.761952) (xy 43.156782 -228.874366)
			(xy 43.172424 -228.988113) (xy 43.180268 -229.102661) (xy 43.180762 -229.16007) (xy 43.180576 -229.193253)
			(xy 43.177909 -229.259567) (xy 43.175428 -229.292658) (xy 43.170272 -229.350942) (xy 43.152948 -229.466671)
			(xy 43.127616 -229.580914) (xy 43.094401 -229.693119) (xy 43.053462 -229.802742) (xy 43.004999 -229.909253)
			(xy 42.949245 -230.012135) (xy 42.886471 -230.110891) (xy 42.816981 -230.205042) (xy 42.741111 -230.294132)
			(xy 42.659229 -230.377729) (xy 42.571732 -230.45543) (xy 42.500813 -230.51008) (xy 63.647577 -230.51008)
			(xy 63.651612 -230.434376) (xy 63.663671 -230.359531) (xy 63.683617 -230.28639) (xy 63.711224 -230.215785)
			(xy 63.74618 -230.148514) (xy 63.788088 -230.085339) (xy 63.836474 -230.026977) (xy 63.89079 -229.974089)
			(xy 63.950419 -229.927274) (xy 64.014687 -229.887062) (xy 64.082864 -229.85391) (xy 64.15418 -229.828192)
			(xy 64.227825 -229.8102) (xy 64.302965 -229.800138) (xy 64.378749 -229.798119) (xy 64.454319 -229.804168)
			(xy 64.528817 -229.818215) (xy 64.6014 -229.840101) (xy 64.671246 -229.869578) (xy 64.737563 -229.906313)
			(xy 64.799599 -229.949888) (xy 64.856652 -229.99981) (xy 64.908076 -230.055514) (xy 64.953287 -230.116369)
			(xy 64.991774 -230.181684) (xy 65.0231 -230.25072) (xy 65.04691 -230.322695) (xy 65.062935 -230.396793)
			(xy 65.070994 -230.472174) (xy 65.071498 -230.51008) (xy 66.187577 -230.51008) (xy 66.191612 -230.434376)
			(xy 66.203671 -230.359531) (xy 66.223617 -230.28639) (xy 66.251224 -230.215785) (xy 66.28618 -230.148514)
			(xy 66.328088 -230.085339) (xy 66.376474 -230.026977) (xy 66.43079 -229.974089) (xy 66.490419 -229.927274)
			(xy 66.554687 -229.887062) (xy 66.622864 -229.85391) (xy 66.69418 -229.828192) (xy 66.767825 -229.8102)
			(xy 66.842965 -229.800138) (xy 66.918749 -229.798119) (xy 66.994319 -229.804168) (xy 67.068817 -229.818215)
			(xy 67.1414 -229.840101) (xy 67.211246 -229.869578) (xy 67.277563 -229.906313) (xy 67.339599 -229.949888)
			(xy 67.396652 -229.99981) (xy 67.448076 -230.055514) (xy 67.493287 -230.116369) (xy 67.531774 -230.181684)
			(xy 67.5631 -230.25072) (xy 67.58691 -230.322695) (xy 67.602935 -230.396793) (xy 67.610994 -230.472174)
			(xy 67.611498 -230.51008) (xy 68.727577 -230.51008) (xy 68.731612 -230.434376) (xy 68.743671 -230.359531)
			(xy 68.763617 -230.28639) (xy 68.791224 -230.215785) (xy 68.82618 -230.148514) (xy 68.868088 -230.085339)
			(xy 68.916474 -230.026977) (xy 68.97079 -229.974089) (xy 69.030419 -229.927274) (xy 69.094687 -229.887062)
			(xy 69.162864 -229.85391) (xy 69.23418 -229.828192) (xy 69.307825 -229.8102) (xy 69.382965 -229.800138)
			(xy 69.458749 -229.798119) (xy 69.534319 -229.804168) (xy 69.608817 -229.818215) (xy 69.6814 -229.840101)
			(xy 69.751246 -229.869578) (xy 69.817563 -229.906313) (xy 69.879599 -229.949888) (xy 69.936652 -229.99981)
			(xy 69.988076 -230.055514) (xy 70.033287 -230.116369) (xy 70.071774 -230.181684) (xy 70.1031 -230.25072)
			(xy 70.12691 -230.322695) (xy 70.142935 -230.396793) (xy 70.150994 -230.472174) (xy 70.151498 -230.51008)
			(xy 71.267577 -230.51008) (xy 71.271612 -230.434376) (xy 71.283671 -230.359531) (xy 71.303617 -230.28639)
			(xy 71.331224 -230.215785) (xy 71.36618 -230.148514) (xy 71.408088 -230.085339) (xy 71.456474 -230.026977)
			(xy 71.51079 -229.974089) (xy 71.570419 -229.927274) (xy 71.634687 -229.887062) (xy 71.702864 -229.85391)
			(xy 71.77418 -229.828192) (xy 71.847825 -229.8102) (xy 71.922965 -229.800138) (xy 71.998749 -229.798119)
			(xy 72.074319 -229.804168) (xy 72.148817 -229.818215) (xy 72.2214 -229.840101) (xy 72.291246 -229.869578)
			(xy 72.357563 -229.906313) (xy 72.419599 -229.949888) (xy 72.476652 -229.99981) (xy 72.528076 -230.055514)
			(xy 72.573287 -230.116369) (xy 72.611774 -230.181684) (xy 72.6431 -230.25072) (xy 72.66691 -230.322695)
			(xy 72.682935 -230.396793) (xy 72.690994 -230.472174) (xy 72.691498 -230.51008) (xy 73.807577 -230.51008)
			(xy 73.811612 -230.434376) (xy 73.823671 -230.359531) (xy 73.843617 -230.28639) (xy 73.871224 -230.215785)
			(xy 73.90618 -230.148514) (xy 73.948088 -230.085339) (xy 73.996474 -230.026977) (xy 74.05079 -229.974089)
			(xy 74.110419 -229.927274) (xy 74.174687 -229.887062) (xy 74.242864 -229.85391) (xy 74.31418 -229.828192)
			(xy 74.387825 -229.8102) (xy 74.462965 -229.800138) (xy 74.538749 -229.798119) (xy 74.614319 -229.804168)
			(xy 74.688817 -229.818215) (xy 74.7614 -229.840101) (xy 74.831246 -229.869578) (xy 74.897563 -229.906313)
			(xy 74.959599 -229.949888) (xy 75.016652 -229.99981) (xy 75.068076 -230.055514) (xy 75.113287 -230.116369)
			(xy 75.151774 -230.181684) (xy 75.1831 -230.25072) (xy 75.20691 -230.322695) (xy 75.222935 -230.396793)
			(xy 75.230994 -230.472174) (xy 75.231498 -230.51008) (xy 76.347577 -230.51008) (xy 76.351612 -230.434376)
			(xy 76.363671 -230.359531) (xy 76.383617 -230.28639) (xy 76.411224 -230.215785) (xy 76.44618 -230.148514)
			(xy 76.488088 -230.085339) (xy 76.536474 -230.026977) (xy 76.59079 -229.974089) (xy 76.650419 -229.927274)
			(xy 76.714687 -229.887062) (xy 76.782864 -229.85391) (xy 76.85418 -229.828192) (xy 76.927825 -229.8102)
			(xy 77.002965 -229.800138) (xy 77.078749 -229.798119) (xy 77.154319 -229.804168) (xy 77.228817 -229.818215)
			(xy 77.3014 -229.840101) (xy 77.371246 -229.869578) (xy 77.437563 -229.906313) (xy 77.499599 -229.949888)
			(xy 77.556652 -229.99981) (xy 77.608076 -230.055514) (xy 77.653287 -230.116369) (xy 77.691774 -230.181684)
			(xy 77.7231 -230.25072) (xy 77.74691 -230.322695) (xy 77.762935 -230.396793) (xy 77.770994 -230.472174)
			(xy 77.771498 -230.51008) (xy 78.887577 -230.51008) (xy 78.891612 -230.434376) (xy 78.903671 -230.359531)
			(xy 78.923617 -230.28639) (xy 78.951224 -230.215785) (xy 78.98618 -230.148514) (xy 79.028088 -230.085339)
			(xy 79.076474 -230.026977) (xy 79.13079 -229.974089) (xy 79.190419 -229.927274) (xy 79.254687 -229.887062)
			(xy 79.322864 -229.85391) (xy 79.39418 -229.828192) (xy 79.467825 -229.8102) (xy 79.542965 -229.800138)
			(xy 79.618749 -229.798119) (xy 79.694319 -229.804168) (xy 79.768817 -229.818215) (xy 79.8414 -229.840101)
			(xy 79.911246 -229.869578) (xy 79.977563 -229.906313) (xy 80.039599 -229.949888) (xy 80.096652 -229.99981)
			(xy 80.148076 -230.055514) (xy 80.193287 -230.116369) (xy 80.231774 -230.181684) (xy 80.2631 -230.25072)
			(xy 80.28691 -230.322695) (xy 80.302935 -230.396793) (xy 80.310994 -230.472174) (xy 80.311498 -230.51008)
			(xy 80.310994 -230.547986) (xy 80.302935 -230.623367) (xy 80.28691 -230.697465) (xy 80.2631 -230.76944)
			(xy 80.231774 -230.838476) (xy 80.193287 -230.903791) (xy 80.148076 -230.964646) (xy 80.096652 -231.02035)
			(xy 80.039599 -231.070272) (xy 79.977563 -231.113847) (xy 79.911246 -231.150582) (xy 79.8414 -231.180059)
			(xy 79.768817 -231.201945) (xy 79.694319 -231.215992) (xy 79.618749 -231.222041) (xy 79.542965 -231.220022)
			(xy 79.467825 -231.20996) (xy 79.39418 -231.191968) (xy 79.322864 -231.16625) (xy 79.254687 -231.133098)
			(xy 79.190419 -231.092886) (xy 79.13079 -231.046071) (xy 79.076474 -230.993183) (xy 79.028088 -230.934821)
			(xy 78.98618 -230.871646) (xy 78.951224 -230.804375) (xy 78.923617 -230.73377) (xy 78.903671 -230.660629)
			(xy 78.891612 -230.585784) (xy 78.887577 -230.51008) (xy 77.771498 -230.51008) (xy 77.770994 -230.547986)
			(xy 77.762935 -230.623367) (xy 77.74691 -230.697465) (xy 77.7231 -230.76944) (xy 77.691774 -230.838476)
			(xy 77.653287 -230.903791) (xy 77.608076 -230.964646) (xy 77.556652 -231.02035) (xy 77.499599 -231.070272)
			(xy 77.437563 -231.113847) (xy 77.371246 -231.150582) (xy 77.3014 -231.180059) (xy 77.228817 -231.201945)
			(xy 77.154319 -231.215992) (xy 77.078749 -231.222041) (xy 77.002965 -231.220022) (xy 76.927825 -231.20996)
			(xy 76.85418 -231.191968) (xy 76.782864 -231.16625) (xy 76.714687 -231.133098) (xy 76.650419 -231.092886)
			(xy 76.59079 -231.046071) (xy 76.536474 -230.993183) (xy 76.488088 -230.934821) (xy 76.44618 -230.871646)
			(xy 76.411224 -230.804375) (xy 76.383617 -230.73377) (xy 76.363671 -230.660629) (xy 76.351612 -230.585784)
			(xy 76.347577 -230.51008) (xy 75.231498 -230.51008) (xy 75.230994 -230.547986) (xy 75.222935 -230.623367)
			(xy 75.20691 -230.697465) (xy 75.1831 -230.76944) (xy 75.151774 -230.838476) (xy 75.113287 -230.903791)
			(xy 75.068076 -230.964646) (xy 75.016652 -231.02035) (xy 74.959599 -231.070272) (xy 74.897563 -231.113847)
			(xy 74.831246 -231.150582) (xy 74.7614 -231.180059) (xy 74.688817 -231.201945) (xy 74.614319 -231.215992)
			(xy 74.538749 -231.222041) (xy 74.462965 -231.220022) (xy 74.387825 -231.20996) (xy 74.31418 -231.191968)
			(xy 74.242864 -231.16625) (xy 74.174687 -231.133098) (xy 74.110419 -231.092886) (xy 74.05079 -231.046071)
			(xy 73.996474 -230.993183) (xy 73.948088 -230.934821) (xy 73.90618 -230.871646) (xy 73.871224 -230.804375)
			(xy 73.843617 -230.73377) (xy 73.823671 -230.660629) (xy 73.811612 -230.585784) (xy 73.807577 -230.51008)
			(xy 72.691498 -230.51008) (xy 72.690994 -230.547986) (xy 72.682935 -230.623367) (xy 72.66691 -230.697465)
			(xy 72.6431 -230.76944) (xy 72.611774 -230.838476) (xy 72.573287 -230.903791) (xy 72.528076 -230.964646)
			(xy 72.476652 -231.02035) (xy 72.419599 -231.070272) (xy 72.357563 -231.113847) (xy 72.291246 -231.150582)
			(xy 72.2214 -231.180059) (xy 72.148817 -231.201945) (xy 72.074319 -231.215992) (xy 71.998749 -231.222041)
			(xy 71.922965 -231.220022) (xy 71.847825 -231.20996) (xy 71.77418 -231.191968) (xy 71.702864 -231.16625)
			(xy 71.634687 -231.133098) (xy 71.570419 -231.092886) (xy 71.51079 -231.046071) (xy 71.456474 -230.993183)
			(xy 71.408088 -230.934821) (xy 71.36618 -230.871646) (xy 71.331224 -230.804375) (xy 71.303617 -230.73377)
			(xy 71.283671 -230.660629) (xy 71.271612 -230.585784) (xy 71.267577 -230.51008) (xy 70.151498 -230.51008)
			(xy 70.150994 -230.547986) (xy 70.142935 -230.623367) (xy 70.12691 -230.697465) (xy 70.1031 -230.76944)
			(xy 70.071774 -230.838476) (xy 70.033287 -230.903791) (xy 69.988076 -230.964646) (xy 69.936652 -231.02035)
			(xy 69.879599 -231.070272) (xy 69.817563 -231.113847) (xy 69.751246 -231.150582) (xy 69.6814 -231.180059)
			(xy 69.608817 -231.201945) (xy 69.534319 -231.215992) (xy 69.458749 -231.222041) (xy 69.382965 -231.220022)
			(xy 69.307825 -231.20996) (xy 69.23418 -231.191968) (xy 69.162864 -231.16625) (xy 69.094687 -231.133098)
			(xy 69.030419 -231.092886) (xy 68.97079 -231.046071) (xy 68.916474 -230.993183) (xy 68.868088 -230.934821)
			(xy 68.82618 -230.871646) (xy 68.791224 -230.804375) (xy 68.763617 -230.73377) (xy 68.743671 -230.660629)
			(xy 68.731612 -230.585784) (xy 68.727577 -230.51008) (xy 67.611498 -230.51008) (xy 67.610994 -230.547986)
			(xy 67.602935 -230.623367) (xy 67.58691 -230.697465) (xy 67.5631 -230.76944) (xy 67.531774 -230.838476)
			(xy 67.493287 -230.903791) (xy 67.448076 -230.964646) (xy 67.396652 -231.02035) (xy 67.339599 -231.070272)
			(xy 67.277563 -231.113847) (xy 67.211246 -231.150582) (xy 67.1414 -231.180059) (xy 67.068817 -231.201945)
			(xy 66.994319 -231.215992) (xy 66.918749 -231.222041) (xy 66.842965 -231.220022) (xy 66.767825 -231.20996)
			(xy 66.69418 -231.191968) (xy 66.622864 -231.16625) (xy 66.554687 -231.133098) (xy 66.490419 -231.092886)
			(xy 66.43079 -231.046071) (xy 66.376474 -230.993183) (xy 66.328088 -230.934821) (xy 66.28618 -230.871646)
			(xy 66.251224 -230.804375) (xy 66.223617 -230.73377) (xy 66.203671 -230.660629) (xy 66.191612 -230.585784)
			(xy 66.187577 -230.51008) (xy 65.071498 -230.51008) (xy 65.070994 -230.547986) (xy 65.062935 -230.623367)
			(xy 65.04691 -230.697465) (xy 65.0231 -230.76944) (xy 64.991774 -230.838476) (xy 64.953287 -230.903791)
			(xy 64.908076 -230.964646) (xy 64.856652 -231.02035) (xy 64.799599 -231.070272) (xy 64.737563 -231.113847)
			(xy 64.671246 -231.150582) (xy 64.6014 -231.180059) (xy 64.528817 -231.201945) (xy 64.454319 -231.215992)
			(xy 64.378749 -231.222041) (xy 64.302965 -231.220022) (xy 64.227825 -231.20996) (xy 64.15418 -231.191968)
			(xy 64.082864 -231.16625) (xy 64.014687 -231.133098) (xy 63.950419 -231.092886) (xy 63.89079 -231.046071)
			(xy 63.836474 -230.993183) (xy 63.788088 -230.934821) (xy 63.74618 -230.871646) (xy 63.711224 -230.804375)
			(xy 63.683617 -230.73377) (xy 63.663671 -230.660629) (xy 63.651612 -230.585784) (xy 63.647577 -230.51008)
			(xy 42.500813 -230.51008) (xy 42.479042 -230.526857) (xy 42.381609 -230.591665) (xy 42.279905 -230.64954)
			(xy 42.174422 -230.700202) (xy 42.065671 -230.743404) (xy 41.954179 -230.778939) (xy 41.840485 -230.806634)
			(xy 41.725141 -230.826354) (xy 41.608704 -230.838005) (xy 41.491739 -230.84153) (xy 41.374812 -230.836912)
			(xy 41.258489 -230.824173) (xy 41.143334 -230.803375) (xy 41.029905 -230.774618) (xy 40.91875 -230.738042)
			(xy 40.810407 -230.693825) (xy 40.705403 -230.642179) (xy 40.604244 -230.583356) (xy 40.507421 -230.51764)
			(xy 40.415403 -230.445349) (xy 40.328636 -230.366834) (xy 40.247539 -230.282474) (xy 40.172506 -230.192679)
			(xy 40.103899 -230.097883) (xy 40.042051 -229.998544) (xy 39.987262 -229.895145) (xy 39.939796 -229.788186)
			(xy 39.899884 -229.678185) (xy 39.86772 -229.565674) (xy 39.843457 -229.451199) (xy 39.827215 -229.335313)
			(xy 39.819072 -229.218579) (xy 39.818564 -229.16007) (xy 27.405584 -229.16007) (xy 27.405584 -230.962708)
			(xy 26.134889 -232.233486) (xy 29.519874 -232.233486) (xy 29.519874 -232.146586) (xy 29.527892 -232.060057)
			(xy 29.54386 -231.974637) (xy 29.567641 -231.891055) (xy 29.599033 -231.810023) (xy 29.637767 -231.732234)
			(xy 29.683514 -231.65835) (xy 29.735883 -231.589003) (xy 29.794427 -231.524783) (xy 29.858647 -231.466239)
			(xy 29.927994 -231.41387) (xy 30.001878 -231.368123) (xy 30.079667 -231.329389) (xy 30.160699 -231.297997)
			(xy 30.244281 -231.274216) (xy 30.329701 -231.258248) (xy 30.41623 -231.25023) (xy 30.50313 -231.25023)
			(xy 30.589659 -231.258248) (xy 30.675079 -231.274216) (xy 30.758661 -231.297997) (xy 30.839693 -231.329389)
			(xy 30.917482 -231.368123) (xy 30.991366 -231.41387) (xy 31.060713 -231.466239) (xy 31.124933 -231.524783)
			(xy 31.183477 -231.589003) (xy 31.235846 -231.65835) (xy 31.281593 -231.732234) (xy 31.320327 -231.810023)
			(xy 31.351719 -231.891055) (xy 31.3755 -231.974637) (xy 31.391468 -232.060057) (xy 31.399486 -232.146586)
			(xy 31.399988 -232.190036) (xy 31.399486 -232.233486) (xy 34.599874 -232.233486) (xy 34.599874 -232.146586)
			(xy 34.607892 -232.060057) (xy 34.62386 -231.974637) (xy 34.647641 -231.891055) (xy 34.679033 -231.810023)
			(xy 34.717767 -231.732234) (xy 34.763514 -231.65835) (xy 34.815883 -231.589003) (xy 34.874427 -231.524783)
			(xy 34.938647 -231.466239) (xy 35.007994 -231.41387) (xy 35.081878 -231.368123) (xy 35.159667 -231.329389)
			(xy 35.240699 -231.297997) (xy 35.324281 -231.274216) (xy 35.409701 -231.258248) (xy 35.49623 -231.25023)
			(xy 35.58313 -231.25023) (xy 35.669659 -231.258248) (xy 35.755079 -231.274216) (xy 35.838661 -231.297997)
			(xy 35.919693 -231.329389) (xy 35.997482 -231.368123) (xy 36.071366 -231.41387) (xy 36.140713 -231.466239)
			(xy 36.204933 -231.524783) (xy 36.263477 -231.589003) (xy 36.315846 -231.65835) (xy 36.361593 -231.732234)
			(xy 36.400327 -231.810023) (xy 36.431719 -231.891055) (xy 36.4555 -231.974637) (xy 36.471468 -232.060057)
			(xy 36.479486 -232.146586) (xy 36.479988 -232.190036) (xy 36.479486 -232.233486) (xy 36.471468 -232.320015)
			(xy 36.4555 -232.405435) (xy 36.431719 -232.489017) (xy 36.400327 -232.570049) (xy 36.361593 -232.647838)
			(xy 36.315846 -232.721722) (xy 36.263477 -232.791069) (xy 36.204933 -232.855289) (xy 36.140713 -232.913833)
			(xy 36.071366 -232.966202) (xy 35.997482 -233.011949) (xy 35.919693 -233.050683) (xy 35.838661 -233.082075)
			(xy 35.755079 -233.105856) (xy 35.669659 -233.121824) (xy 35.58313 -233.129842) (xy 35.49623 -233.129842)
			(xy 35.409701 -233.121824) (xy 35.324281 -233.105856) (xy 35.240699 -233.082075) (xy 35.159667 -233.050683)
			(xy 35.081878 -233.011949) (xy 35.007994 -232.966202) (xy 34.938647 -232.913833) (xy 34.874427 -232.855289)
			(xy 34.815883 -232.791069) (xy 34.763514 -232.721722) (xy 34.717767 -232.647838) (xy 34.679033 -232.570049)
			(xy 34.647641 -232.489017) (xy 34.62386 -232.405435) (xy 34.607892 -232.320015) (xy 34.599874 -232.233486)
			(xy 31.399486 -232.233486) (xy 31.391468 -232.320015) (xy 31.3755 -232.405435) (xy 31.351719 -232.489017)
			(xy 31.320327 -232.570049) (xy 31.281593 -232.647838) (xy 31.235846 -232.721722) (xy 31.183477 -232.791069)
			(xy 31.124933 -232.855289) (xy 31.060713 -232.913833) (xy 30.991366 -232.966202) (xy 30.917482 -233.011949)
			(xy 30.839693 -233.050683) (xy 30.758661 -233.082075) (xy 30.675079 -233.105856) (xy 30.589659 -233.121824)
			(xy 30.50313 -233.129842) (xy 30.41623 -233.129842) (xy 30.329701 -233.121824) (xy 30.244281 -233.105856)
			(xy 30.160699 -233.082075) (xy 30.079667 -233.050683) (xy 30.001878 -233.011949) (xy 29.927994 -232.966202)
			(xy 29.858647 -232.913833) (xy 29.794427 -232.855289) (xy 29.735883 -232.791069) (xy 29.683514 -232.721722)
			(xy 29.637767 -232.647838) (xy 29.599033 -232.570049) (xy 29.567641 -232.489017) (xy 29.54386 -232.405435)
			(xy 29.527892 -232.320015) (xy 29.519874 -232.233486) (xy 26.134889 -232.233486) (xy 23.595054 -234.773486)
			(xy 29.519874 -234.773486) (xy 29.519874 -234.686586) (xy 29.527892 -234.600057) (xy 29.54386 -234.514637)
			(xy 29.567641 -234.431055) (xy 29.599033 -234.350023) (xy 29.637767 -234.272234) (xy 29.683514 -234.19835)
			(xy 29.735883 -234.129003) (xy 29.794427 -234.064783) (xy 29.858647 -234.006239) (xy 29.927994 -233.95387)
			(xy 30.001878 -233.908123) (xy 30.079667 -233.869389) (xy 30.160699 -233.837997) (xy 30.244281 -233.814216)
			(xy 30.329701 -233.798248) (xy 30.41623 -233.79023) (xy 30.50313 -233.79023) (xy 30.589659 -233.798248)
			(xy 30.675079 -233.814216) (xy 30.758661 -233.837997) (xy 30.839693 -233.869389) (xy 30.917482 -233.908123)
			(xy 30.991366 -233.95387) (xy 31.060713 -234.006239) (xy 31.124933 -234.064783) (xy 31.183477 -234.129003)
			(xy 31.235846 -234.19835) (xy 31.281593 -234.272234) (xy 31.320327 -234.350023) (xy 31.351719 -234.431055)
			(xy 31.3755 -234.514637) (xy 31.391468 -234.600057) (xy 31.399486 -234.686586) (xy 31.399988 -234.730036)
			(xy 31.399486 -234.773486) (xy 34.599874 -234.773486) (xy 34.599874 -234.686586) (xy 34.607892 -234.600057)
			(xy 34.62386 -234.514637) (xy 34.647641 -234.431055) (xy 34.679033 -234.350023) (xy 34.717767 -234.272234)
			(xy 34.763514 -234.19835) (xy 34.815883 -234.129003) (xy 34.874427 -234.064783) (xy 34.938647 -234.006239)
			(xy 35.007994 -233.95387) (xy 35.081878 -233.908123) (xy 35.159667 -233.869389) (xy 35.240699 -233.837997)
			(xy 35.324281 -233.814216) (xy 35.409701 -233.798248) (xy 35.49623 -233.79023) (xy 35.58313 -233.79023)
			(xy 35.669659 -233.798248) (xy 35.755079 -233.814216) (xy 35.838661 -233.837997) (xy 35.919693 -233.869389)
			(xy 35.997482 -233.908123) (xy 36.071366 -233.95387) (xy 36.140713 -234.006239) (xy 36.204933 -234.064783)
			(xy 36.263477 -234.129003) (xy 36.315846 -234.19835) (xy 36.361593 -234.272234) (xy 36.400327 -234.350023)
			(xy 36.431719 -234.431055) (xy 36.4555 -234.514637) (xy 36.471468 -234.600057) (xy 36.479486 -234.686586)
			(xy 36.479988 -234.730036) (xy 36.479486 -234.773486) (xy 36.471468 -234.860015) (xy 36.4555 -234.945435)
			(xy 36.431719 -235.029017) (xy 36.400327 -235.110049) (xy 36.361593 -235.187838) (xy 36.315846 -235.261722)
			(xy 36.263477 -235.331069) (xy 36.204933 -235.395289) (xy 36.140713 -235.453833) (xy 36.071366 -235.506202)
			(xy 35.997482 -235.551949) (xy 35.919693 -235.590683) (xy 35.838661 -235.622075) (xy 35.755079 -235.645856)
			(xy 35.669659 -235.661824) (xy 35.58313 -235.669842) (xy 35.49623 -235.669842) (xy 35.409701 -235.661824)
			(xy 35.324281 -235.645856) (xy 35.240699 -235.622075) (xy 35.159667 -235.590683) (xy 35.081878 -235.551949)
			(xy 35.007994 -235.506202) (xy 34.938647 -235.453833) (xy 34.874427 -235.395289) (xy 34.815883 -235.331069)
			(xy 34.763514 -235.261722) (xy 34.717767 -235.187838) (xy 34.679033 -235.110049) (xy 34.647641 -235.029017)
			(xy 34.62386 -234.945435) (xy 34.607892 -234.860015) (xy 34.599874 -234.773486) (xy 31.399486 -234.773486)
			(xy 31.391468 -234.860015) (xy 31.3755 -234.945435) (xy 31.351719 -235.029017) (xy 31.320327 -235.110049)
			(xy 31.281593 -235.187838) (xy 31.235846 -235.261722) (xy 31.183477 -235.331069) (xy 31.124933 -235.395289)
			(xy 31.060713 -235.453833) (xy 30.991366 -235.506202) (xy 30.917482 -235.551949) (xy 30.839693 -235.590683)
			(xy 30.758661 -235.622075) (xy 30.675079 -235.645856) (xy 30.589659 -235.661824) (xy 30.50313 -235.669842)
			(xy 30.41623 -235.669842) (xy 30.329701 -235.661824) (xy 30.244281 -235.645856) (xy 30.160699 -235.622075)
			(xy 30.079667 -235.590683) (xy 30.001878 -235.551949) (xy 29.927994 -235.506202) (xy 29.858647 -235.453833)
			(xy 29.794427 -235.395289) (xy 29.735883 -235.331069) (xy 29.683514 -235.261722) (xy 29.637767 -235.187838)
			(xy 29.599033 -235.110049) (xy 29.567641 -235.029017) (xy 29.54386 -234.945435) (xy 29.527892 -234.860015)
			(xy 29.519874 -234.773486) (xy 23.595054 -234.773486) (xy 23.502874 -234.865672) (xy 23.486772 -234.882523)
			(xy 23.460382 -234.920936) (xy 23.44143 -234.963512) (xy 23.430551 -235.008829) (xy 23.428107 -235.055368)
			(xy 23.434182 -235.101575) (xy 23.448572 -235.145902) (xy 23.470794 -235.186866) (xy 23.485094 -235.20527)
			(xy 23.501936 -235.22679) (xy 23.529938 -235.273715) (xy 23.550961 -235.324155) (xy 23.564573 -235.377078)
			(xy 23.570498 -235.431402) (xy 23.568613 -235.486015) (xy 23.558957 -235.539801) (xy 23.541727 -235.591659)
			(xy 23.517276 -235.640529) (xy 23.486105 -235.685412) (xy 23.448849 -235.725389) (xy 23.406273 -235.759644)
			(xy 23.359245 -235.787475) (xy 23.308729 -235.808312) (xy 23.255756 -235.821731) (xy 23.201411 -235.827457)
			(xy 23.146806 -235.825372) (xy 23.093056 -235.815519) (xy 23.06701 -235.80725) (xy 23.044747 -235.800291)
			(xy 22.998579 -235.793682) (xy 22.95198 -235.795597) (xy 22.90651 -235.805972) (xy 22.863693 -235.82446)
			(xy 22.824961 -235.850441) (xy 22.791613 -235.883046) (xy 22.764766 -235.921182) (xy 22.745318 -235.963572)
			(xy 22.733921 -236.008797) (xy 22.731984 -236.03204) (xy 22.731984 -237.313486) (xy 29.519874 -237.313486)
			(xy 29.519874 -237.226586) (xy 29.527892 -237.140057) (xy 29.54386 -237.054637) (xy 29.567641 -236.971055)
			(xy 29.599033 -236.890023) (xy 29.637767 -236.812234) (xy 29.683514 -236.73835) (xy 29.735883 -236.669003)
			(xy 29.794427 -236.604783) (xy 29.858647 -236.546239) (xy 29.927994 -236.49387) (xy 30.001878 -236.448123)
			(xy 30.079667 -236.409389) (xy 30.160699 -236.377997) (xy 30.244281 -236.354216) (xy 30.329701 -236.338248)
			(xy 30.41623 -236.33023) (xy 30.50313 -236.33023) (xy 30.589659 -236.338248) (xy 30.675079 -236.354216)
			(xy 30.758661 -236.377997) (xy 30.839693 -236.409389) (xy 30.917482 -236.448123) (xy 30.991366 -236.49387)
			(xy 31.060713 -236.546239) (xy 31.124933 -236.604783) (xy 31.183477 -236.669003) (xy 31.235846 -236.73835)
			(xy 31.281593 -236.812234) (xy 31.320327 -236.890023) (xy 31.351719 -236.971055) (xy 31.3755 -237.054637)
			(xy 31.391468 -237.140057) (xy 31.399486 -237.226586) (xy 31.399988 -237.270036) (xy 31.399486 -237.313486)
			(xy 34.599874 -237.313486) (xy 34.599874 -237.226586) (xy 34.607892 -237.140057) (xy 34.62386 -237.054637)
			(xy 34.647641 -236.971055) (xy 34.679033 -236.890023) (xy 34.717767 -236.812234) (xy 34.763514 -236.73835)
			(xy 34.815883 -236.669003) (xy 34.874427 -236.604783) (xy 34.938647 -236.546239) (xy 35.007994 -236.49387)
			(xy 35.081878 -236.448123) (xy 35.159667 -236.409389) (xy 35.240699 -236.377997) (xy 35.324281 -236.354216)
			(xy 35.409701 -236.338248) (xy 35.49623 -236.33023) (xy 35.58313 -236.33023) (xy 35.669659 -236.338248)
			(xy 35.755079 -236.354216) (xy 35.838661 -236.377997) (xy 35.919693 -236.409389) (xy 35.997482 -236.448123)
			(xy 36.071366 -236.49387) (xy 36.140713 -236.546239) (xy 36.204933 -236.604783) (xy 36.263477 -236.669003)
			(xy 36.315846 -236.73835) (xy 36.361593 -236.812234) (xy 36.400327 -236.890023) (xy 36.431719 -236.971055)
			(xy 36.4555 -237.054637) (xy 36.471468 -237.140057) (xy 36.479486 -237.226586) (xy 36.479988 -237.270036)
			(xy 36.479486 -237.313486) (xy 36.471468 -237.400015) (xy 36.4555 -237.485435) (xy 36.431719 -237.569017)
			(xy 36.400327 -237.650049) (xy 36.361593 -237.727838) (xy 36.315846 -237.801722) (xy 36.263477 -237.871069)
			(xy 36.204933 -237.935289) (xy 36.183787 -237.954566) (xy 44.324776 -237.954566) (xy 44.328847 -237.898944)
			(xy 44.340973 -237.844507) (xy 44.360896 -237.792416) (xy 44.388192 -237.743781) (xy 44.422278 -237.699638)
			(xy 44.462427 -237.660929) (xy 44.507785 -237.628478) (xy 44.557385 -237.602977) (xy 44.610169 -237.58497)
			(xy 44.665012 -237.57484) (xy 44.720746 -237.572803) (xy 44.776183 -237.578903) (xy 44.83014 -237.593009)
			(xy 44.881469 -237.614821) (xy 44.929075 -237.643875) (xy 44.971943 -237.67955) (xy 45.00916 -237.721087)
			(xy 45.039933 -237.7676) (xy 45.063605 -237.818097) (xy 45.079673 -237.871504) (xy 45.087793 -237.92668)
			(xy 45.088302 -237.954566) (xy 45.087793 -237.982452) (xy 45.079673 -238.037628) (xy 45.063605 -238.091035)
			(xy 45.039933 -238.141532) (xy 45.00916 -238.188045) (xy 44.971943 -238.229582) (xy 44.929075 -238.265257)
			(xy 44.881469 -238.294311) (xy 44.83014 -238.316123) (xy 44.776183 -238.330229) (xy 44.720746 -238.336329)
			(xy 44.665012 -238.334292) (xy 44.610169 -238.324162) (xy 44.557385 -238.306155) (xy 44.507785 -238.280654)
			(xy 44.462427 -238.248203) (xy 44.422278 -238.209494) (xy 44.388192 -238.165351) (xy 44.360896 -238.116716)
			(xy 44.340973 -238.064625) (xy 44.328847 -238.010188) (xy 44.324776 -237.954566) (xy 36.183787 -237.954566)
			(xy 36.140713 -237.993833) (xy 36.071366 -238.046202) (xy 35.997482 -238.091949) (xy 35.919693 -238.130683)
			(xy 35.838661 -238.162075) (xy 35.755079 -238.185856) (xy 35.669659 -238.201824) (xy 35.58313 -238.209842)
			(xy 35.49623 -238.209842) (xy 35.409701 -238.201824) (xy 35.324281 -238.185856) (xy 35.240699 -238.162075)
			(xy 35.159667 -238.130683) (xy 35.081878 -238.091949) (xy 35.007994 -238.046202) (xy 34.938647 -237.993833)
			(xy 34.874427 -237.935289) (xy 34.815883 -237.871069) (xy 34.763514 -237.801722) (xy 34.717767 -237.727838)
			(xy 34.679033 -237.650049) (xy 34.647641 -237.569017) (xy 34.62386 -237.485435) (xy 34.607892 -237.400015)
			(xy 34.599874 -237.313486) (xy 31.399486 -237.313486) (xy 31.391468 -237.400015) (xy 31.3755 -237.485435)
			(xy 31.351719 -237.569017) (xy 31.320327 -237.650049) (xy 31.281593 -237.727838) (xy 31.235846 -237.801722)
			(xy 31.183477 -237.871069) (xy 31.124933 -237.935289) (xy 31.060713 -237.993833) (xy 30.991366 -238.046202)
			(xy 30.917482 -238.091949) (xy 30.839693 -238.130683) (xy 30.758661 -238.162075) (xy 30.675079 -238.185856)
			(xy 30.589659 -238.201824) (xy 30.50313 -238.209842) (xy 30.41623 -238.209842) (xy 30.329701 -238.201824)
			(xy 30.244281 -238.185856) (xy 30.160699 -238.162075) (xy 30.079667 -238.130683) (xy 30.001878 -238.091949)
			(xy 29.927994 -238.046202) (xy 29.858647 -237.993833) (xy 29.794427 -237.935289) (xy 29.735883 -237.871069)
			(xy 29.683514 -237.801722) (xy 29.637767 -237.727838) (xy 29.599033 -237.650049) (xy 29.567641 -237.569017)
			(xy 29.54386 -237.485435) (xy 29.527892 -237.400015) (xy 29.519874 -237.313486) (xy 22.731984 -237.313486)
			(xy 22.731984 -237.445296) (xy 20.323886 -239.853486) (xy 29.519874 -239.853486) (xy 29.519874 -239.766586)
			(xy 29.527892 -239.680057) (xy 29.54386 -239.594637) (xy 29.567641 -239.511055) (xy 29.599033 -239.430023)
			(xy 29.637767 -239.352234) (xy 29.683514 -239.27835) (xy 29.735883 -239.209003) (xy 29.794427 -239.144783)
			(xy 29.858647 -239.086239) (xy 29.927994 -239.03387) (xy 30.001878 -238.988123) (xy 30.079667 -238.949389)
			(xy 30.160699 -238.917997) (xy 30.244281 -238.894216) (xy 30.329701 -238.878248) (xy 30.41623 -238.87023)
			(xy 30.50313 -238.87023) (xy 30.589659 -238.878248) (xy 30.675079 -238.894216) (xy 30.758661 -238.917997)
			(xy 30.839693 -238.949389) (xy 30.917482 -238.988123) (xy 30.991366 -239.03387) (xy 31.060713 -239.086239)
			(xy 31.124933 -239.144783) (xy 31.183477 -239.209003) (xy 31.235846 -239.27835) (xy 31.281593 -239.352234)
			(xy 31.320327 -239.430023) (xy 31.351719 -239.511055) (xy 31.3755 -239.594637) (xy 31.391468 -239.680057)
			(xy 31.399486 -239.766586) (xy 31.399988 -239.810036) (xy 31.399486 -239.853486) (xy 34.599874 -239.853486)
			(xy 34.599874 -239.766586) (xy 34.607892 -239.680057) (xy 34.62386 -239.594637) (xy 34.647641 -239.511055)
			(xy 34.679033 -239.430023) (xy 34.717767 -239.352234) (xy 34.763514 -239.27835) (xy 34.815883 -239.209003)
			(xy 34.874427 -239.144783) (xy 34.938647 -239.086239) (xy 35.007994 -239.03387) (xy 35.081878 -238.988123)
			(xy 35.159667 -238.949389) (xy 35.240699 -238.917997) (xy 35.324281 -238.894216) (xy 35.409701 -238.878248)
			(xy 35.49623 -238.87023) (xy 35.58313 -238.87023) (xy 35.669659 -238.878248) (xy 35.755079 -238.894216)
			(xy 35.838661 -238.917997) (xy 35.919693 -238.949389) (xy 35.997482 -238.988123) (xy 36.071366 -239.03387)
			(xy 36.140713 -239.086239) (xy 36.204933 -239.144783) (xy 36.263477 -239.209003) (xy 36.315846 -239.27835)
			(xy 36.361593 -239.352234) (xy 36.400327 -239.430023) (xy 36.431719 -239.511055) (xy 36.4555 -239.594637)
			(xy 36.471468 -239.680057) (xy 36.479486 -239.766586) (xy 36.479988 -239.810036) (xy 36.479486 -239.853486)
			(xy 36.474027 -239.912398) (xy 44.319188 -239.912398) (xy 44.323259 -239.856776) (xy 44.335385 -239.802339)
			(xy 44.355308 -239.750248) (xy 44.382604 -239.701613) (xy 44.41669 -239.65747) (xy 44.456839 -239.618761)
			(xy 44.502197 -239.58631) (xy 44.551797 -239.560809) (xy 44.604581 -239.542802) (xy 44.659424 -239.532672)
			(xy 44.715158 -239.530635) (xy 44.770595 -239.536735) (xy 44.824552 -239.550841) (xy 44.875881 -239.572653)
			(xy 44.923487 -239.601707) (xy 44.966355 -239.637382) (xy 45.003572 -239.678919) (xy 45.034345 -239.725432)
			(xy 45.058017 -239.775929) (xy 45.074085 -239.829336) (xy 45.082205 -239.884512) (xy 45.082714 -239.912398)
			(xy 45.082205 -239.940284) (xy 45.074085 -239.99546) (xy 45.058017 -240.048867) (xy 45.034345 -240.099364)
			(xy 45.003572 -240.145877) (xy 44.966355 -240.187414) (xy 44.923487 -240.223089) (xy 44.875881 -240.252143)
			(xy 44.824552 -240.273955) (xy 44.770595 -240.288061) (xy 44.715158 -240.294161) (xy 44.659424 -240.292124)
			(xy 44.604581 -240.281994) (xy 44.551797 -240.263987) (xy 44.502197 -240.238486) (xy 44.456839 -240.206035)
			(xy 44.41669 -240.167326) (xy 44.382604 -240.123183) (xy 44.355308 -240.074548) (xy 44.335385 -240.022457)
			(xy 44.323259 -239.96802) (xy 44.319188 -239.912398) (xy 36.474027 -239.912398) (xy 36.471468 -239.940015)
			(xy 36.4555 -240.025435) (xy 36.431719 -240.109017) (xy 36.400327 -240.190049) (xy 36.361593 -240.267838)
			(xy 36.315846 -240.341722) (xy 36.263477 -240.411069) (xy 36.204933 -240.475289) (xy 36.140713 -240.533833)
			(xy 36.071366 -240.586202) (xy 36.000851 -240.629863) (xy 49.037484 -240.629863) (xy 49.037484 -240.548753)
			(xy 49.045434 -240.468034) (xy 49.061257 -240.388483) (xy 49.084802 -240.310867) (xy 49.115841 -240.235931)
			(xy 49.154076 -240.164399) (xy 49.199138 -240.096959) (xy 49.250593 -240.03426) (xy 49.307946 -239.976907)
			(xy 49.370645 -239.925452) (xy 49.438085 -239.88039) (xy 49.509617 -239.842155) (xy 49.584553 -239.811116)
			(xy 49.662169 -239.787571) (xy 49.74172 -239.771748) (xy 49.822439 -239.763798) (xy 49.903549 -239.763798)
			(xy 49.984268 -239.771748) (xy 50.063819 -239.787571) (xy 50.141435 -239.811116) (xy 50.216371 -239.842155)
			(xy 50.287903 -239.88039) (xy 50.355343 -239.925452) (xy 50.418042 -239.976907) (xy 50.475395 -240.03426)
			(xy 50.52685 -240.096959) (xy 50.571912 -240.164399) (xy 50.610147 -240.235931) (xy 50.641186 -240.310867)
			(xy 50.664731 -240.388483) (xy 50.680554 -240.468034) (xy 50.688504 -240.548753) (xy 50.689002 -240.589308)
			(xy 50.688504 -240.629863) (xy 52.537604 -240.629863) (xy 52.537604 -240.548753) (xy 52.545554 -240.468034)
			(xy 52.561377 -240.388483) (xy 52.584922 -240.310867) (xy 52.615961 -240.235931) (xy 52.654196 -240.164399)
			(xy 52.699258 -240.096959) (xy 52.750713 -240.03426) (xy 52.808066 -239.976907) (xy 52.870765 -239.925452)
			(xy 52.938205 -239.88039) (xy 53.009737 -239.842155) (xy 53.084673 -239.811116) (xy 53.162289 -239.787571)
			(xy 53.24184 -239.771748) (xy 53.322559 -239.763798) (xy 53.403669 -239.763798) (xy 53.484388 -239.771748)
			(xy 53.563939 -239.787571) (xy 53.641555 -239.811116) (xy 53.716491 -239.842155) (xy 53.788023 -239.88039)
			(xy 53.855463 -239.925452) (xy 53.918162 -239.976907) (xy 53.975515 -240.03426) (xy 54.02697 -240.096959)
			(xy 54.072032 -240.164399) (xy 54.110267 -240.235931) (xy 54.141306 -240.310867) (xy 54.164851 -240.388483)
			(xy 54.180674 -240.468034) (xy 54.188624 -240.548753) (xy 54.189122 -240.589308) (xy 54.188624 -240.629863)
			(xy 54.180674 -240.710582) (xy 54.164851 -240.790133) (xy 54.141306 -240.867749) (xy 54.110267 -240.942685)
			(xy 54.072032 -241.014217) (xy 54.02697 -241.081657) (xy 53.984495 -241.133414) (xy 66.360686 -241.133414)
			(xy 66.364571 -241.079062) (xy 66.376152 -241.025815) (xy 66.395194 -240.974758) (xy 66.421307 -240.926931)
			(xy 66.453961 -240.883308) (xy 66.492492 -240.844775) (xy 66.536114 -240.812119) (xy 66.583939 -240.786002)
			(xy 66.634994 -240.766958) (xy 66.68824 -240.755374) (xy 66.742593 -240.751486) (xy 66.796946 -240.755372)
			(xy 66.850192 -240.766955) (xy 66.901249 -240.785997) (xy 66.949075 -240.812111) (xy 66.971164 -240.828068)
			(xy 66.990176 -240.841664) (xy 67.032059 -240.862396) (xy 67.077027 -240.875122) (xy 67.123564 -240.879412)
			(xy 67.170101 -240.875122) (xy 67.215069 -240.862396) (xy 67.256952 -240.841664) (xy 67.275964 -240.828068)
			(xy 67.298076 -240.812137) (xy 67.345902 -240.786014) (xy 67.39696 -240.766964) (xy 67.450209 -240.755374)
			(xy 67.504566 -240.751481) (xy 67.558923 -240.755364) (xy 67.612175 -240.766944) (xy 67.663236 -240.785986)
			(xy 67.711067 -240.8121) (xy 67.754695 -240.844757) (xy 67.79323 -240.883291) (xy 67.825889 -240.926916)
			(xy 67.852006 -240.974746) (xy 67.87105 -241.025806) (xy 67.882633 -241.079057) (xy 67.886519 -241.133414)
			(xy 69.352279 -241.133414) (xy 69.356164 -241.07906) (xy 69.367746 -241.025812) (xy 69.386788 -240.974754)
			(xy 69.412902 -240.926925) (xy 69.445558 -240.883301) (xy 69.48409 -240.844767) (xy 69.527713 -240.81211)
			(xy 69.575541 -240.785994) (xy 69.626598 -240.76695) (xy 69.679846 -240.755366) (xy 69.7342 -240.751479)
			(xy 69.788554 -240.755366) (xy 69.841802 -240.76695) (xy 69.892859 -240.785994) (xy 69.940687 -240.81211)
			(xy 69.962776 -240.828068) (xy 69.981788 -240.841664) (xy 70.023671 -240.862396) (xy 70.068639 -240.875122)
			(xy 70.115176 -240.879412) (xy 70.161713 -240.875122) (xy 70.206681 -240.862396) (xy 70.248564 -240.841664)
			(xy 70.267576 -240.828068) (xy 70.289687 -240.812138) (xy 70.337513 -240.786017) (xy 70.38857 -240.766968)
			(xy 70.441818 -240.75538) (xy 70.496173 -240.751488) (xy 70.550528 -240.755372) (xy 70.603778 -240.766953)
			(xy 70.654837 -240.785994) (xy 70.702667 -240.812109) (xy 70.746293 -240.844765) (xy 70.784827 -240.883298)
			(xy 70.817484 -240.926922) (xy 70.8436 -240.974751) (xy 70.862644 -241.02581) (xy 70.874226 -241.079059)
			(xy 70.878112 -241.133414) (xy 70.874222 -241.18777) (xy 70.862635 -241.241018) (xy 70.843588 -241.292075)
			(xy 70.817469 -241.339902) (xy 70.784808 -241.383524) (xy 70.746271 -241.422054) (xy 70.702643 -241.454707)
			(xy 70.654811 -241.480818) (xy 70.60375 -241.499855) (xy 70.5505 -241.511432) (xy 70.496144 -241.515312)
			(xy 70.441789 -241.511416) (xy 70.388542 -241.499824) (xy 70.337487 -241.480771) (xy 70.289663 -241.454646)
			(xy 70.267576 -241.438684) (xy 70.248564 -241.425088) (xy 70.206681 -241.404356) (xy 70.161713 -241.39163)
			(xy 70.115176 -241.38734) (xy 70.068639 -241.39163) (xy 70.023671 -241.404356) (xy 69.981788 -241.425088)
			(xy 69.962776 -241.438684) (xy 69.940711 -241.454674) (xy 69.892886 -241.480794) (xy 69.84183 -241.499842)
			(xy 69.788583 -241.51143) (xy 69.734229 -241.515321) (xy 69.679874 -241.511438) (xy 69.626625 -241.499858)
			(xy 69.575567 -241.480818) (xy 69.527738 -241.454705) (xy 69.484112 -241.422051) (xy 69.445577 -241.383521)
			(xy 69.412918 -241.339899) (xy 69.3868 -241.292073) (xy 69.367754 -241.241016) (xy 69.356168 -241.187769)
			(xy 69.352279 -241.133414) (xy 67.886519 -241.133414) (xy 67.882629 -241.187771) (xy 67.871042 -241.241021)
			(xy 67.851994 -241.29208) (xy 67.825873 -241.339908) (xy 67.793211 -241.383531) (xy 67.754673 -241.422062)
			(xy 67.711043 -241.454715) (xy 67.66321 -241.480826) (xy 67.612147 -241.499864) (xy 67.558895 -241.51144)
			(xy 67.504537 -241.515319) (xy 67.450181 -241.511422) (xy 67.396932 -241.499828) (xy 67.345876 -241.480774)
			(xy 67.298051 -241.454647) (xy 67.275964 -241.438684) (xy 67.256952 -241.425088) (xy 67.215069 -241.404356)
			(xy 67.170101 -241.39163) (xy 67.123564 -241.38734) (xy 67.077027 -241.39163) (xy 67.032059 -241.404356)
			(xy 66.990176 -241.425088) (xy 66.971164 -241.438684) (xy 66.949099 -241.454673) (xy 66.901275 -241.480791)
			(xy 66.85022 -241.499837) (xy 66.796974 -241.511424) (xy 66.742622 -241.515314) (xy 66.688269 -241.51143)
			(xy 66.635022 -241.49985) (xy 66.583965 -241.48081) (xy 66.536138 -241.454697) (xy 66.492513 -241.422044)
			(xy 66.45398 -241.383514) (xy 66.421323 -241.339893) (xy 66.395206 -241.292068) (xy 66.37616 -241.241013)
			(xy 66.364575 -241.187767) (xy 66.360686 -241.133414) (xy 53.984495 -241.133414) (xy 53.975515 -241.144356)
			(xy 53.918162 -241.201709) (xy 53.855463 -241.253164) (xy 53.788023 -241.298226) (xy 53.716491 -241.336461)
			(xy 53.641555 -241.3675) (xy 53.563939 -241.391045) (xy 53.484388 -241.406868) (xy 53.403669 -241.414818)
			(xy 53.322559 -241.414818) (xy 53.24184 -241.406868) (xy 53.162289 -241.391045) (xy 53.084673 -241.3675)
			(xy 53.009737 -241.336461) (xy 52.938205 -241.298226) (xy 52.870765 -241.253164) (xy 52.808066 -241.201709)
			(xy 52.750713 -241.144356) (xy 52.699258 -241.081657) (xy 52.654196 -241.014217) (xy 52.615961 -240.942685)
			(xy 52.584922 -240.867749) (xy 52.561377 -240.790133) (xy 52.545554 -240.710582) (xy 52.537604 -240.629863)
			(xy 50.688504 -240.629863) (xy 50.680554 -240.710582) (xy 50.664731 -240.790133) (xy 50.641186 -240.867749)
			(xy 50.610147 -240.942685) (xy 50.571912 -241.014217) (xy 50.52685 -241.081657) (xy 50.475395 -241.144356)
			(xy 50.418042 -241.201709) (xy 50.355343 -241.253164) (xy 50.287903 -241.298226) (xy 50.216371 -241.336461)
			(xy 50.141435 -241.3675) (xy 50.063819 -241.391045) (xy 49.984268 -241.406868) (xy 49.903549 -241.414818)
			(xy 49.822439 -241.414818) (xy 49.74172 -241.406868) (xy 49.662169 -241.391045) (xy 49.584553 -241.3675)
			(xy 49.509617 -241.336461) (xy 49.438085 -241.298226) (xy 49.370645 -241.253164) (xy 49.307946 -241.201709)
			(xy 49.250593 -241.144356) (xy 49.199138 -241.081657) (xy 49.154076 -241.014217) (xy 49.115841 -240.942685)
			(xy 49.084802 -240.867749) (xy 49.061257 -240.790133) (xy 49.045434 -240.710582) (xy 49.037484 -240.629863)
			(xy 36.000851 -240.629863) (xy 35.997482 -240.631949) (xy 35.919693 -240.670683) (xy 35.838661 -240.702075)
			(xy 35.755079 -240.725856) (xy 35.669659 -240.741824) (xy 35.58313 -240.749842) (xy 35.49623 -240.749842)
			(xy 35.409701 -240.741824) (xy 35.324281 -240.725856) (xy 35.240699 -240.702075) (xy 35.159667 -240.670683)
			(xy 35.081878 -240.631949) (xy 35.007994 -240.586202) (xy 34.938647 -240.533833) (xy 34.874427 -240.475289)
			(xy 34.815883 -240.411069) (xy 34.763514 -240.341722) (xy 34.717767 -240.267838) (xy 34.679033 -240.190049)
			(xy 34.647641 -240.109017) (xy 34.62386 -240.025435) (xy 34.607892 -239.940015) (xy 34.599874 -239.853486)
			(xy 31.399486 -239.853486) (xy 31.391468 -239.940015) (xy 31.3755 -240.025435) (xy 31.351719 -240.109017)
			(xy 31.320327 -240.190049) (xy 31.281593 -240.267838) (xy 31.235846 -240.341722) (xy 31.183477 -240.411069)
			(xy 31.124933 -240.475289) (xy 31.060713 -240.533833) (xy 30.991366 -240.586202) (xy 30.917482 -240.631949)
			(xy 30.839693 -240.670683) (xy 30.758661 -240.702075) (xy 30.675079 -240.725856) (xy 30.589659 -240.741824)
			(xy 30.50313 -240.749842) (xy 30.41623 -240.749842) (xy 30.329701 -240.741824) (xy 30.244281 -240.725856)
			(xy 30.160699 -240.702075) (xy 30.079667 -240.670683) (xy 30.001878 -240.631949) (xy 29.927994 -240.586202)
			(xy 29.858647 -240.533833) (xy 29.794427 -240.475289) (xy 29.735883 -240.411069) (xy 29.683514 -240.341722)
			(xy 29.637767 -240.267838) (xy 29.599033 -240.190049) (xy 29.567641 -240.109017) (xy 29.54386 -240.025435)
			(xy 29.527892 -239.940015) (xy 29.519874 -239.853486) (xy 20.323886 -239.853486) (xy 17.783983 -242.393486)
			(xy 29.519874 -242.393486) (xy 29.519874 -242.306586) (xy 29.527892 -242.220057) (xy 29.54386 -242.134637)
			(xy 29.567641 -242.051055) (xy 29.599033 -241.970023) (xy 29.637767 -241.892234) (xy 29.683514 -241.81835)
			(xy 29.735883 -241.749003) (xy 29.794427 -241.684783) (xy 29.858647 -241.626239) (xy 29.927994 -241.57387)
			(xy 30.001878 -241.528123) (xy 30.079667 -241.489389) (xy 30.160699 -241.457997) (xy 30.244281 -241.434216)
			(xy 30.329701 -241.418248) (xy 30.41623 -241.41023) (xy 30.50313 -241.41023) (xy 30.589659 -241.418248)
			(xy 30.675079 -241.434216) (xy 30.758661 -241.457997) (xy 30.839693 -241.489389) (xy 30.917482 -241.528123)
			(xy 30.991366 -241.57387) (xy 31.060713 -241.626239) (xy 31.124933 -241.684783) (xy 31.183477 -241.749003)
			(xy 31.235846 -241.81835) (xy 31.281593 -241.892234) (xy 31.320327 -241.970023) (xy 31.351719 -242.051055)
			(xy 31.3755 -242.134637) (xy 31.391468 -242.220057) (xy 31.399486 -242.306586) (xy 31.399988 -242.350036)
			(xy 31.399486 -242.393486) (xy 34.599874 -242.393486) (xy 34.599874 -242.306586) (xy 34.607892 -242.220057)
			(xy 34.62386 -242.134637) (xy 34.647641 -242.051055) (xy 34.679033 -241.970023) (xy 34.717767 -241.892234)
			(xy 34.763514 -241.81835) (xy 34.815883 -241.749003) (xy 34.874427 -241.684783) (xy 34.938647 -241.626239)
			(xy 35.007994 -241.57387) (xy 35.081878 -241.528123) (xy 35.159667 -241.489389) (xy 35.240699 -241.457997)
			(xy 35.324281 -241.434216) (xy 35.409701 -241.418248) (xy 35.49623 -241.41023) (xy 35.58313 -241.41023)
			(xy 35.669659 -241.418248) (xy 35.755079 -241.434216) (xy 35.838661 -241.457997) (xy 35.919693 -241.489389)
			(xy 35.997482 -241.528123) (xy 36.071366 -241.57387) (xy 36.140713 -241.626239) (xy 36.204933 -241.684783)
			(xy 36.263477 -241.749003) (xy 36.315846 -241.81835) (xy 36.361593 -241.892234) (xy 36.400327 -241.970023)
			(xy 36.431719 -242.051055) (xy 36.4555 -242.134637) (xy 36.471468 -242.220057) (xy 36.479486 -242.306586)
			(xy 36.479988 -242.350036) (xy 36.479486 -242.393486) (xy 36.471468 -242.480015) (xy 36.4555 -242.565435)
			(xy 36.431719 -242.649017) (xy 36.400327 -242.730049) (xy 36.361593 -242.807838) (xy 36.357248 -242.814856)
			(xy 44.210476 -242.814856) (xy 44.214547 -242.759234) (xy 44.226673 -242.704797) (xy 44.246596 -242.652706)
			(xy 44.273892 -242.604071) (xy 44.307978 -242.559928) (xy 44.348127 -242.521219) (xy 44.393485 -242.488768)
			(xy 44.443085 -242.463267) (xy 44.495869 -242.44526) (xy 44.550712 -242.43513) (xy 44.606446 -242.433093)
			(xy 44.661883 -242.439193) (xy 44.71584 -242.453299) (xy 44.767169 -242.475111) (xy 44.814775 -242.504165)
			(xy 44.857643 -242.53984) (xy 44.89486 -242.581377) (xy 44.925633 -242.62789) (xy 44.949305 -242.678387)
			(xy 44.965373 -242.731794) (xy 44.973493 -242.78697) (xy 44.974002 -242.814856) (xy 44.973493 -242.842742)
			(xy 44.965373 -242.897918) (xy 44.949305 -242.951325) (xy 44.925633 -243.001822) (xy 44.89486 -243.048335)
			(xy 44.857643 -243.089872) (xy 44.814775 -243.125547) (xy 44.767169 -243.154601) (xy 44.71584 -243.176413)
			(xy 44.661883 -243.190519) (xy 44.606446 -243.196619) (xy 44.550712 -243.194582) (xy 44.495869 -243.184452)
			(xy 44.443085 -243.166445) (xy 44.393485 -243.140944) (xy 44.348127 -243.108493) (xy 44.307978 -243.069784)
			(xy 44.273892 -243.025641) (xy 44.246596 -242.977006) (xy 44.226673 -242.924915) (xy 44.214547 -242.870478)
			(xy 44.210476 -242.814856) (xy 36.357248 -242.814856) (xy 36.315846 -242.881722) (xy 36.263477 -242.951069)
			(xy 36.204933 -243.015289) (xy 36.140713 -243.073833) (xy 36.071366 -243.126202) (xy 35.997482 -243.171949)
			(xy 35.919693 -243.210683) (xy 35.838661 -243.242075) (xy 35.755079 -243.265856) (xy 35.669659 -243.281824)
			(xy 35.58313 -243.289842) (xy 35.49623 -243.289842) (xy 35.409701 -243.281824) (xy 35.324281 -243.265856)
			(xy 35.240699 -243.242075) (xy 35.159667 -243.210683) (xy 35.081878 -243.171949) (xy 35.007994 -243.126202)
			(xy 34.938647 -243.073833) (xy 34.874427 -243.015289) (xy 34.815883 -242.951069) (xy 34.763514 -242.881722)
			(xy 34.717767 -242.807838) (xy 34.679033 -242.730049) (xy 34.647641 -242.649017) (xy 34.62386 -242.565435)
			(xy 34.607892 -242.480015) (xy 34.599874 -242.393486) (xy 31.399486 -242.393486) (xy 31.391468 -242.480015)
			(xy 31.3755 -242.565435) (xy 31.351719 -242.649017) (xy 31.320327 -242.730049) (xy 31.281593 -242.807838)
			(xy 31.235846 -242.881722) (xy 31.183477 -242.951069) (xy 31.124933 -243.015289) (xy 31.060713 -243.073833)
			(xy 30.991366 -243.126202) (xy 30.917482 -243.171949) (xy 30.839693 -243.210683) (xy 30.758661 -243.242075)
			(xy 30.675079 -243.265856) (xy 30.589659 -243.281824) (xy 30.50313 -243.289842) (xy 30.41623 -243.289842)
			(xy 30.329701 -243.281824) (xy 30.244281 -243.265856) (xy 30.160699 -243.242075) (xy 30.079667 -243.210683)
			(xy 30.001878 -243.171949) (xy 29.927994 -243.126202) (xy 29.858647 -243.073833) (xy 29.794427 -243.015289)
			(xy 29.735883 -242.951069) (xy 29.683514 -242.881722) (xy 29.637767 -242.807838) (xy 29.599033 -242.730049)
			(xy 29.567641 -242.649017) (xy 29.54386 -242.565435) (xy 29.527892 -242.480015) (xy 29.519874 -242.393486)
			(xy 17.783983 -242.393486) (xy 16.373314 -243.804208) (xy 66.360694 -243.804208) (xy 66.36458 -243.749857)
			(xy 66.376162 -243.696611) (xy 66.395203 -243.645556) (xy 66.421317 -243.597731) (xy 66.453971 -243.554108)
			(xy 66.492501 -243.515577) (xy 66.536123 -243.482922) (xy 66.583948 -243.456807) (xy 66.635002 -243.437764)
			(xy 66.688248 -243.426181) (xy 66.742599 -243.422294) (xy 66.796951 -243.426181) (xy 66.850196 -243.437764)
			(xy 66.901251 -243.456806) (xy 66.949076 -243.482921) (xy 66.971164 -243.498878) (xy 66.990176 -243.512474)
			(xy 67.032059 -243.533206) (xy 67.077027 -243.545932) (xy 67.123564 -243.550222) (xy 67.170101 -243.545932)
			(xy 67.215069 -243.533206) (xy 67.256952 -243.512474) (xy 67.275964 -243.498878) (xy 67.298066 -243.482934)
			(xy 67.345893 -243.456809) (xy 67.396952 -243.437758) (xy 67.450202 -243.426167) (xy 67.50456 -243.422273)
			(xy 67.558919 -243.426155) (xy 67.612171 -243.437735) (xy 67.663234 -243.456776) (xy 67.711066 -243.482891)
			(xy 67.754695 -243.515547) (xy 67.793232 -243.554081) (xy 67.825892 -243.597707) (xy 67.852011 -243.645537)
			(xy 67.871056 -243.696598) (xy 67.88264 -243.74985) (xy 67.886527 -243.804208) (xy 69.352287 -243.804208)
			(xy 69.356173 -243.749855) (xy 69.367755 -243.696608) (xy 69.386798 -243.645552) (xy 69.412912 -243.597725)
			(xy 69.445568 -243.554101) (xy 69.4841 -243.51557) (xy 69.527723 -243.482914) (xy 69.575549 -243.456799)
			(xy 69.626606 -243.437756) (xy 69.679853 -243.426173) (xy 69.734206 -243.422287) (xy 69.788559 -243.426175)
			(xy 69.841806 -243.437759) (xy 69.892862 -243.456804) (xy 69.940687 -243.48292) (xy 69.962776 -243.498878)
			(xy 69.981788 -243.512474) (xy 70.023671 -243.533206) (xy 70.068639 -243.545932) (xy 70.115176 -243.550222)
			(xy 70.161713 -243.545932) (xy 70.206681 -243.533206) (xy 70.248564 -243.512474) (xy 70.267576 -243.498878)
			(xy 70.289678 -243.482935) (xy 70.337504 -243.456812) (xy 70.388562 -243.437762) (xy 70.44181 -243.426173)
			(xy 70.496167 -243.42228) (xy 70.550524 -243.426163) (xy 70.603775 -243.437743) (xy 70.654835 -243.456785)
			(xy 70.702666 -243.482899) (xy 70.746293 -243.515555) (xy 70.784829 -243.554088) (xy 70.817488 -243.597713)
			(xy 70.843605 -243.645542) (xy 70.86265 -243.696602) (xy 70.874233 -243.749852) (xy 70.87812 -243.804208)
			(xy 70.874231 -243.858565) (xy 70.862645 -243.911815) (xy 70.843598 -243.962873) (xy 70.817479 -244.010701)
			(xy 70.784818 -244.054325) (xy 70.746281 -244.092856) (xy 70.702652 -244.12551) (xy 70.65482 -244.151622)
			(xy 70.603758 -244.170661) (xy 70.550507 -244.182239) (xy 70.49615 -244.18612) (xy 70.441794 -244.182225)
			(xy 70.388545 -244.170633) (xy 70.337489 -244.151581) (xy 70.289664 -244.125456) (xy 70.267576 -244.109494)
			(xy 70.248564 -244.095898) (xy 70.206681 -244.075166) (xy 70.161713 -244.06244) (xy 70.115176 -244.05815)
			(xy 70.068639 -244.06244) (xy 70.023671 -244.075166) (xy 69.981788 -244.095898) (xy 69.962776 -244.109494)
			(xy 69.940702 -244.125471) (xy 69.892877 -244.151589) (xy 69.841822 -244.170636) (xy 69.788576 -244.182223)
			(xy 69.734223 -244.186113) (xy 69.679869 -244.182229) (xy 69.626622 -244.170649) (xy 69.575565 -244.151608)
			(xy 69.527737 -244.125495) (xy 69.484112 -244.092841) (xy 69.445579 -244.054311) (xy 69.412921 -244.010689)
			(xy 69.386805 -243.962864) (xy 69.36776 -243.911808) (xy 69.356175 -243.858562) (xy 69.352287 -243.804208)
			(xy 67.886527 -243.804208) (xy 67.882638 -243.858567) (xy 67.871051 -243.911818) (xy 67.852004 -243.962878)
			(xy 67.825883 -244.010707) (xy 67.793221 -244.054332) (xy 67.754683 -244.092864) (xy 67.711052 -244.125519)
			(xy 67.663218 -244.151631) (xy 67.612155 -244.17067) (xy 67.558902 -244.182247) (xy 67.504543 -244.186127)
			(xy 67.450185 -244.182231) (xy 67.396936 -244.170638) (xy 67.345878 -244.151584) (xy 67.298052 -244.125457)
			(xy 67.275964 -244.109494) (xy 67.256952 -244.095898) (xy 67.215069 -244.075166) (xy 67.170101 -244.06244)
			(xy 67.123564 -244.05815) (xy 67.077027 -244.06244) (xy 67.032059 -244.075166) (xy 66.990176 -244.095898)
			(xy 66.971164 -244.109494) (xy 66.94909 -244.12547) (xy 66.901266 -244.151587) (xy 66.850212 -244.170631)
			(xy 66.796967 -244.182217) (xy 66.742616 -244.186106) (xy 66.688264 -244.182221) (xy 66.635019 -244.17064)
			(xy 66.583963 -244.1516) (xy 66.536137 -244.125487) (xy 66.492514 -244.092834) (xy 66.453982 -244.054304)
			(xy 66.421326 -244.010683) (xy 66.39521 -243.962859) (xy 66.376166 -243.911805) (xy 66.364582 -243.85856)
			(xy 66.360694 -243.804208) (xy 16.373314 -243.804208) (xy 16.065246 -244.112288) (xy 9.284716 -244.112288)
			(xy 9.263013 -244.112719) (xy 9.220235 -244.120069) (xy 9.179326 -244.134577) (xy 9.141475 -244.15582)
			(xy 9.10778 -244.183182) (xy 9.079221 -244.215868) (xy 9.056626 -244.252928) (xy 9.040652 -244.293287)
			(xy 9.031763 -244.335772) (xy 9.030217 -244.379149) (xy 9.036059 -244.42216) (xy 9.042146 -244.442996)
			(xy 9.04621 -244.454172) (xy 9.052052 -244.470682) (xy 9.055862 -244.482874) (xy 9.065941 -244.517132)
			(xy 9.079244 -244.587294) (xy 9.084597 -244.658506) (xy 9.081935 -244.729869) (xy 9.07129 -244.800483)
			(xy 9.052796 -244.86946) (xy 9.026687 -244.935928) (xy 8.993292 -244.999051) (xy 8.953032 -245.058033)
			(xy 8.906414 -245.11213) (xy 8.854026 -245.160661) (xy 8.796528 -245.203013) (xy 8.734645 -245.238654)
			(xy 8.669156 -245.267132) (xy 8.600889 -245.288091) (xy 8.530702 -245.301265) (xy 8.459481 -245.306488)
			(xy 8.388123 -245.303695) (xy 8.317528 -245.292921) (xy 8.248585 -245.274301) (xy 8.182164 -245.248071)
			(xy 8.119103 -245.21456) (xy 8.060194 -245.174192) (xy 8.006183 -245.127475) (xy 7.957748 -245.074998)
			(xy 7.93623 -245.0465) (xy 7.922908 -245.02912) (xy 7.891337 -244.998779) (xy 7.855033 -244.974299)
			(xy 7.815071 -244.956402) (xy 7.772632 -244.945619) (xy 7.728974 -244.942269) (xy 7.685387 -244.94645)
			(xy 7.643162 -244.95804) (xy 7.603548 -244.976696) (xy 7.567717 -245.001864) (xy 7.551928 -245.017036)
			(xy 7.111492 -245.457472) (xy 7.101123 -245.468402) (xy 7.085384 -245.49408) (xy 7.076138 -245.522744)
			(xy 7.073906 -245.552779) (xy 7.075932 -245.567708) (xy 7.081204 -245.6029) (xy 7.084808 -245.673972)
			(xy 7.08045 -245.745001) (xy 7.068185 -245.815099) (xy 7.048166 -245.883388) (xy 7.020643 -245.949012)
			(xy 6.985961 -246.011152) (xy 6.944555 -246.069028) (xy 6.896942 -246.121916) (xy 6.843719 -246.169155)
			(xy 6.785552 -246.210152) (xy 6.723169 -246.244394) (xy 6.657352 -246.271453) (xy 6.588923 -246.29099)
			(xy 6.51874 -246.30276) (xy 6.447682 -246.306616) (xy 6.376638 -246.30251) (xy 6.306497 -246.290493)
			(xy 6.238138 -246.270716) (xy 6.172416 -246.243426) (xy 6.110154 -246.208965) (xy 6.052131 -246.167764)
			(xy 5.999075 -246.120338) (xy 5.951648 -246.067283) (xy 5.910445 -246.009262) (xy 5.875982 -245.947001)
			(xy 5.84869 -245.88128) (xy 5.828911 -245.812921) (xy 5.816892 -245.74278) (xy 5.812784 -245.671736)
			(xy 5.816638 -245.600678) (xy 5.828406 -245.530495) (xy 5.847941 -245.462066) (xy 5.874998 -245.396247)
			(xy 5.909239 -245.333864) (xy 5.950234 -245.275695) (xy 5.997471 -245.222471) (xy 6.050358 -245.174857)
			(xy 6.108232 -245.133449) (xy 6.170371 -245.098765) (xy 6.235995 -245.071241) (xy 6.304283 -245.051219)
			(xy 6.374381 -245.038952) (xy 6.44541 -245.034592) (xy 6.516482 -245.038194) (xy 6.551676 -245.043452)
			(xy 6.566603 -245.045438) (xy 6.596622 -245.043158) (xy 6.625276 -245.033923) (xy 6.650976 -245.018243)
			(xy 6.661912 -245.007892) (xy 8.102346 -243.567458) (xy 8.11751 -243.551653) (xy 8.142717 -243.515836)
			(xy 8.161404 -243.476225) (xy 8.173017 -243.433995) (xy 8.177212 -243.390399) (xy 8.173864 -243.34673)
			(xy 8.163073 -243.304283) (xy 8.145159 -243.264317) (xy 8.120653 -243.228017) (xy 8.090282 -243.196461)
			(xy 8.072882 -243.183156) (xy 8.047039 -243.163705) (xy 7.999035 -243.120351) (xy 7.955682 -243.072345)
			(xy 7.93623 -243.046504) (xy 7.922909 -243.029124) (xy 7.891338 -242.998783) (xy 7.855034 -242.974301)
			(xy 7.815071 -242.956404) (xy 7.772633 -242.945621) (xy 7.728974 -242.942271) (xy 7.685387 -242.946453)
			(xy 7.643162 -242.958043) (xy 7.603548 -242.976699) (xy 7.567717 -243.001867) (xy 7.551928 -243.01704)
			(xy 7.111492 -243.457476) (xy 7.101124 -243.468406) (xy 7.085385 -243.494084) (xy 7.07614 -243.522748)
			(xy 7.073909 -243.552783) (xy 7.075932 -243.567712) (xy 7.081203 -243.602904) (xy 7.084807 -243.673975)
			(xy 7.080449 -243.745005) (xy 7.068184 -243.815102) (xy 7.048164 -243.883391) (xy 7.020641 -243.949015)
			(xy 6.985959 -244.011155) (xy 6.944552 -244.06903) (xy 6.896939 -244.121918) (xy 6.843716 -244.169156)
			(xy 6.785549 -244.210153) (xy 6.723166 -244.244395) (xy 6.657348 -244.271453) (xy 6.58892 -244.29099)
			(xy 6.518738 -244.302759) (xy 6.447679 -244.306615) (xy 6.376635 -244.302509) (xy 6.306495 -244.290492)
			(xy 6.238136 -244.270714) (xy 6.172414 -244.243424) (xy 6.110152 -244.208963) (xy 6.05213 -244.167762)
			(xy 5.999073 -244.120336) (xy 5.951647 -244.067281) (xy 5.910445 -244.00926) (xy 5.875982 -243.946999)
			(xy 5.84869 -243.881277) (xy 5.828911 -243.812919) (xy 5.816892 -243.742778) (xy 5.812785 -243.671734)
			(xy 5.816639 -243.600676) (xy 5.828407 -243.530493) (xy 5.847942 -243.462065) (xy 5.875 -243.396246)
			(xy 5.90924 -243.333863) (xy 5.950235 -243.275695) (xy 5.997472 -243.222471) (xy 6.050359 -243.174857)
			(xy 6.108234 -243.133449) (xy 6.170372 -243.098765) (xy 6.235996 -243.071241) (xy 6.304284 -243.05122)
			(xy 6.374382 -243.038952) (xy 6.445411 -243.034593) (xy 6.516482 -243.038195) (xy 6.551676 -243.043456)
			(xy 6.566603 -243.045442) (xy 6.596622 -243.043162) (xy 6.625276 -243.033927) (xy 6.650977 -243.018247)
			(xy 6.661912 -243.007896) (xy 7.107428 -242.56238) (xy 7.107428 -240.333276) (xy 7.237984 -240.20272)
			(xy 7.249432 -240.190602) (xy 7.266129 -240.161761) (xy 7.274788 -240.129581) (xy 7.274819 -240.096255)
			(xy 7.26622 -240.064059) (xy 7.249577 -240.035187) (xy 7.226025 -240.011609) (xy 7.197172 -239.994934)
			(xy 7.164985 -239.986299) (xy 7.148322 -239.985804) (xy 7.069836 -239.985804) (xy 6.968236 -240.038382)
			(xy 6.950964 -240.06048) (xy 6.950964 -240.060734) (xy 6.928329 -240.08903) (xy 6.877651 -240.140825)
			(xy 6.821412 -240.186521) (xy 6.760341 -240.225525) (xy 6.69523 -240.257331) (xy 6.626925 -240.281526)
			(xy 6.556312 -240.297796) (xy 6.484306 -240.305931) (xy 6.411843 -240.305824) (xy 6.339862 -240.297477)
			(xy 6.269297 -240.280999) (xy 6.201063 -240.256603) (xy 6.136047 -240.224606) (xy 6.075091 -240.185422)
			(xy 6.018986 -240.139561) (xy 5.968461 -240.087617) (xy 5.924171 -240.030264) (xy 5.904992 -239.99952)
			(xy 5.892653 -239.980056) (xy 5.862109 -239.945552) (xy 5.825845 -239.917121) (xy 5.785048 -239.895695)
			(xy 5.741057 -239.881977) (xy 5.695313 -239.876417) (xy 5.649316 -239.879196) (xy 5.604574 -239.890224)
			(xy 5.562554 -239.909138) (xy 5.524634 -239.93532) (xy 5.50799 -239.95126) (xy 5.448808 -240.010442)
			(xy 5.448808 -240.620296) (xy 4.589526 -241.479578) (xy 4.570984 -241.539268) (xy 4.576572 -241.569748)
			(xy 4.576572 -241.57051) (xy 4.581669 -241.605412) (xy 4.585027 -241.675871) (xy 4.580563 -241.746267)
			(xy 4.568331 -241.815737) (xy 4.548482 -241.883425) (xy 4.52126 -241.948499) (xy 4.487 -242.010159)
			(xy 4.446123 -242.067646) (xy 4.399132 -242.120253) (xy 4.346605 -242.167333) (xy 4.289188 -242.208308)
			(xy 4.227587 -242.242673) (xy 4.162559 -242.270005) (xy 4.094905 -242.28997) (xy 4.025456 -242.30232)
			(xy 3.955067 -242.306904) (xy 3.884603 -242.303666) (xy 3.814931 -242.292645) (xy 3.746907 -242.273978)
			(xy 3.681369 -242.247893) (xy 3.619122 -242.214712) (xy 3.560933 -242.174842) (xy 3.507515 -242.128774)
			(xy 3.459527 -242.077075) (xy 3.417559 -242.02038) (xy 3.382127 -241.959387) (xy 3.353666 -241.894845)
			(xy 3.34264 -241.86134) (xy 3.332093 -241.826074) (xy 3.318257 -241.753774) (xy 3.312871 -241.68036)
			(xy 3.316006 -241.606816) (xy 3.32762 -241.534127) (xy 3.347559 -241.463267) (xy 3.375554 -241.395187)
			(xy 3.392932 -241.362738) (xy 3.403788 -241.342115) (xy 3.418617 -241.297938) (xy 3.42515 -241.251799)
			(xy 3.42317 -241.205242) (xy 3.412743 -241.159824) (xy 3.394217 -241.117065) (xy 3.368213 -241.078397)
			(xy 3.3356 -241.045111) (xy 3.297469 -241.018323) (xy 3.255098 -240.998929) (xy 3.209902 -240.987577)
			(xy 3.186684 -240.985548) (xy 2.56921 -240.985548) (xy 2.468372 -241.03838) (xy 2.4511 -241.060224)
			(xy 2.450846 -241.060732) (xy 2.428952 -241.088092) (xy 2.380102 -241.138338) (xy 2.326023 -241.182906)
			(xy 2.267371 -241.221256) (xy 2.204857 -241.252923) (xy 2.139239 -241.277524) (xy 2.071314 -241.294758)
			(xy 2.001906 -241.304418) (xy 1.931856 -241.306386) (xy 1.862014 -241.300638) (xy 1.82753 -241.294412)
			(xy 1.80544 -241.290594) (xy 1.760621 -241.289878) (xy 1.716372 -241.297037) (xy 1.674065 -241.311848)
			(xy 1.635013 -241.333854) (xy 1.600429 -241.362369) (xy 1.571384 -241.396511) (xy 1.54878 -241.43522)
			(xy 1.533319 -241.477293) (xy 1.52548 -241.521427) (xy 1.525016 -241.54384) (xy 1.525016 -241.797332)
			(xy 1.525496 -241.819739) (xy 1.533362 -241.863857) (xy 1.54884 -241.905913) (xy 1.571451 -241.944605)
			(xy 1.600494 -241.978734) (xy 1.63507 -242.007243) (xy 1.674109 -242.02925) (xy 1.7164 -242.044073)
			(xy 1.760635 -242.051253) (xy 1.805444 -242.050567) (xy 1.82753 -242.04676) (xy 1.863115 -242.040353)
			(xy 1.9352 -242.034684) (xy 2.007462 -242.037234) (xy 2.078968 -242.047968) (xy 2.148793 -242.066749)
			(xy 2.216036 -242.093334) (xy 2.279827 -242.127378) (xy 2.339341 -242.168443) (xy 2.393811 -242.215997)
			(xy 2.442531 -242.269427) (xy 2.484872 -242.32804) (xy 2.520287 -242.39108) (xy 2.548318 -242.457733)
			(xy 2.568603 -242.527137) (xy 2.58088 -242.598394) (xy 2.58499 -242.670584) (xy 2.58088 -242.742774)
			(xy 2.568603 -242.814031) (xy 2.548318 -242.883435) (xy 2.520287 -242.950088) (xy 2.484872 -243.013128)
			(xy 2.442531 -243.071741) (xy 2.393811 -243.125171) (xy 2.339341 -243.172725) (xy 2.279827 -243.21379)
			(xy 2.216036 -243.247834) (xy 2.148793 -243.274419) (xy 2.078968 -243.2932) (xy 2.007462 -243.303934)
			(xy 1.9352 -243.306484) (xy 1.863115 -243.300815) (xy 1.82753 -243.294408) (xy 1.80544 -243.29059)
			(xy 1.760621 -243.289874) (xy 1.716371 -243.297033) (xy 1.674064 -243.311844) (xy 1.635012 -243.33385)
			(xy 1.600427 -243.362365) (xy 1.571382 -243.396507) (xy 1.548778 -243.435215) (xy 1.533316 -243.477289)
			(xy 1.525477 -243.521423) (xy 1.525016 -243.543836) (xy 1.525016 -243.706243) (xy 3.31393 -243.706243)
			(xy 3.31393 -243.634921) (xy 3.321916 -243.564047) (xy 3.337786 -243.494512) (xy 3.361343 -243.427192)
			(xy 3.392288 -243.362933) (xy 3.430234 -243.302542) (xy 3.474703 -243.24678) (xy 3.525136 -243.196347)
			(xy 3.580898 -243.151878) (xy 3.641289 -243.113932) (xy 3.705548 -243.082987) (xy 3.772868 -243.05943)
			(xy 3.842403 -243.04356) (xy 3.913277 -243.035574) (xy 3.984599 -243.035574) (xy 4.055473 -243.04356)
			(xy 4.125008 -243.05943) (xy 4.192328 -243.082987) (xy 4.256587 -243.113932) (xy 4.316978 -243.151878)
			(xy 4.37274 -243.196347) (xy 4.423173 -243.24678) (xy 4.467642 -243.302542) (xy 4.505588 -243.362933)
			(xy 4.536533 -243.427192) (xy 4.56009 -243.494512) (xy 4.57596 -243.564047) (xy 4.583946 -243.634921)
			(xy 4.584446 -243.670582) (xy 4.583946 -243.706243) (xy 4.57596 -243.777117) (xy 4.56009 -243.846652)
			(xy 4.536533 -243.913972) (xy 4.505588 -243.978231) (xy 4.467642 -244.038622) (xy 4.423173 -244.094384)
			(xy 4.37274 -244.144817) (xy 4.316978 -244.189286) (xy 4.256587 -244.227232) (xy 4.192328 -244.258177)
			(xy 4.125008 -244.281734) (xy 4.055473 -244.297604) (xy 3.984599 -244.30559) (xy 3.913277 -244.30559)
			(xy 3.842403 -244.297604) (xy 3.772868 -244.281734) (xy 3.705548 -244.258177) (xy 3.641289 -244.227232)
			(xy 3.580898 -244.189286) (xy 3.525136 -244.144817) (xy 3.474703 -244.094384) (xy 3.430234 -244.038622)
			(xy 3.392288 -243.978231) (xy 3.361343 -243.913972) (xy 3.337786 -243.846652) (xy 3.321916 -243.777117)
			(xy 3.31393 -243.706243) (xy 1.525016 -243.706243) (xy 1.525016 -245.706239) (xy 3.31393 -245.706239)
			(xy 3.31393 -245.634917) (xy 3.321916 -245.564043) (xy 3.337786 -245.494508) (xy 3.361343 -245.427188)
			(xy 3.392288 -245.362929) (xy 3.430234 -245.302538) (xy 3.474703 -245.246776) (xy 3.525136 -245.196343)
			(xy 3.580898 -245.151874) (xy 3.641289 -245.113928) (xy 3.705548 -245.082983) (xy 3.772868 -245.059426)
			(xy 3.842403 -245.043556) (xy 3.913277 -245.03557) (xy 3.984599 -245.03557) (xy 4.055473 -245.043556)
			(xy 4.125008 -245.059426) (xy 4.192328 -245.082983) (xy 4.256587 -245.113928) (xy 4.316978 -245.151874)
			(xy 4.37274 -245.196343) (xy 4.423173 -245.246776) (xy 4.467642 -245.302538) (xy 4.505588 -245.362929)
			(xy 4.536533 -245.427188) (xy 4.56009 -245.494508) (xy 4.57596 -245.564043) (xy 4.583946 -245.634917)
			(xy 4.584446 -245.670578) (xy 4.583946 -245.706239) (xy 4.57596 -245.777113) (xy 4.56009 -245.846648)
			(xy 4.536533 -245.913968) (xy 4.505588 -245.978227) (xy 4.467642 -246.038618) (xy 4.423173 -246.09438)
			(xy 4.37274 -246.144813) (xy 4.316978 -246.189282) (xy 4.256587 -246.227228) (xy 4.192328 -246.258173)
			(xy 4.125008 -246.28173) (xy 4.055473 -246.2976) (xy 3.984599 -246.305586) (xy 3.913277 -246.305586)
			(xy 3.842403 -246.2976) (xy 3.772868 -246.28173) (xy 3.705548 -246.258173) (xy 3.641289 -246.227228)
			(xy 3.580898 -246.189282) (xy 3.525136 -246.144813) (xy 3.474703 -246.09438) (xy 3.430234 -246.038618)
			(xy 3.392288 -245.978227) (xy 3.361343 -245.913968) (xy 3.337786 -245.846648) (xy 3.321916 -245.777113)
			(xy 3.31393 -245.706239) (xy 1.525016 -245.706239) (xy 1.525016 -245.797324) (xy 1.525496 -245.819731)
			(xy 1.533363 -245.863849) (xy 1.548841 -245.905904) (xy 1.571452 -245.944596) (xy 1.600495 -245.978724)
			(xy 1.635071 -246.007233) (xy 1.674109 -246.02924) (xy 1.7164 -246.044063) (xy 1.760635 -246.051243)
			(xy 1.805444 -246.050557) (xy 1.82753 -246.046752) (xy 1.863115 -246.040345) (xy 1.9352 -246.034676)
			(xy 2.007462 -246.037226) (xy 2.078968 -246.04796) (xy 2.148793 -246.066741) (xy 2.216036 -246.093326)
			(xy 2.279827 -246.12737) (xy 2.339341 -246.168435) (xy 2.393811 -246.215989) (xy 2.442531 -246.269419)
			(xy 2.484872 -246.328032) (xy 2.520287 -246.391072) (xy 2.548318 -246.457725) (xy 2.568603 -246.527129)
			(xy 2.58088 -246.598386) (xy 2.58499 -246.670576) (xy 2.58088 -246.742766) (xy 2.568603 -246.814023)
			(xy 2.548318 -246.883427) (xy 2.520287 -246.95008) (xy 2.484872 -247.01312) (xy 2.442531 -247.071733)
			(xy 2.393811 -247.125163) (xy 2.339341 -247.172717) (xy 2.279827 -247.213782) (xy 2.216036 -247.247826)
			(xy 2.148793 -247.274411) (xy 2.078968 -247.293192) (xy 2.007462 -247.303926) (xy 1.9352 -247.306476)
			(xy 1.863115 -247.300807) (xy 1.82753 -247.2944) (xy 1.80544 -247.290582) (xy 1.760621 -247.289866)
			(xy 1.716371 -247.297025) (xy 1.674065 -247.311836) (xy 1.635013 -247.333842) (xy 1.600428 -247.362357)
			(xy 1.571383 -247.396499) (xy 1.548779 -247.435207) (xy 1.533318 -247.477281) (xy 1.525479 -247.521415)
			(xy 1.525016 -247.543828) (xy 1.525016 -247.706235) (xy 3.31393 -247.706235) (xy 3.31393 -247.634913)
			(xy 3.321916 -247.564039) (xy 3.337786 -247.494504) (xy 3.361343 -247.427184) (xy 3.392288 -247.362925)
			(xy 3.430234 -247.302534) (xy 3.474703 -247.246772) (xy 3.525136 -247.196339) (xy 3.580898 -247.15187)
			(xy 3.641289 -247.113924) (xy 3.705548 -247.082979) (xy 3.772868 -247.059422) (xy 3.842403 -247.043552)
			(xy 3.913277 -247.035566) (xy 3.984599 -247.035566) (xy 4.055473 -247.043552) (xy 4.125008 -247.059422)
			(xy 4.192328 -247.082979) (xy 4.256587 -247.113924) (xy 4.316978 -247.15187) (xy 4.37274 -247.196339)
			(xy 4.423173 -247.246772) (xy 4.467642 -247.302534) (xy 4.505588 -247.362925) (xy 4.536533 -247.427184)
			(xy 4.56009 -247.494504) (xy 4.57596 -247.564039) (xy 4.583946 -247.634913) (xy 4.584446 -247.670574)
			(xy 4.583946 -247.706235) (xy 5.813798 -247.706235) (xy 5.813798 -247.634913) (xy 5.821784 -247.564039)
			(xy 5.837654 -247.494504) (xy 5.861211 -247.427184) (xy 5.892156 -247.362925) (xy 5.930102 -247.302534)
			(xy 5.974571 -247.246772) (xy 6.025004 -247.196339) (xy 6.080766 -247.15187) (xy 6.141157 -247.113924)
			(xy 6.205416 -247.082979) (xy 6.272736 -247.059422) (xy 6.342271 -247.043552) (xy 6.413145 -247.035566)
			(xy 6.484467 -247.035566) (xy 6.555341 -247.043552) (xy 6.624876 -247.059422) (xy 6.692196 -247.082979)
			(xy 6.756455 -247.113924) (xy 6.816846 -247.15187) (xy 6.872608 -247.196339) (xy 6.923041 -247.246772)
			(xy 6.96751 -247.302534) (xy 7.005456 -247.362925) (xy 7.036401 -247.427184) (xy 7.059958 -247.494504)
			(xy 7.075828 -247.564039) (xy 7.083814 -247.634913) (xy 7.084314 -247.670574) (xy 7.083814 -247.706235)
			(xy 7.075828 -247.777109) (xy 7.059958 -247.846644) (xy 7.036401 -247.913964) (xy 7.005456 -247.978223)
			(xy 6.96751 -248.038614) (xy 6.923041 -248.094376) (xy 6.872608 -248.144809) (xy 6.816846 -248.189278)
			(xy 6.756455 -248.227224) (xy 6.692196 -248.258169) (xy 6.624876 -248.281726) (xy 6.555341 -248.297596)
			(xy 6.484467 -248.305582) (xy 6.413145 -248.305582) (xy 6.342271 -248.297596) (xy 6.272736 -248.281726)
			(xy 6.205416 -248.258169) (xy 6.141157 -248.227224) (xy 6.080766 -248.189278) (xy 6.025004 -248.144809)
			(xy 5.974571 -248.094376) (xy 5.930102 -248.038614) (xy 5.892156 -247.978223) (xy 5.861211 -247.913964)
			(xy 5.837654 -247.846644) (xy 5.821784 -247.777109) (xy 5.813798 -247.706235) (xy 4.583946 -247.706235)
			(xy 4.57596 -247.777109) (xy 4.56009 -247.846644) (xy 4.536533 -247.913964) (xy 4.505588 -247.978223)
			(xy 4.467642 -248.038614) (xy 4.423173 -248.094376) (xy 4.37274 -248.144809) (xy 4.316978 -248.189278)
			(xy 4.256587 -248.227224) (xy 4.192328 -248.258169) (xy 4.125008 -248.281726) (xy 4.055473 -248.297596)
			(xy 3.984599 -248.305582) (xy 3.913277 -248.305582) (xy 3.842403 -248.297596) (xy 3.772868 -248.281726)
			(xy 3.705548 -248.258169) (xy 3.641289 -248.227224) (xy 3.580898 -248.189278) (xy 3.525136 -248.144809)
			(xy 3.474703 -248.094376) (xy 3.430234 -248.038614) (xy 3.392288 -247.978223) (xy 3.361343 -247.913964)
			(xy 3.337786 -247.846644) (xy 3.321916 -247.777109) (xy 3.31393 -247.706235) (xy 1.525016 -247.706235)
			(xy 1.525016 -247.79732) (xy 1.525496 -247.819726) (xy 1.533364 -247.863843) (xy 1.548843 -247.905898)
			(xy 1.571454 -247.944588) (xy 1.600497 -247.978716) (xy 1.635073 -248.007225) (xy 1.67411 -248.029231)
			(xy 1.716401 -248.044053) (xy 1.760635 -248.051233) (xy 1.805443 -248.050548) (xy 1.82753 -248.046748)
			(xy 1.863115 -248.040341) (xy 1.935199 -248.034673) (xy 2.007461 -248.037222) (xy 2.078966 -248.047957)
			(xy 2.148791 -248.066738) (xy 2.216034 -248.093322) (xy 2.279824 -248.127367) (xy 2.339338 -248.168431)
			(xy 2.393807 -248.215985) (xy 2.442527 -248.269414) (xy 2.484868 -248.328028) (xy 2.520283 -248.391068)
			(xy 2.548314 -248.45772) (xy 2.568599 -248.527123) (xy 2.580876 -248.59838) (xy 2.584986 -248.67057)
			(xy 2.580876 -248.742759) (xy 2.568599 -248.814016) (xy 2.548314 -248.883419) (xy 2.520283 -248.950072)
			(xy 2.484868 -249.013112) (xy 2.442528 -249.071725) (xy 2.393808 -249.125154) (xy 2.339339 -249.172708)
			(xy 2.279825 -249.213773) (xy 2.216034 -249.247818) (xy 2.148792 -249.274402) (xy 2.078967 -249.293183)
			(xy 2.007462 -249.303918) (xy 1.9352 -249.306467) (xy 1.863116 -249.300799) (xy 1.82753 -249.294396)
			(xy 1.80544 -249.290578) (xy 1.760621 -249.289862) (xy 1.716372 -249.297021) (xy 1.674066 -249.311833)
			(xy 1.635015 -249.333838) (xy 1.60043 -249.362354) (xy 1.571386 -249.396496) (xy 1.548783 -249.435204)
			(xy 1.533323 -249.477278) (xy 1.525484 -249.521412) (xy 1.525016 -249.543824) (xy 1.525016 -251.797312)
			(xy 1.525496 -251.819719) (xy 1.533362 -251.863837) (xy 1.54884 -251.905893) (xy 1.571451 -251.944585)
			(xy 1.600494 -251.978714) (xy 1.63507 -252.007223) (xy 1.674109 -252.02923) (xy 1.7164 -252.044053)
			(xy 1.760635 -252.051233) (xy 1.805444 -252.050547) (xy 1.82753 -252.04674) (xy 1.863115 -252.040333)
			(xy 1.9352 -252.034664) (xy 2.007462 -252.037214) (xy 2.078968 -252.047948) (xy 2.148793 -252.066729)
			(xy 2.216036 -252.093314) (xy 2.279827 -252.127358) (xy 2.339341 -252.168423) (xy 2.393811 -252.215977)
			(xy 2.442531 -252.269407) (xy 2.484872 -252.32802) (xy 2.520287 -252.39106) (xy 2.548318 -252.457713)
			(xy 2.568603 -252.527117) (xy 2.58088 -252.598374) (xy 2.58499 -252.670564) (xy 2.58088 -252.742754)
			(xy 2.568603 -252.814011) (xy 2.548318 -252.883415) (xy 2.520287 -252.950068) (xy 2.484872 -253.013108)
			(xy 2.442531 -253.071721) (xy 2.393811 -253.125151) (xy 2.339341 -253.172705) (xy 2.279827 -253.21377)
			(xy 2.216036 -253.247814) (xy 2.148793 -253.274399) (xy 2.078968 -253.29318) (xy 2.007462 -253.303914)
			(xy 1.9352 -253.306464) (xy 1.863115 -253.300795) (xy 1.82753 -253.294388) (xy 1.80544 -253.29057)
			(xy 1.760621 -253.289854) (xy 1.716371 -253.297013) (xy 1.674064 -253.311824) (xy 1.635012 -253.33383)
			(xy 1.600427 -253.362345) (xy 1.571382 -253.396487) (xy 1.548778 -253.435195) (xy 1.533316 -253.477269)
			(xy 1.525477 -253.521403) (xy 1.525016 -253.543816) (xy 1.525016 -253.797308) (xy 1.525496 -253.819714)
			(xy 1.533363 -253.863832) (xy 1.548842 -253.905887) (xy 1.571453 -253.944578) (xy 1.600496 -253.978706)
			(xy 1.635072 -254.007214) (xy 1.67411 -254.02922) (xy 1.716401 -254.044043) (xy 1.760635 -254.051223)
			(xy 1.805443 -254.050538) (xy 1.82753 -254.046736) (xy 1.863196 -254.040319) (xy 1.935443 -254.034656)
			(xy 2.007866 -254.037248) (xy 2.079524 -254.048061) (xy 2.149487 -254.066955) (xy 2.216847 -254.093684)
			(xy 2.280729 -254.127902) (xy 2.340305 -254.169164) (xy 2.3948 -254.216935) (xy 2.443508 -254.270594)
			(xy 2.46507 -254.29972) (xy 2.474232 -254.311718) (xy 2.497126 -254.331384) (xy 2.524004 -254.345111)
			(xy 2.553357 -254.352131) (xy 2.568448 -254.352552) (xy 3.963416 -254.352552) (xy 4.5847 -253.731268)
			(xy 4.5847 -253.086362) (xy 5.281676 -252.389132) (xy 5.479288 -252.19152) (xy 5.600446 -252.19152)
			(xy 5.622104 -252.191061) (xy 5.664785 -252.183674) (xy 5.705596 -252.169156) (xy 5.743354 -252.147928)
			(xy 5.776965 -252.120604) (xy 5.805455 -252.087976) (xy 5.828 -252.05099) (xy 5.843946 -252.010716)
			(xy 5.852832 -251.968321) (xy 5.8544 -251.925033) (xy 5.848604 -251.882107) (xy 5.842508 -251.86132)
			(xy 5.832602 -251.826268) (xy 5.82803 -251.806964) (xy 5.826252 -251.798328) (xy 5.825236 -251.793248)
			(xy 5.819193 -251.770209) (xy 5.799719 -251.726748) (xy 5.772489 -251.687675) (xy 5.738458 -251.654359)
			(xy 5.698815 -251.627966) (xy 5.65495 -251.60942) (xy 5.608397 -251.599371) (xy 5.560788 -251.598169)
			(xy 5.5372 -251.601478) (xy 5.479868 -251.613208) (xy 5.363951 -251.629341) (xy 5.24717 -251.637046)
			(xy 5.130138 -251.636282) (xy 5.013468 -251.627053) (xy 4.95554 -251.61875) (xy 4.934374 -251.615494)
			(xy 4.892204 -251.608001) (xy 4.871212 -251.603764) (xy 4.849685 -251.599774) (xy 4.805929 -251.598375)
			(xy 4.76258 -251.604493) (xy 4.720921 -251.617946) (xy 4.682182 -251.638337) (xy 4.647508 -251.665064)
			(xy 4.617926 -251.697335) (xy 4.59431 -251.734197) (xy 4.577358 -251.77456) (xy 4.572 -251.795788)
			(xy 4.564424 -251.830949) (xy 4.542379 -251.899417) (xy 4.512745 -251.964958) (xy 4.4759 -252.026734)
			(xy 4.432316 -252.083955) (xy 4.382551 -252.13589) (xy 4.32724 -252.181874) (xy 4.267091 -252.221319)
			(xy 4.202873 -252.253721) (xy 4.135408 -252.278665) (xy 4.065557 -252.295833) (xy 3.994215 -252.305005)
			(xy 3.922294 -252.306063) (xy 3.886454 -252.303026) (xy 3.84921 -252.298792) (xy 3.776 -252.282691)
			(xy 3.70519 -252.258097) (xy 3.637763 -252.225349) (xy 3.574652 -252.184902) (xy 3.545332 -252.161548)
			(xy 3.518712 -252.139056) (xy 3.470036 -252.089177) (xy 3.42711 -252.034271) (xy 3.39045 -251.974998)
			(xy 3.360496 -251.91207) (xy 3.337606 -251.846242) (xy 3.322057 -251.778304) (xy 3.314035 -251.709074)
			(xy 3.313636 -251.639381) (xy 3.320864 -251.570063) (xy 3.335634 -251.501952) (xy 3.357768 -251.435866)
			(xy 3.387 -251.372599) (xy 3.422979 -251.31291) (xy 3.465273 -251.257516) (xy 3.513373 -251.207082)
			(xy 3.566704 -251.162214) (xy 3.624623 -251.123451) (xy 3.655314 -251.10694) (xy 3.674736 -251.096282)
			(xy 3.70988 -251.069316) (xy 3.739814 -251.036663) (xy 3.763631 -250.999313) (xy 3.78061 -250.958399)
			(xy 3.790235 -250.915159) (xy 3.792216 -250.870906) (xy 3.786491 -250.82698) (xy 3.773235 -250.784713)
			(xy 3.763518 -250.764802) (xy 3.74015 -250.717558) (xy 3.714757 -250.66313) (xy 3.671165 -250.551205)
			(xy 3.635996 -250.436355) (xy 3.609445 -250.319212) (xy 3.591658 -250.200422) (xy 3.582733 -250.080639)
			(xy 3.582162 -250.020582) (xy 3.582654 -249.963717) (xy 3.590641 -249.850267) (xy 3.606581 -249.737659)
			(xy 3.630398 -249.62645) (xy 3.661973 -249.517191) (xy 3.701149 -249.410421) (xy 3.747734 -249.306669)
			(xy 3.801496 -249.206447) (xy 3.86217 -249.110253) (xy 3.929455 -249.018562) (xy 4.003018 -248.931826)
			(xy 4.082497 -248.850476) (xy 4.167497 -248.774914) (xy 4.257598 -248.705513) (xy 4.352354 -248.642618)
			(xy 4.451297 -248.586538) (xy 4.553937 -248.537552) (xy 4.659766 -248.495901) (xy 4.768262 -248.461792)
			(xy 4.878886 -248.435394) (xy 4.991092 -248.416837) (xy 5.104325 -248.406213) (xy 5.218025 -248.403574)
			(xy 5.33163 -248.408934) (xy 5.444576 -248.422265) (xy 5.556306 -248.443503) (xy 5.666267 -248.472542)
			(xy 5.773914 -248.509238) (xy 5.826506 -248.530872) (xy 5.879808 -248.553886) (xy 5.983301 -248.606528)
			(xy 6.08275 -248.666461) (xy 6.139151 -248.706233) (xy 7.813794 -248.706233) (xy 7.813794 -248.634911)
			(xy 7.82178 -248.564037) (xy 7.83765 -248.494502) (xy 7.861207 -248.427182) (xy 7.892152 -248.362923)
			(xy 7.930098 -248.302532) (xy 7.974567 -248.24677) (xy 8.025 -248.196337) (xy 8.080762 -248.151868)
			(xy 8.141153 -248.113922) (xy 8.205412 -248.082977) (xy 8.272732 -248.05942) (xy 8.342267 -248.04355)
			(xy 8.413141 -248.035564) (xy 8.484463 -248.035564) (xy 8.555337 -248.04355) (xy 8.624872 -248.05942)
			(xy 8.692192 -248.082977) (xy 8.756451 -248.113922) (xy 8.816842 -248.151868) (xy 8.872604 -248.196337)
			(xy 8.923037 -248.24677) (xy 8.967506 -248.302532) (xy 9.005452 -248.362923) (xy 9.036397 -248.427182)
			(xy 9.059954 -248.494502) (xy 9.075824 -248.564037) (xy 9.08381 -248.634911) (xy 9.08431 -248.670572)
			(xy 9.08381 -248.706233) (xy 9.075824 -248.777107) (xy 9.059954 -248.846642) (xy 9.036397 -248.913962)
			(xy 9.005452 -248.978221) (xy 8.967506 -249.038612) (xy 8.923037 -249.094374) (xy 8.872604 -249.144807)
			(xy 8.816842 -249.189276) (xy 8.756451 -249.227222) (xy 8.692192 -249.258167) (xy 8.624872 -249.281724)
			(xy 8.555337 -249.297594) (xy 8.484463 -249.30558) (xy 8.413141 -249.30558) (xy 8.342267 -249.297594)
			(xy 8.272732 -249.281724) (xy 8.205412 -249.258167) (xy 8.141153 -249.227222) (xy 8.080762 -249.189276)
			(xy 8.025 -249.144807) (xy 7.974567 -249.094374) (xy 7.930098 -249.038612) (xy 7.892152 -248.978221)
			(xy 7.861207 -248.913962) (xy 7.83765 -248.846642) (xy 7.82178 -248.777107) (xy 7.813794 -248.706233)
			(xy 6.139151 -248.706233) (xy 6.177642 -248.733375) (xy 6.267488 -248.806926) (xy 6.351824 -248.886735)
			(xy 6.430216 -248.972389) (xy 6.502259 -249.063448) (xy 6.567583 -249.159442) (xy 6.625849 -249.259876)
			(xy 6.676759 -249.364232) (xy 6.720049 -249.471973) (xy 6.755496 -249.582542) (xy 6.782917 -249.695369)
			(xy 6.802171 -249.809874) (xy 6.81316 -249.925465) (xy 6.815825 -250.041546) (xy 6.810153 -250.15752)
			(xy 6.796175 -250.272787) (xy 6.77396 -250.386754) (xy 6.743626 -250.498834) (xy 6.705326 -250.608447)
			(xy 6.68274 -250.661932) (xy 6.671004 -250.688738) (xy 6.645852 -250.741583) (xy 6.632448 -250.767596)
			(xy 6.623175 -250.787067) (xy 6.610598 -250.828316) (xy 6.605168 -250.871096) (xy 6.60704 -250.914179)
			(xy 6.616161 -250.956327) (xy 6.632269 -250.99633) (xy 6.654901 -251.033037) (xy 6.683407 -251.065395)
			(xy 6.716968 -251.092475) (xy 6.735572 -251.103384) (xy 6.759725 -251.11592) (xy 6.806016 -251.144535)
			(xy 6.828028 -251.160534) (xy 6.8496 -251.176966) (xy 6.890168 -251.212957) (xy 6.909054 -251.232416)
			(xy 6.929805 -251.254737) (xy 6.96741 -251.302702) (xy 7.000252 -251.354046) (xy 7.014464 -251.381006)
			(xy 7.01675 -251.385324) (xy 7.026959 -251.404647) (xy 7.052957 -251.439771) (xy 7.084583 -251.469928)
			(xy 7.120903 -251.494228) (xy 7.160845 -251.511955) (xy 7.203231 -251.522585) (xy 7.246811 -251.525805)
			(xy 7.2903 -251.52152) (xy 7.332414 -251.509856) (xy 7.37191 -251.491158) (xy 7.407625 -251.465977)
			(xy 7.423404 -251.450856) (xy 7.497826 -251.376434) (xy 7.759954 -251.11456) (xy 9.17829 -251.11456)
			(xy 11.327892 -253.264162) (xy 11.327892 -254.962914) (xy 11.328434 -254.979531) (xy 11.337029 -255.011633)
			(xy 11.353631 -255.040422) (xy 11.364976 -255.052576) (xy 14.536928 -258.224274) (xy 14.553412 -258.239008)
			(xy 14.590459 -258.263129) (xy 14.631119 -258.280481) (xy 14.674166 -258.290543) (xy 14.718305 -258.29301)
			(xy 14.762206 -258.287809) (xy 14.804546 -258.275097) (xy 14.844051 -258.255255) (xy 14.879531 -258.228882)
			(xy 14.909916 -258.196773) (xy 14.934293 -258.159893) (xy 14.951927 -258.119355) (xy 14.962286 -258.076378)
			(xy 14.964156 -258.054348) (xy 14.964156 -255.546606) (xy 18.483072 -252.027436) (xy 24.295608 -252.027436)
			(xy 24.319349 -252.026904) (xy 24.366006 -252.018086) (xy 24.410214 -252.000759) (xy 24.450436 -251.975524)
			(xy 24.485273 -251.94326) (xy 24.513514 -251.905089) (xy 24.534176 -251.862338) (xy 24.546541 -251.816493)
			(xy 24.550179 -251.76915) (xy 24.548084 -251.745496) (xy 24.545501 -251.717715) (xy 24.547515 -251.661957)
			(xy 24.557627 -251.607087) (xy 24.575623 -251.554275) (xy 24.601119 -251.504648) (xy 24.633571 -251.459262)
			(xy 24.672287 -251.419087) (xy 24.716441 -251.384979) (xy 24.765092 -251.357665) (xy 24.817203 -251.337729)
			(xy 24.871661 -251.325594) (xy 24.927306 -251.32152) (xy 24.982951 -251.325594) (xy 25.037409 -251.337729)
			(xy 25.08952 -251.357665) (xy 25.138171 -251.384979) (xy 25.182325 -251.419087) (xy 25.221041 -251.459262)
			(xy 25.253493 -251.504648) (xy 25.278989 -251.554275) (xy 25.296985 -251.607087) (xy 25.307097 -251.661957)
			(xy 25.309111 -251.717715) (xy 25.306528 -251.745496) (xy 25.304449 -251.76915) (xy 25.308086 -251.81649)
			(xy 25.320451 -251.86233) (xy 25.341112 -251.905078) (xy 25.369351 -251.943246) (xy 25.404186 -251.975507)
			(xy 25.444406 -252.000738) (xy 25.488611 -252.018063) (xy 25.535265 -252.026878) (xy 25.559004 -252.027436)
			(xy 27.94762 -252.027436) (xy 29.29382 -250.681236) (xy 29.356304 -250.681236) (xy 29.378978 -250.680736)
			(xy 29.423606 -250.672686) (xy 29.466096 -250.656841) (xy 29.505098 -250.633706) (xy 29.539374 -250.604015)
			(xy 29.567836 -250.56871) (xy 29.589578 -250.528914) (xy 29.603911 -250.485891) (xy 29.61038 -250.441007)
			(xy 29.608778 -250.395687) (xy 29.599156 -250.351371) (xy 29.591 -250.330208) (xy 29.574763 -250.289765)
			(xy 29.548973 -250.206512) (xy 29.530999 -250.121229) (xy 29.520996 -250.034649) (xy 29.51905 -249.947515)
			(xy 29.525177 -249.860574) (xy 29.539325 -249.774574) (xy 29.561372 -249.690252) (xy 29.591129 -249.608334)
			(xy 29.609288 -249.568716) (xy 29.618715 -249.547483) (xy 29.630539 -249.502561) (xy 29.634003 -249.456238)
			(xy 29.62899 -249.410057) (xy 29.615668 -249.365556) (xy 29.594481 -249.324217) (xy 29.566134 -249.287417)
			(xy 29.531571 -249.256382) (xy 29.491943 -249.232144) (xy 29.448571 -249.215512) (xy 29.402898 -249.207039)
			(xy 29.379672 -249.206512) (xy 27.026362 -249.206512) (xy 26.186892 -248.366788) (xy 25.58034 -247.760236)
			(xy 25.58034 -246.94388) (xy 25.580808 -246.913677) (xy 25.588344 -246.853742) (xy 25.603295 -246.795215)
			(xy 25.625429 -246.739009) (xy 25.654399 -246.686002) (xy 25.689753 -246.637022) (xy 25.730939 -246.592833)
			(xy 25.777315 -246.554125) (xy 25.828156 -246.521503) (xy 25.882668 -246.495476) (xy 25.94 -246.476451)
			(xy 25.999257 -246.464723) (xy 26.059515 -246.460477) (xy 26.119831 -246.463779) (xy 26.179265 -246.474577)
			(xy 26.236888 -246.492703) (xy 26.291801 -246.517873) (xy 26.317702 -246.533416) (xy 26.331351 -246.541338)
			(xy 26.361413 -246.550905) (xy 26.392904 -246.552808) (xy 26.4239 -246.54693) (xy 26.452508 -246.533631)
			(xy 26.465022 -246.524018) (xy 26.490054 -246.504252) (xy 26.544348 -246.470783) (xy 26.602576 -246.444754)
			(xy 26.663724 -246.426617) (xy 26.695146 -246.421148) (xy 26.713816 -246.418341) (xy 26.751451 -246.415292)
			(xy 26.77033 -246.415052) (xy 28.552394 -246.415052) (xy 29.25953 -245.707916) (xy 29.40685 -245.707916)
			(xy 29.430424 -245.707432) (xy 29.476774 -245.698799) (xy 29.520736 -245.681764) (xy 29.560802 -245.656913)
			(xy 29.595595 -245.625097) (xy 29.623923 -245.58741) (xy 29.644813 -245.545143) (xy 29.657548 -245.499749)
			(xy 29.661691 -245.452784) (xy 29.657099 -245.405861) (xy 29.643931 -245.36059) (xy 29.633672 -245.339362)
			(xy 29.613442 -245.301142) (xy 29.579267 -245.221698) (xy 29.552531 -245.139452) (xy 29.533461 -245.055098)
			(xy 29.522217 -244.96935) (xy 29.518895 -244.882931) (xy 29.523522 -244.796573) (xy 29.536059 -244.711004)
			(xy 29.556401 -244.626948) (xy 29.584376 -244.545115) (xy 29.619747 -244.466197) (xy 29.662215 -244.39086)
			(xy 29.711422 -244.319741) (xy 29.766951 -244.25344) (xy 29.828334 -244.192519) (xy 29.895051 -244.137492)
			(xy 29.96654 -244.088824) (xy 30.042196 -244.046926) (xy 30.121379 -244.012152) (xy 30.203421 -243.984797)
			(xy 30.287628 -243.96509) (xy 30.373289 -243.953199) (xy 30.45968 -243.949224) (xy 30.546071 -243.953199)
			(xy 30.631732 -243.96509) (xy 30.715939 -243.984797) (xy 30.797981 -244.012152) (xy 30.877164 -244.046926)
			(xy 30.95282 -244.088824) (xy 31.024309 -244.137492) (xy 31.091026 -244.192519) (xy 31.152409 -244.25344)
			(xy 31.207938 -244.319741) (xy 31.257145 -244.39086) (xy 31.299613 -244.466197) (xy 31.334984 -244.545115)
			(xy 31.362959 -244.626948) (xy 31.383301 -244.711004) (xy 31.395838 -244.796573) (xy 31.400465 -244.882931)
			(xy 31.397143 -244.96935) (xy 31.385899 -245.055098) (xy 31.366829 -245.139452) (xy 31.340093 -245.221698)
			(xy 31.305918 -245.301142) (xy 31.285688 -245.339362) (xy 31.275523 -245.360624) (xy 31.26239 -245.405881)
			(xy 31.257822 -245.452782) (xy 31.261978 -245.499722) (xy 31.274713 -245.545091) (xy 31.295592 -245.587337)
			(xy 31.3239 -245.62501) (xy 31.358666 -245.656821) (xy 31.398699 -245.681679) (xy 31.442628 -245.698732)
			(xy 31.488948 -245.707398) (xy 31.51251 -245.707916) (xy 34.48685 -245.707916) (xy 34.510424 -245.707432)
			(xy 34.556774 -245.698799) (xy 34.600736 -245.681764) (xy 34.640802 -245.656913) (xy 34.675595 -245.625097)
			(xy 34.703923 -245.58741) (xy 34.724813 -245.545143) (xy 34.737548 -245.499749) (xy 34.741691 -245.452784)
			(xy 34.737099 -245.405861) (xy 34.723931 -245.36059) (xy 34.713672 -245.339362) (xy 34.693442 -245.301142)
			(xy 34.659267 -245.221698) (xy 34.632531 -245.139452) (xy 34.613461 -245.055098) (xy 34.602217 -244.96935)
			(xy 34.598895 -244.882931) (xy 34.603522 -244.796573) (xy 34.616059 -244.711004) (xy 34.636401 -244.626948)
			(xy 34.664376 -244.545115) (xy 34.699747 -244.466197) (xy 34.742215 -244.39086) (xy 34.791422 -244.319741)
			(xy 34.846951 -244.25344) (xy 34.908334 -244.192519) (xy 34.975051 -244.137492) (xy 35.04654 -244.088824)
			(xy 35.122196 -244.046926) (xy 35.201379 -244.012152) (xy 35.283421 -243.984797) (xy 35.367628 -243.96509)
			(xy 35.453289 -243.953199) (xy 35.53968 -243.949224) (xy 35.626071 -243.953199) (xy 35.711732 -243.96509)
			(xy 35.795939 -243.984797) (xy 35.877981 -244.012152) (xy 35.957164 -244.046926) (xy 36.03282 -244.088824)
			(xy 36.104309 -244.137492) (xy 36.171026 -244.192519) (xy 36.232409 -244.25344) (xy 36.287938 -244.319741)
			(xy 36.337145 -244.39086) (xy 36.379613 -244.466197) (xy 36.414984 -244.545115) (xy 36.442959 -244.626948)
			(xy 36.463301 -244.711004) (xy 36.465417 -244.725444) (xy 44.159168 -244.725444) (xy 44.163239 -244.669822)
			(xy 44.175365 -244.615385) (xy 44.195288 -244.563294) (xy 44.222584 -244.514659) (xy 44.25667 -244.470516)
			(xy 44.296819 -244.431807) (xy 44.342177 -244.399356) (xy 44.391777 -244.373855) (xy 44.444561 -244.355848)
			(xy 44.499404 -244.345718) (xy 44.555138 -244.343681) (xy 44.610575 -244.349781) (xy 44.664532 -244.363887)
			(xy 44.715861 -244.385699) (xy 44.763467 -244.414753) (xy 44.806335 -244.450428) (xy 44.843552 -244.491965)
			(xy 44.874325 -244.538478) (xy 44.897997 -244.588975) (xy 44.914065 -244.642382) (xy 44.922185 -244.697558)
			(xy 44.922694 -244.725444) (xy 44.922185 -244.75333) (xy 44.914065 -244.808506) (xy 44.897997 -244.861913)
			(xy 44.874325 -244.91241) (xy 44.843552 -244.958923) (xy 44.806335 -245.00046) (xy 44.763467 -245.036135)
			(xy 44.715861 -245.065189) (xy 44.664532 -245.087001) (xy 44.610575 -245.101107) (xy 44.555138 -245.107207)
			(xy 44.499404 -245.10517) (xy 44.444561 -245.09504) (xy 44.391777 -245.077033) (xy 44.342177 -245.051532)
			(xy 44.296819 -245.019081) (xy 44.25667 -244.980372) (xy 44.222584 -244.936229) (xy 44.195288 -244.887594)
			(xy 44.175365 -244.835503) (xy 44.163239 -244.781066) (xy 44.159168 -244.725444) (xy 36.465417 -244.725444)
			(xy 36.475838 -244.796573) (xy 36.480465 -244.882931) (xy 36.477143 -244.96935) (xy 36.465899 -245.055098)
			(xy 36.446829 -245.139452) (xy 36.420093 -245.221698) (xy 36.385918 -245.301142) (xy 36.365688 -245.339362)
			(xy 36.355523 -245.360624) (xy 36.34239 -245.405881) (xy 36.337822 -245.452782) (xy 36.341978 -245.499722)
			(xy 36.354713 -245.545091) (xy 36.375592 -245.587337) (xy 36.4039 -245.62501) (xy 36.425622 -245.644886)
			(xy 66.360724 -245.644886) (xy 66.364613 -245.590538) (xy 66.376197 -245.537298) (xy 66.39524 -245.486248)
			(xy 66.421355 -245.438428) (xy 66.454009 -245.394811) (xy 66.492539 -245.356285) (xy 66.536159 -245.323635)
			(xy 66.583981 -245.297525) (xy 66.635033 -245.278487) (xy 66.688274 -245.266908) (xy 66.742622 -245.263024)
			(xy 66.796969 -245.266914) (xy 66.850209 -245.278499) (xy 66.901259 -245.297544) (xy 66.949078 -245.323659)
			(xy 66.971164 -245.339616) (xy 66.990176 -245.353212) (xy 67.032059 -245.373944) (xy 67.077027 -245.38667)
			(xy 67.123564 -245.39096) (xy 67.170101 -245.38667) (xy 67.215069 -245.373944) (xy 67.256952 -245.353212)
			(xy 67.275964 -245.339616) (xy 67.298031 -245.323621) (xy 67.34586 -245.297491) (xy 67.396921 -245.278435)
			(xy 67.450175 -245.26684) (xy 67.504537 -245.262943) (xy 67.5589 -245.266822) (xy 67.612158 -245.278399)
			(xy 67.663226 -245.297439) (xy 67.711064 -245.323553) (xy 67.754698 -245.356209) (xy 67.79324 -245.394744)
			(xy 67.825906 -245.438371) (xy 67.852029 -245.486204) (xy 67.871079 -245.537268) (xy 67.882667 -245.590523)
			(xy 67.886557 -245.644886) (xy 69.352317 -245.644886) (xy 69.356206 -245.590537) (xy 69.367791 -245.537295)
			(xy 69.386835 -245.486243) (xy 69.41295 -245.438422) (xy 69.445606 -245.394804) (xy 69.484137 -245.356278)
			(xy 69.527758 -245.323627) (xy 69.575583 -245.297517) (xy 69.626636 -245.278479) (xy 69.67988 -245.2669)
			(xy 69.734229 -245.263017) (xy 69.788577 -245.266908) (xy 69.841819 -245.278495) (xy 69.89287 -245.297541)
			(xy 69.94069 -245.323658) (xy 69.962776 -245.339616) (xy 69.981788 -245.353212) (xy 70.023671 -245.373944)
			(xy 70.068639 -245.38667) (xy 70.115176 -245.39096) (xy 70.161713 -245.38667) (xy 70.206681 -245.373944)
			(xy 70.248564 -245.353212) (xy 70.267576 -245.339616) (xy 70.289642 -245.323622) (xy 70.337471 -245.297494)
			(xy 70.388531 -245.278439) (xy 70.441784 -245.266846) (xy 70.496144 -245.26295) (xy 70.550505 -245.26683)
			(xy 70.603761 -245.278408) (xy 70.654827 -245.297447) (xy 70.702663 -245.323561) (xy 70.746296 -245.356217)
			(xy 70.784837 -245.394751) (xy 70.817501 -245.438377) (xy 70.843623 -245.486209) (xy 70.862672 -245.537271)
			(xy 70.87426 -245.590525) (xy 70.87815 -245.644886) (xy 70.874264 -245.699247) (xy 70.86268 -245.752501)
			(xy 70.843635 -245.803565) (xy 70.817516 -245.851398) (xy 70.784856 -245.895028) (xy 70.746318 -245.933564)
			(xy 70.702688 -245.966223) (xy 70.654853 -245.992341) (xy 70.603789 -246.011384) (xy 70.550534 -246.022966)
			(xy 70.496173 -246.02685) (xy 70.441812 -246.022958) (xy 70.388559 -246.011369) (xy 70.337497 -245.992318)
			(xy 70.289666 -245.966194) (xy 70.267576 -245.950232) (xy 70.248564 -245.936636) (xy 70.206681 -245.915904)
			(xy 70.161713 -245.903178) (xy 70.115176 -245.898888) (xy 70.068639 -245.903178) (xy 70.023671 -245.915904)
			(xy 69.981788 -245.936636) (xy 69.962776 -245.950232) (xy 69.940666 -245.966158) (xy 69.892843 -245.992271)
			(xy 69.841791 -246.011313) (xy 69.788549 -246.022896) (xy 69.7342 -246.026783) (xy 69.679851 -246.022896)
			(xy 69.626609 -246.011313) (xy 69.575557 -245.992271) (xy 69.527734 -245.966158) (xy 69.484115 -245.933504)
			(xy 69.445587 -245.894974) (xy 69.412935 -245.851354) (xy 69.386823 -245.80353) (xy 69.367783 -245.752478)
			(xy 69.356202 -245.699235) (xy 69.352317 -245.644886) (xy 67.886557 -245.644886) (xy 67.882671 -245.699248)
			(xy 67.871087 -245.752504) (xy 67.852041 -245.80357) (xy 67.825921 -245.851404) (xy 67.793259 -245.895035)
			(xy 67.75472 -245.933572) (xy 67.711088 -245.966232) (xy 67.663252 -245.992349) (xy 67.612186 -246.011392)
			(xy 67.558929 -246.022974) (xy 67.504566 -246.026857) (xy 67.450204 -246.022964) (xy 67.396949 -246.011373)
			(xy 67.345886 -245.992321) (xy 67.298055 -245.966195) (xy 67.275964 -245.950232) (xy 67.256952 -245.936636)
			(xy 67.215069 -245.915904) (xy 67.170101 -245.903178) (xy 67.123564 -245.898888) (xy 67.077027 -245.903178)
			(xy 67.032059 -245.915904) (xy 66.990176 -245.936636) (xy 66.971164 -245.950232) (xy 66.949054 -245.966157)
			(xy 66.901233 -245.992268) (xy 66.850182 -246.011309) (xy 66.79694 -246.02289) (xy 66.742593 -246.026776)
			(xy 66.688246 -246.022888) (xy 66.635005 -246.011305) (xy 66.583955 -245.992263) (xy 66.536134 -245.966149)
			(xy 66.492517 -245.933496) (xy 66.45399 -245.894967) (xy 66.421339 -245.851348) (xy 66.395228 -245.803526)
			(xy 66.376189 -245.752474) (xy 66.364609 -245.699233) (xy 66.360724 -245.644886) (xy 36.425622 -245.644886)
			(xy 36.438666 -245.656821) (xy 36.478699 -245.681679) (xy 36.522628 -245.698732) (xy 36.568948 -245.707398)
			(xy 36.59251 -245.707916) (xy 43.863006 -245.707916) (xy 44.82592 -246.67083) (xy 44.847922 -246.693563)
			(xy 44.886435 -246.743755) (xy 44.918068 -246.798544) (xy 44.942279 -246.856994) (xy 44.958653 -246.918103)
			(xy 44.966911 -246.980827) (xy 44.966911 -247.044093) (xy 44.958653 -247.106817) (xy 44.942279 -247.167926)
			(xy 44.918068 -247.226376) (xy 44.886435 -247.281165) (xy 44.847922 -247.331357) (xy 44.803187 -247.376092)
			(xy 44.752995 -247.414605) (xy 44.698206 -247.446238) (xy 44.639756 -247.470449) (xy 44.578647 -247.486823)
			(xy 44.524331 -247.493974) (xy 66.323798 -247.493974) (xy 66.32769 -247.439619) (xy 66.339278 -247.386372)
			(xy 66.358326 -247.335317) (xy 66.384447 -247.287492) (xy 66.417109 -247.243871) (xy 66.455647 -247.205344)
			(xy 66.499276 -247.172693) (xy 66.547108 -247.146585) (xy 66.598168 -247.12755) (xy 66.651418 -247.115976)
			(xy 66.705774 -247.112098) (xy 66.760128 -247.115997) (xy 66.813373 -247.127591) (xy 66.864427 -247.146646)
			(xy 66.912248 -247.172773) (xy 66.934334 -247.188736) (xy 66.953346 -247.202332) (xy 66.995229 -247.223064)
			(xy 67.040197 -247.23579) (xy 67.086734 -247.24008) (xy 67.133271 -247.23579) (xy 67.178239 -247.223064)
			(xy 67.220122 -247.202332) (xy 67.239134 -247.188736) (xy 67.26118 -247.17272) (xy 67.309006 -247.146599)
			(xy 67.360062 -247.12755) (xy 67.41331 -247.115961) (xy 67.467665 -247.112069) (xy 67.522021 -247.115951)
			(xy 67.57527 -247.12753) (xy 67.62633 -247.146569) (xy 67.674161 -247.172682) (xy 67.717788 -247.205335)
			(xy 67.756325 -247.243865) (xy 67.788985 -247.287487) (xy 67.815105 -247.335314) (xy 67.834153 -247.386371)
			(xy 67.84574 -247.439619) (xy 67.849631 -247.493974) (xy 69.315391 -247.493974) (xy 69.319283 -247.439618)
			(xy 69.330871 -247.386369) (xy 69.349921 -247.335312) (xy 69.376043 -247.287486) (xy 69.408706 -247.243864)
			(xy 69.447245 -247.205336) (xy 69.490876 -247.172685) (xy 69.538709 -247.146576) (xy 69.589772 -247.127541)
			(xy 69.643024 -247.115968) (xy 69.697381 -247.112091) (xy 69.751736 -247.115991) (xy 69.804983 -247.127587)
			(xy 69.856037 -247.146643) (xy 69.90386 -247.172772) (xy 69.925946 -247.188736) (xy 69.944958 -247.202332)
			(xy 69.986841 -247.223064) (xy 70.031809 -247.23579) (xy 70.078346 -247.24008) (xy 70.124883 -247.23579)
			(xy 70.169851 -247.223064) (xy 70.211734 -247.202332) (xy 70.230746 -247.188736) (xy 70.252792 -247.172721)
			(xy 70.300617 -247.146602) (xy 70.351672 -247.127555) (xy 70.404918 -247.115967) (xy 70.459272 -247.112076)
			(xy 70.513626 -247.115959) (xy 70.566874 -247.127539) (xy 70.617932 -247.146578) (xy 70.665761 -247.17269)
			(xy 70.709386 -247.205343) (xy 70.747921 -247.243872) (xy 70.78058 -247.287493) (xy 70.806699 -247.335318)
			(xy 70.825746 -247.386374) (xy 70.837333 -247.43962) (xy 70.841224 -247.493974) (xy 70.83734 -247.548328)
			(xy 70.825761 -247.601575) (xy 70.806721 -247.652633) (xy 70.780609 -247.700462) (xy 70.747956 -247.744088)
			(xy 70.709426 -247.782622) (xy 70.665805 -247.815281) (xy 70.61798 -247.8414) (xy 70.566924 -247.860447)
			(xy 70.513678 -247.872033) (xy 70.459325 -247.875924) (xy 70.404971 -247.87204) (xy 70.351723 -247.86046)
			(xy 70.300665 -247.84142) (xy 70.252836 -247.815308) (xy 70.230746 -247.799352) (xy 70.211734 -247.785756)
			(xy 70.169851 -247.765024) (xy 70.124883 -247.752298) (xy 70.078346 -247.748008) (xy 70.031809 -247.752298)
			(xy 69.986841 -247.765024) (xy 69.944958 -247.785756) (xy 69.925946 -247.799352) (xy 69.903815 -247.815257)
			(xy 69.855989 -247.841379) (xy 69.804932 -247.860428) (xy 69.751684 -247.872017) (xy 69.697328 -247.875909)
			(xy 69.642971 -247.872025) (xy 69.589721 -247.860444) (xy 69.538661 -247.841402) (xy 69.490831 -247.815287)
			(xy 69.447205 -247.78263) (xy 69.408671 -247.744096) (xy 69.376014 -247.70047) (xy 69.349899 -247.65264)
			(xy 69.330856 -247.60158) (xy 69.319275 -247.54833) (xy 69.315391 -247.493974) (xy 67.849631 -247.493974)
			(xy 67.845748 -247.548329) (xy 67.834167 -247.601579) (xy 67.815127 -247.652638) (xy 67.789014 -247.700468)
			(xy 67.756359 -247.744095) (xy 67.717828 -247.78263) (xy 67.674205 -247.81529) (xy 67.626378 -247.841409)
			(xy 67.575321 -247.860455) (xy 67.522073 -247.872041) (xy 67.467718 -247.875931) (xy 67.413362 -247.872046)
			(xy 67.360113 -247.860465) (xy 67.309054 -247.841423) (xy 67.261225 -247.815309) (xy 67.239134 -247.799352)
			(xy 67.220122 -247.785756) (xy 67.178239 -247.765024) (xy 67.133271 -247.752298) (xy 67.086734 -247.748008)
			(xy 67.040197 -247.752298) (xy 66.995229 -247.765024) (xy 66.953346 -247.785756) (xy 66.934334 -247.799352)
			(xy 66.912204 -247.815255) (xy 66.864379 -247.841376) (xy 66.813323 -247.860424) (xy 66.760075 -247.872011)
			(xy 66.705721 -247.875902) (xy 66.651366 -247.872017) (xy 66.598118 -247.860435) (xy 66.54706 -247.841393)
			(xy 66.499232 -247.815278) (xy 66.455607 -247.782622) (xy 66.417075 -247.744089) (xy 66.384419 -247.700464)
			(xy 66.358304 -247.652635) (xy 66.339263 -247.601577) (xy 66.327682 -247.548328) (xy 66.323798 -247.493974)
			(xy 44.524331 -247.493974) (xy 44.515923 -247.495081) (xy 44.452657 -247.495081) (xy 44.389933 -247.486823)
			(xy 44.328824 -247.470449) (xy 44.270374 -247.446238) (xy 44.215585 -247.414605) (xy 44.165393 -247.376092)
			(xy 44.14266 -247.35409) (xy 43.462702 -246.674132) (xy 43.209464 -246.674132) (xy 43.186942 -246.67462)
			(xy 43.142603 -246.682565) (xy 43.100359 -246.6982) (xy 43.061532 -246.721036) (xy 43.027336 -246.750357)
			(xy 42.998844 -246.785246) (xy 42.976947 -246.82461) (xy 42.96233 -246.867217) (xy 42.955452 -246.911734)
			(xy 42.956526 -246.956765) (xy 42.960544 -246.978932) (xy 42.968118 -247.013738) (xy 42.976374 -247.084493)
			(xy 42.976664 -247.155727) (xy 42.968986 -247.226547) (xy 42.953435 -247.296063) (xy 42.930207 -247.363404)
			(xy 42.899594 -247.427725) (xy 42.861978 -247.488219) (xy 42.817833 -247.544125) (xy 42.767712 -247.594744)
			(xy 42.712244 -247.63944) (xy 42.652126 -247.677651) (xy 42.58811 -247.708899) (xy 42.521002 -247.732792)
			(xy 42.451643 -247.749029) (xy 42.380902 -247.757407) (xy 42.309669 -247.75782) (xy 42.238836 -247.750264)
			(xy 42.169293 -247.734834) (xy 42.101912 -247.711722) (xy 42.037538 -247.681219) (xy 41.97698 -247.643708)
			(xy 41.920997 -247.599659) (xy 41.870292 -247.549626) (xy 41.847516 -247.522238) (xy 41.837324 -247.510368)
			(xy 41.812324 -247.491574) (xy 41.783499 -247.479433) (xy 41.752587 -247.474676) (xy 41.721446 -247.477589)
			(xy 41.706546 -247.48236) (xy 41.67787 -247.491872) (xy 41.618443 -247.502755) (xy 41.558044 -247.504141)
			(xy 41.498181 -247.495996) (xy 41.440349 -247.478522) (xy 41.412922 -247.46585) (xy 41.388716 -247.453585)
			(xy 41.343735 -247.423232) (xy 41.303513 -247.386807) (xy 41.268862 -247.345047) (xy 41.240484 -247.298795)
			(xy 41.22928 -247.27408) (xy 41.218827 -247.24869) (xy 41.204498 -247.195685) (xy 41.197919 -247.141173)
			(xy 41.199227 -247.086281) (xy 41.208395 -247.032144) (xy 41.216326 -247.005856) (xy 41.222558 -246.98502)
			(xy 41.228627 -246.94196) (xy 41.227276 -246.898494) (xy 41.218546 -246.855894) (xy 41.202691 -246.815401)
			(xy 41.180174 -246.778198) (xy 41.151652 -246.745372) (xy 41.117959 -246.717881) (xy 41.080076 -246.696527)
			(xy 41.039112 -246.681934) (xy 40.996261 -246.674528) (xy 40.974518 -246.674132) (xy 36.623244 -246.674132)
			(xy 36.600252 -246.674652) (xy 36.555027 -246.682972) (xy 36.512037 -246.699294) (xy 36.472685 -246.723085)
			(xy 36.438257 -246.753568) (xy 36.409875 -246.789749) (xy 36.388468 -246.830447) (xy 36.374732 -246.874332)
			(xy 36.369118 -246.919972) (xy 36.371807 -246.965878) (xy 36.382713 -247.01055) (xy 36.391596 -247.031764)
			(xy 36.413694 -247.083072) (xy 36.429239 -247.123574) (xy 36.453688 -247.206819) (xy 36.47036 -247.291962)
			(xy 36.479115 -247.37828) (xy 36.479988 -247.421654) (xy 36.479757 -247.472126) (xy 36.469813 -247.572571)
			(xy 36.449174 -247.671375) (xy 36.434268 -247.719596) (xy 36.421463 -247.757867) (xy 36.390176 -247.832264)
			(xy 36.371784 -247.868186) (xy 36.362064 -247.887655) (xy 36.348691 -247.929059) (xy 36.342566 -247.972137)
			(xy 36.343867 -248.015628) (xy 36.352556 -248.058262) (xy 36.36838 -248.098793) (xy 36.390876 -248.136037)
			(xy 36.419387 -248.168906) (xy 36.453079 -248.196438) (xy 36.490968 -248.217829) (xy 36.531948 -248.232454)
			(xy 36.574819 -248.239886) (xy 36.596574 -248.240296) (xy 43.77817 -248.240296) (xy 44.009056 -248.471182)
			(xy 44.021188 -248.482572) (xy 44.049973 -248.499242) (xy 44.082088 -248.507909) (xy 44.098718 -248.50852)
			(xy 44.455588 -248.50852) (xy 44.487206 -248.509014) (xy 44.5499 -248.517266) (xy 44.610981 -248.533632)
			(xy 44.669404 -248.55783) (xy 44.724168 -248.589446) (xy 44.774336 -248.627941) (xy 44.819051 -248.672655)
			(xy 44.857547 -248.722822) (xy 44.889165 -248.777585) (xy 44.913365 -248.836007) (xy 44.929731 -248.897088)
			(xy 44.937985 -248.959782) (xy 44.937985 -249.023018) (xy 44.929731 -249.085712) (xy 44.913365 -249.146793)
			(xy 44.889165 -249.205215) (xy 44.857547 -249.259978) (xy 44.819051 -249.310145) (xy 44.774336 -249.354859)
			(xy 44.724168 -249.393354) (xy 44.669404 -249.42497) (xy 44.610981 -249.449168) (xy 44.581653 -249.457026)
			(xy 66.323728 -249.457026) (xy 66.327613 -249.402662) (xy 66.339195 -249.349403) (xy 66.35824 -249.298335)
			(xy 66.38436 -249.250498) (xy 66.417022 -249.206865) (xy 66.455561 -249.168325) (xy 66.499193 -249.135663)
			(xy 66.54703 -249.109543) (xy 66.598098 -249.090497) (xy 66.651356 -249.078913) (xy 66.705721 -249.075028)
			(xy 66.760085 -249.078919) (xy 66.813342 -249.090509) (xy 66.864408 -249.10956) (xy 66.912242 -249.135685)
			(xy 66.934334 -249.151648) (xy 66.953346 -249.165244) (xy 66.995229 -249.185976) (xy 67.040197 -249.198702)
			(xy 67.086734 -249.202992) (xy 67.133271 -249.198702) (xy 67.178239 -249.185976) (xy 67.220122 -249.165244)
			(xy 67.239134 -249.151648) (xy 67.261263 -249.13575) (xy 67.309083 -249.109641) (xy 67.360133 -249.090603)
			(xy 67.413372 -249.079023) (xy 67.467718 -249.075139) (xy 67.522063 -249.079029) (xy 67.575301 -249.090613)
			(xy 67.626349 -249.109655) (xy 67.674167 -249.135769) (xy 67.717782 -249.168423) (xy 67.756306 -249.206951)
			(xy 67.788954 -249.25057) (xy 67.815063 -249.298391) (xy 67.8341 -249.349441) (xy 67.845678 -249.402681)
			(xy 67.849561 -249.457026) (xy 69.315321 -249.457026) (xy 69.319206 -249.40266) (xy 69.330789 -249.3494)
			(xy 69.349835 -249.298331) (xy 69.375955 -249.250492) (xy 69.408618 -249.206858) (xy 69.447159 -249.168317)
			(xy 69.490793 -249.135654) (xy 69.538632 -249.109534) (xy 69.589701 -249.090488) (xy 69.642961 -249.078905)
			(xy 69.697328 -249.075021) (xy 69.751694 -249.078913) (xy 69.804952 -249.090504) (xy 69.856019 -249.109557)
			(xy 69.903854 -249.135684) (xy 69.925946 -249.151648) (xy 69.944958 -249.165244) (xy 69.986841 -249.185976)
			(xy 70.031809 -249.198702) (xy 70.078346 -249.202992) (xy 70.124883 -249.198702) (xy 70.169851 -249.185976)
			(xy 70.211734 -249.165244) (xy 70.230746 -249.151648) (xy 70.252874 -249.135751) (xy 70.300694 -249.109644)
			(xy 70.351743 -249.090607) (xy 70.404981 -249.07903) (xy 70.459325 -249.075146) (xy 70.513668 -249.079037)
			(xy 70.566904 -249.090621) (xy 70.617951 -249.109664) (xy 70.665767 -249.135778) (xy 70.70938 -249.168431)
			(xy 70.747903 -249.206958) (xy 70.78055 -249.250576) (xy 70.806657 -249.298396) (xy 70.825693 -249.349444)
			(xy 70.837271 -249.402683) (xy 70.841154 -249.457026) (xy 70.837263 -249.51137) (xy 70.825678 -249.564606)
			(xy 70.806635 -249.615652) (xy 70.780521 -249.663468) (xy 70.747868 -249.707082) (xy 70.70934 -249.745604)
			(xy 70.665722 -249.778251) (xy 70.617903 -249.804358) (xy 70.566854 -249.823394) (xy 70.513616 -249.834971)
			(xy 70.459272 -249.838854) (xy 70.404928 -249.834963) (xy 70.351692 -249.823378) (xy 70.300646 -249.804334)
			(xy 70.25283 -249.77822) (xy 70.230746 -249.762264) (xy 70.211734 -249.748668) (xy 70.169851 -249.727936)
			(xy 70.124883 -249.71521) (xy 70.078346 -249.71092) (xy 70.031809 -249.71521) (xy 69.986841 -249.727936)
			(xy 69.944958 -249.748668) (xy 69.925946 -249.762264) (xy 69.903898 -249.778287) (xy 69.856067 -249.804421)
			(xy 69.805003 -249.823481) (xy 69.751746 -249.835079) (xy 69.697381 -249.838979) (xy 69.643014 -249.835102)
			(xy 69.589752 -249.823526) (xy 69.53868 -249.804488) (xy 69.490838 -249.778374) (xy 69.447199 -249.745717)
			(xy 69.408653 -249.707182) (xy 69.375983 -249.663552) (xy 69.349857 -249.615717) (xy 69.330804 -249.564651)
			(xy 69.319213 -249.511392) (xy 69.315321 -249.457026) (xy 67.849561 -249.457026) (xy 67.84567 -249.511371)
			(xy 67.834085 -249.56461) (xy 67.815041 -249.615657) (xy 67.788926 -249.663474) (xy 67.756271 -249.707089)
			(xy 67.717742 -249.745612) (xy 67.674123 -249.778259) (xy 67.626301 -249.804367) (xy 67.57525 -249.823402)
			(xy 67.522011 -249.834979) (xy 67.467665 -249.838861) (xy 67.41332 -249.834969) (xy 67.360082 -249.823383)
			(xy 67.309035 -249.804337) (xy 67.261218 -249.778221) (xy 67.239134 -249.762264) (xy 67.220122 -249.748668)
			(xy 67.178239 -249.727936) (xy 67.133271 -249.71521) (xy 67.086734 -249.71092) (xy 67.040197 -249.71521)
			(xy 66.995229 -249.727936) (xy 66.953346 -249.748668) (xy 66.934334 -249.762264) (xy 66.912286 -249.778286)
			(xy 66.864456 -249.804418) (xy 66.813393 -249.823476) (xy 66.760138 -249.835073) (xy 66.705774 -249.838972)
			(xy 66.651408 -249.835094) (xy 66.598149 -249.823518) (xy 66.547078 -249.804479) (xy 66.499238 -249.778366)
			(xy 66.455601 -249.745709) (xy 66.417056 -249.707175) (xy 66.384388 -249.663546) (xy 66.358262 -249.615713)
			(xy 66.33921 -249.564648) (xy 66.32762 -249.511391) (xy 66.323728 -249.457026) (xy 44.581653 -249.457026)
			(xy 44.5499 -249.465534) (xy 44.487206 -249.473786) (xy 44.455588 -249.474228) (xy 43.645836 -249.474228)
			(xy 43.533568 -249.36196) (xy 43.377866 -249.206512) (xy 43.166284 -249.206512) (xy 43.143705 -249.206995)
			(xy 43.099256 -249.214965) (xy 43.056916 -249.230668) (xy 43.01802 -249.253609) (xy 42.983793 -249.283066)
			(xy 42.955313 -249.31811) (xy 42.933477 -249.357638) (xy 42.918975 -249.400403) (xy 42.912262 -249.445059)
			(xy 42.91355 -249.490199) (xy 42.922799 -249.534399) (xy 42.930826 -249.555508) (xy 42.943905 -249.589201)
			(xy 42.963222 -249.65885) (xy 42.974501 -249.730243) (xy 42.976546 -249.766328) (xy 42.977552 -249.799783)
			(xy 42.973378 -249.866588) (xy 42.9622 -249.932583) (xy 42.944145 -249.997036) (xy 42.919411 -250.059234)
			(xy 42.888273 -250.118485) (xy 42.851077 -250.174133) (xy 42.808235 -250.225561) (xy 42.784522 -250.249182)
			(xy 42.76879 -250.265895) (xy 42.743026 -250.303876) (xy 42.724501 -250.345865) (xy 42.713816 -250.390498)
			(xy 42.71132 -250.436325) (xy 42.717093 -250.481855) (xy 42.730948 -250.525608) (xy 42.752435 -250.566162)
			(xy 42.780854 -250.602199) (xy 42.815283 -250.632546) (xy 42.854601 -250.656219) (xy 42.897531 -250.672446)
			(xy 42.942677 -250.6807) (xy 42.965624 -250.681236) (xy 43.944032 -250.681236) (xy 44.22902 -250.966224)
			(xy 44.638468 -250.966224) (xy 44.670099 -250.966717) (xy 44.732821 -250.974971) (xy 44.793929 -250.991341)
			(xy 44.852378 -251.015548) (xy 44.907166 -251.047176) (xy 44.957357 -251.085686) (xy 45.002092 -251.130418)
			(xy 45.040606 -251.180607) (xy 45.072238 -251.235394) (xy 45.096449 -251.29384) (xy 45.112823 -251.354947)
			(xy 45.121081 -251.417669) (xy 45.121081 -251.480931) (xy 45.112823 -251.543653) (xy 45.097584 -251.600523)
			(xy 66.323733 -251.600523) (xy 66.327618 -251.546159) (xy 66.339201 -251.492901) (xy 66.358246 -251.441834)
			(xy 66.384366 -251.393998) (xy 66.417028 -251.350366) (xy 66.455567 -251.311826) (xy 66.499199 -251.279165)
			(xy 66.547036 -251.253045) (xy 66.598103 -251.234001) (xy 66.65136 -251.222418) (xy 66.705725 -251.218533)
			(xy 66.760088 -251.222425) (xy 66.813344 -251.234014) (xy 66.864409 -251.253066) (xy 66.912242 -251.279191)
			(xy 66.934334 -251.295154) (xy 66.953346 -251.30875) (xy 66.995229 -251.329482) (xy 67.040197 -251.342208)
			(xy 67.086734 -251.346498) (xy 67.133271 -251.342208) (xy 67.178239 -251.329482) (xy 67.220122 -251.30875)
			(xy 67.239134 -251.295154) (xy 67.261257 -251.279248) (xy 67.309078 -251.253138) (xy 67.360128 -251.234099)
			(xy 67.413368 -251.222519) (xy 67.467714 -251.218634) (xy 67.52206 -251.222523) (xy 67.575299 -251.234107)
			(xy 67.626348 -251.25315) (xy 67.674167 -251.279263) (xy 67.717783 -251.311917) (xy 67.756307 -251.350445)
			(xy 67.788957 -251.394064) (xy 67.815066 -251.441886) (xy 67.834103 -251.492936) (xy 67.845682 -251.546177)
			(xy 67.849566 -251.600523) (xy 69.315325 -251.600523) (xy 69.319211 -251.546157) (xy 69.330794 -251.492898)
			(xy 69.34984 -251.441829) (xy 69.375961 -251.393992) (xy 69.408624 -251.350359) (xy 69.447165 -251.311818)
			(xy 69.490799 -251.279156) (xy 69.538637 -251.253037) (xy 69.589706 -251.233992) (xy 69.642966 -251.22241)
			(xy 69.697331 -251.218525) (xy 69.751697 -251.222419) (xy 69.804954 -251.23401) (xy 69.85602 -251.253063)
			(xy 69.903854 -251.27919) (xy 69.925946 -251.295154) (xy 69.944958 -251.30875) (xy 69.986841 -251.329482)
			(xy 70.031809 -251.342208) (xy 70.078346 -251.346498) (xy 70.124883 -251.342208) (xy 70.169851 -251.329482)
			(xy 70.211734 -251.30875) (xy 70.230746 -251.295154) (xy 70.252869 -251.279249) (xy 70.300689 -251.253141)
			(xy 70.351738 -251.234104) (xy 70.404976 -251.222525) (xy 70.459321 -251.218641) (xy 70.513665 -251.222531)
			(xy 70.566902 -251.234115) (xy 70.617949 -251.253158) (xy 70.665766 -251.279272) (xy 70.709381 -251.311925)
			(xy 70.747904 -251.350452) (xy 70.780552 -251.39407) (xy 70.80666 -251.441891) (xy 70.825697 -251.49294)
			(xy 70.837275 -251.546178) (xy 70.841159 -251.600523) (xy 70.837268 -251.654867) (xy 70.825684 -251.708104)
			(xy 70.806641 -251.759151) (xy 70.780527 -251.806968) (xy 70.747874 -251.850582) (xy 70.709346 -251.889105)
			(xy 70.665728 -251.921753) (xy 70.617908 -251.947861) (xy 70.566859 -251.966897) (xy 70.51362 -251.978475)
			(xy 70.459275 -251.982359) (xy 70.404931 -251.978468) (xy 70.351694 -251.966884) (xy 70.300647 -251.94784)
			(xy 70.25283 -251.921726) (xy 70.230746 -251.90577) (xy 70.211734 -251.892174) (xy 70.169851 -251.871442)
			(xy 70.124883 -251.858716) (xy 70.078346 -251.854426) (xy 70.031809 -251.858716) (xy 69.986841 -251.871442)
			(xy 69.944958 -251.892174) (xy 69.925946 -251.90577) (xy 69.903892 -251.921785) (xy 69.856061 -251.947918)
			(xy 69.804998 -251.966977) (xy 69.751742 -251.978575) (xy 69.697377 -251.982475) (xy 69.643011 -251.978597)
			(xy 69.58975 -251.967021) (xy 69.538679 -251.947982) (xy 69.490837 -251.921868) (xy 69.447199 -251.889211)
			(xy 69.408654 -251.850676) (xy 69.375986 -251.807047) (xy 69.349859 -251.759212) (xy 69.330807 -251.708146)
			(xy 69.319217 -251.654888) (xy 69.315325 -251.600523) (xy 67.849566 -251.600523) (xy 67.845676 -251.654869)
			(xy 67.834091 -251.708107) (xy 67.815047 -251.759156) (xy 67.788932 -251.806974) (xy 67.756277 -251.850589)
			(xy 67.717748 -251.889113) (xy 67.674128 -251.921761) (xy 67.626306 -251.947869) (xy 67.575255 -251.966906)
			(xy 67.522015 -251.978483) (xy 67.467668 -251.982366) (xy 67.413323 -251.978474) (xy 67.360084 -251.966888)
			(xy 67.309036 -251.947843) (xy 67.261219 -251.921727) (xy 67.239134 -251.90577) (xy 67.220122 -251.892174)
			(xy 67.178239 -251.871442) (xy 67.133271 -251.858716) (xy 67.086734 -251.854426) (xy 67.040197 -251.858716)
			(xy 66.995229 -251.871442) (xy 66.953346 -251.892174) (xy 66.934334 -251.90577) (xy 66.912281 -251.921784)
			(xy 66.864451 -251.947915) (xy 66.813388 -251.966973) (xy 66.760133 -251.978569) (xy 66.70577 -251.982467)
			(xy 66.651406 -251.978589) (xy 66.598146 -251.967012) (xy 66.547077 -251.947973) (xy 66.499237 -251.92186)
			(xy 66.455601 -251.889204) (xy 66.417057 -251.850669) (xy 66.38439 -251.807041) (xy 66.358265 -251.759207)
			(xy 66.339214 -251.708143) (xy 66.327624 -251.654886) (xy 66.323733 -251.600523) (xy 45.097584 -251.600523)
			(xy 45.096449 -251.60476) (xy 45.072238 -251.663206) (xy 45.040606 -251.717993) (xy 45.002092 -251.768182)
			(xy 44.957357 -251.812914) (xy 44.907166 -251.851424) (xy 44.852378 -251.883052) (xy 44.793929 -251.907259)
			(xy 44.732821 -251.923629) (xy 44.670099 -251.931883) (xy 44.638468 -251.93244) (xy 43.828716 -251.93244)
			(xy 43.543728 -251.647452) (xy 43.032172 -251.647452) (xy 43.010315 -251.64791) (xy 42.967247 -251.655394)
			(xy 42.926095 -251.670137) (xy 42.888072 -251.691704) (xy 42.854301 -251.719459) (xy 42.825776 -251.752583)
			(xy 42.80334 -251.7901) (xy 42.787654 -251.830902) (xy 42.77918 -251.873786) (xy 42.77817 -251.917488)
			(xy 42.784652 -251.960718) (xy 42.798435 -252.002202) (xy 42.819113 -252.040715) (xy 42.832274 -252.05817)
			(xy 42.854609 -252.086088) (xy 42.893544 -252.146054) (xy 42.925502 -252.210013) (xy 42.950077 -252.277155)
			(xy 42.966959 -252.346632) (xy 42.975935 -252.417565) (xy 42.976891 -252.489057) (xy 42.969815 -252.560204)
			(xy 42.954797 -252.630107) (xy 42.932026 -252.697882) (xy 42.901791 -252.762673) (xy 42.864472 -252.82366)
			(xy 42.820544 -252.880071) (xy 42.77056 -252.931195) (xy 42.715153 -252.976384) (xy 42.655023 -253.015067)
			(xy 42.59093 -253.046755) (xy 42.523685 -253.071048) (xy 42.454138 -253.087638) (xy 42.383168 -253.096316)
			(xy 42.311673 -253.096971) (xy 42.240556 -253.089596) (xy 42.170717 -253.074284) (xy 42.103038 -253.051229)
			(xy 42.038375 -253.020721) (xy 41.977546 -252.983147) (xy 41.921319 -252.938981) (xy 41.870406 -252.888783)
			(xy 41.847516 -252.861318) (xy 41.837323 -252.84945) (xy 41.812322 -252.830659) (xy 41.783499 -252.81852)
			(xy 41.752587 -252.813764) (xy 41.721448 -252.816676) (xy 41.706546 -252.82144) (xy 41.679943 -252.830312)
			(xy 41.624902 -252.841047) (xy 41.568883 -252.843608) (xy 41.513092 -252.837938) (xy 41.458733 -252.824161)
			(xy 41.406977 -252.802573) (xy 41.35894 -252.773639) (xy 41.315657 -252.737983) (xy 41.278062 -252.696374)
			(xy 41.246964 -252.649709) (xy 41.223034 -252.598993) (xy 41.206788 -252.54532) (xy 41.198576 -252.489847)
			(xy 41.198574 -252.433769) (xy 41.206784 -252.378295) (xy 41.223028 -252.324622) (xy 41.246956 -252.273905)
			(xy 41.278052 -252.227238) (xy 41.315646 -252.185628) (xy 41.358927 -252.14997) (xy 41.406963 -252.121035)
			(xy 41.458718 -252.099444) (xy 41.513077 -252.085664) (xy 41.568867 -252.079993) (xy 41.624886 -252.082551)
			(xy 41.679928 -252.093284) (xy 41.706546 -252.102112) (xy 41.721556 -252.106937) (xy 41.752938 -252.109866)
			(xy 41.784078 -252.105004) (xy 41.813073 -252.092647) (xy 41.838148 -252.073551) (xy 41.848278 -252.061472)
			(xy 41.850818 -252.05817) (xy 41.863939 -252.040689) (xy 41.884614 -252.002183) (xy 41.898395 -251.960708)
			(xy 41.904876 -251.917486) (xy 41.903866 -251.873793) (xy 41.895394 -251.830916) (xy 41.879711 -251.790122)
			(xy 41.857278 -251.752613) (xy 41.828759 -251.719496) (xy 41.794993 -251.691747) (xy 41.756977 -251.670184)
			(xy 41.715832 -251.655445) (xy 41.672773 -251.647963) (xy 41.65092 -251.647452) (xy 36.56711 -251.647452)
			(xy 36.544814 -251.647908) (xy 36.500905 -251.655676) (xy 36.459027 -251.670993) (xy 36.420467 -251.693387)
			(xy 36.386411 -251.722171) (xy 36.357904 -251.756461) (xy 36.335824 -251.795201) (xy 36.320848 -251.837202)
			(xy 36.313437 -251.881173) (xy 36.313818 -251.925762) (xy 36.32198 -251.9696) (xy 36.337673 -252.011339)
			(xy 36.34867 -252.030738) (xy 36.37113 -252.069684) (xy 36.409361 -252.15106) (xy 36.439652 -252.235714)
			(xy 36.461726 -252.322871) (xy 36.475384 -252.411737) (xy 36.480499 -252.501501) (xy 36.477025 -252.591344)
			(xy 36.464994 -252.680445) (xy 36.444515 -252.767991) (xy 36.415776 -252.853184) (xy 36.379038 -252.935245)
			(xy 36.357306 -252.974602) (xy 36.346835 -252.994049) (xy 36.332037 -253.03566) (xy 36.324656 -253.079203)
			(xy 36.324915 -253.123366) (xy 36.332805 -253.166819) (xy 36.348089 -253.208254) (xy 36.370307 -253.246423)
			(xy 36.398789 -253.280175) (xy 36.432677 -253.308495) (xy 36.470952 -253.330529) (xy 36.51246 -253.345614)
			(xy 36.555951 -253.353296) (xy 36.578032 -253.353824) (xy 43.932602 -253.353824) (xy 44.222416 -253.06401)
			(xy 44.245149 -253.042008) (xy 44.295341 -253.003495) (xy 44.35013 -252.971862) (xy 44.40858 -252.947651)
			(xy 44.469689 -252.931277) (xy 44.532413 -252.923019) (xy 44.595679 -252.923019) (xy 44.658403 -252.931277)
			(xy 44.719512 -252.947651) (xy 44.777962 -252.971862) (xy 44.832751 -253.003495) (xy 44.882943 -253.042008)
			(xy 44.927678 -253.086743) (xy 44.966191 -253.136935) (xy 44.997824 -253.191724) (xy 45.022035 -253.250174)
			(xy 45.038409 -253.311283) (xy 45.046667 -253.374007) (xy 45.046667 -253.437273) (xy 45.038409 -253.499997)
			(xy 45.022035 -253.561106) (xy 44.997824 -253.619556) (xy 44.966191 -253.674345) (xy 44.927678 -253.724537)
			(xy 44.905676 -253.74727) (xy 44.332906 -254.32004) (xy 43.096688 -254.32004) (xy 43.074336 -254.320493)
			(xy 43.030316 -254.32828) (xy 42.988338 -254.343647) (xy 42.949694 -254.36612) (xy 42.915577 -254.395006)
			(xy 42.887039 -254.429415) (xy 42.86496 -254.468285) (xy 42.85002 -254.510418) (xy 42.842681 -254.554514)
			(xy 42.843168 -254.599215) (xy 42.851467 -254.643141) (xy 42.858944 -254.66421) (xy 42.872596 -254.698613)
			(xy 42.892767 -254.76983) (xy 42.90454 -254.842906) (xy 42.906696 -254.879856) (xy 42.907668 -254.912094)
			(xy 42.903851 -254.976482) (xy 42.899076 -255.00838) (xy 42.896019 -255.030173) (xy 42.89657 -255.074173)
			(xy 42.904692 -255.11742) (xy 42.920143 -255.158621) (xy 42.94246 -255.196544) (xy 42.970977 -255.230057)
			(xy 43.004841 -255.258155) (xy 43.043038 -255.28) (xy 43.084428 -255.294938) (xy 43.127773 -255.302523)
			(xy 43.149774 -255.30302) (xy 44.396152 -255.30302) (xy 44.968922 -255.87579) (xy 44.990924 -255.898523)
			(xy 45.029437 -255.948715) (xy 45.06107 -256.003504) (xy 45.085281 -256.061954) (xy 45.101655 -256.123063)
			(xy 45.109913 -256.185787) (xy 45.109913 -256.249053) (xy 45.101655 -256.311777) (xy 45.085281 -256.372886)
			(xy 45.06107 -256.431336) (xy 45.029437 -256.486125) (xy 44.990924 -256.536317) (xy 44.946189 -256.581052)
			(xy 44.895997 -256.619565) (xy 44.841208 -256.651198) (xy 44.782758 -256.675409) (xy 44.721649 -256.691783)
			(xy 44.658925 -256.700041) (xy 44.595659 -256.700041) (xy 44.532935 -256.691783) (xy 44.471826 -256.675409)
			(xy 44.413376 -256.651198) (xy 44.358587 -256.619565) (xy 44.308395 -256.581052) (xy 44.285662 -256.55905)
			(xy 43.995848 -256.269236) (xy 43.090846 -256.269236) (xy 43.068271 -256.269723) (xy 43.02383 -256.277697)
			(xy 42.981499 -256.293403) (xy 42.942611 -256.316345) (xy 42.908392 -256.345801) (xy 42.87992 -256.380843)
			(xy 42.858091 -256.420366) (xy 42.843594 -256.463126) (xy 42.836885 -256.507776) (xy 42.838175 -256.552908)
			(xy 42.847425 -256.597101) (xy 42.855388 -256.618232) (xy 42.86718 -256.646539) (xy 42.885904 -256.704935)
			(xy 42.89892 -256.764863) (xy 42.902886 -256.79527) (xy 42.906844 -256.833733) (xy 42.906516 -256.911056)
			(xy 42.896814 -256.987769) (xy 42.8879 -257.025394) (xy 42.882862 -257.047163) (xy 42.879613 -257.091725)
			(xy 42.884198 -257.136169) (xy 42.896475 -257.179129) (xy 42.916068 -257.219285) (xy 42.942373 -257.255401)
			(xy 42.974581 -257.286367) (xy 43.011704 -257.311231) (xy 43.052599 -257.329229) (xy 43.096008 -257.339807)
			(xy 43.118278 -257.341624) (xy 43.845988 -257.341624) (xy 43.863768 -257.359404) (xy 43.920918 -257.4163)
			(xy 44.160694 -257.656076) (xy 44.570142 -257.656076) (xy 44.601772 -257.656596) (xy 44.66449 -257.664858)
			(xy 44.725593 -257.681235) (xy 44.784036 -257.705447) (xy 44.838819 -257.737081) (xy 44.889005 -257.775593)
			(xy 44.933734 -257.820327) (xy 44.972243 -257.870516) (xy 45.003871 -257.925301) (xy 45.028078 -257.983747)
			(xy 45.04445 -258.044851) (xy 45.052707 -258.10757) (xy 45.052707 -258.17083) (xy 45.04445 -258.233549)
			(xy 45.028078 -258.294653) (xy 45.003871 -258.353099) (xy 44.972243 -258.407884) (xy 44.933734 -258.458073)
			(xy 44.889005 -258.502807) (xy 44.838819 -258.541319) (xy 44.784036 -258.572953) (xy 44.725593 -258.597165)
			(xy 44.66449 -258.613542) (xy 44.601772 -258.621804) (xy 44.570142 -258.622292) (xy 43.76039 -258.622292)
			(xy 43.482768 -258.34467) (xy 43.470639 -258.333274) (xy 43.441856 -258.316592) (xy 43.409739 -258.307915)
			(xy 43.393106 -258.307332) (xy 43.022012 -258.307332) (xy 42.998625 -258.309354) (xy 42.953122 -258.320865)
			(xy 42.910502 -258.340526) (xy 42.872211 -258.36767) (xy 42.839548 -258.401377) (xy 42.813622 -258.440502)
			(xy 42.795311 -258.48372) (xy 42.785237 -258.529562) (xy 42.783742 -258.576474) (xy 42.790877 -258.622865)
			(xy 42.806399 -258.66716) (xy 42.817542 -258.687824) (xy 42.835184 -258.718389) (xy 42.864349 -258.782656)
			(xy 42.886212 -258.849759) (xy 42.900505 -258.918872) (xy 42.907052 -258.989143) (xy 42.905771 -259.059706)
			(xy 42.896678 -259.129693) (xy 42.879886 -259.198241) (xy 42.855601 -259.264507) (xy 42.824123 -259.327673)
			(xy 42.785839 -259.386962) (xy 42.74122 -259.441643) (xy 42.690817 -259.491043) (xy 42.63525 -259.534553)
			(xy 42.575203 -259.571638) (xy 42.511417 -259.601841) (xy 42.444677 -259.624789) (xy 42.375805 -259.640199)
			(xy 42.30565 -259.647883) (xy 42.235075 -259.647746) (xy 42.16495 -259.639788) (xy 42.096138 -259.624109)
			(xy 42.029488 -259.600901) (xy 41.96582 -259.57045) (xy 41.905919 -259.533131) (xy 41.850522 -259.489405)
			(xy 41.800312 -259.439808) (xy 41.777666 -259.41274) (xy 41.767475 -259.400865) (xy 41.742475 -259.38206)
			(xy 41.713648 -259.369908) (xy 41.68273 -259.36514) (xy 41.651582 -259.368043) (xy 41.636696 -259.372862)
			(xy 41.609346 -259.38198) (xy 41.552725 -259.392817) (xy 41.495117 -259.395013) (xy 41.437835 -259.38852)
			(xy 41.409874 -259.381498) (xy 41.385043 -259.37432) (xy 41.337437 -259.354186) (xy 41.292982 -259.327812)
			(xy 41.252493 -259.295683) (xy 41.216708 -259.258385) (xy 41.186282 -259.216599) (xy 41.173654 -259.194046)
			(xy 41.16147 -259.170451) (xy 41.143022 -259.120657) (xy 41.13166 -259.068785) (xy 41.127602 -259.015839)
			(xy 41.130928 -258.962841) (xy 41.141572 -258.910817) (xy 41.15933 -258.860773) (xy 41.183858 -258.813675)
			(xy 41.214681 -258.770435) (xy 41.251204 -258.731888) (xy 41.271698 -258.715002) (xy 41.294607 -258.697398)
			(xy 41.344679 -258.668579) (xy 41.398523 -258.647638) (xy 41.454909 -258.635055) (xy 41.512548 -258.631117)
			(xy 41.570121 -258.635914) (xy 41.598342 -258.642104) (xy 41.615026 -258.645139) (xy 41.648874 -258.643277)
			(xy 41.681038 -258.632569) (xy 41.709248 -258.613772) (xy 41.731515 -258.588212) (xy 41.746268 -258.557691)
			(xy 41.752466 -258.524364) (xy 41.749671 -258.49058) (xy 41.744392 -258.474464) (xy 41.73682 -258.454784)
			(xy 41.716113 -258.418053) (xy 41.689632 -258.385241) (xy 41.658101 -258.357246) (xy 41.622384 -258.334835)
			(xy 41.583461 -258.318622) (xy 41.542396 -258.309051) (xy 41.52138 -258.307332) (xy 39.826438 -258.307332)
			(xy 38.775894 -259.357876) (xy 36.599876 -259.357876) (xy 36.577314 -259.359788) (xy 36.533343 -259.370583)
			(xy 36.49198 -259.388995) (xy 36.454531 -259.414441) (xy 36.422181 -259.446117) (xy 36.395952 -259.483021)
			(xy 36.376673 -259.523988) (xy 36.364955 -259.567721) (xy 36.361167 -259.612838) (xy 36.365429 -259.657913)
			(xy 36.377606 -259.70152) (xy 36.387024 -259.722112) (xy 36.405879 -259.762477) (xy 36.436763 -259.846051)
			(xy 36.459605 -259.93217) (xy 36.4742 -260.020064) (xy 36.479459 -260.095238) (xy 44.29582 -260.095238)
			(xy 44.299891 -260.039616) (xy 44.312017 -259.985179) (xy 44.33194 -259.933088) (xy 44.359236 -259.884453)
			(xy 44.393322 -259.84031) (xy 44.433471 -259.801601) (xy 44.478829 -259.76915) (xy 44.528429 -259.743649)
			(xy 44.581213 -259.725642) (xy 44.636056 -259.715512) (xy 44.69179 -259.713475) (xy 44.747227 -259.719575)
			(xy 44.801184 -259.733681) (xy 44.852513 -259.755493) (xy 44.900119 -259.784547) (xy 44.942987 -259.820222)
			(xy 44.980204 -259.861759) (xy 45.010977 -259.908272) (xy 45.034649 -259.958769) (xy 45.050717 -260.012176)
			(xy 45.058837 -260.067352) (xy 45.059346 -260.095238) (xy 45.058837 -260.123124) (xy 45.050717 -260.1783)
			(xy 45.034649 -260.231707) (xy 45.010977 -260.282204) (xy 44.980204 -260.328717) (xy 44.942987 -260.370254)
			(xy 44.900119 -260.405929) (xy 44.852513 -260.434983) (xy 44.801184 -260.456795) (xy 44.747227 -260.470901)
			(xy 44.69179 -260.477001) (xy 44.636056 -260.474964) (xy 44.581213 -260.464834) (xy 44.528429 -260.446827)
			(xy 44.478829 -260.421326) (xy 44.433471 -260.388875) (xy 44.393322 -260.350166) (xy 44.359236 -260.306023)
			(xy 44.33194 -260.257388) (xy 44.312017 -260.205297) (xy 44.299891 -260.15086) (xy 44.29582 -260.095238)
			(xy 36.479459 -260.095238) (xy 36.480418 -260.108944) (xy 36.478202 -260.198014) (xy 36.473384 -260.242304)
			(xy 36.469949 -260.269005) (xy 36.460419 -260.321997) (xy 36.454334 -260.348222) (xy 36.44497 -260.385946)
			(xy 36.42081 -260.459829) (xy 36.406074 -260.495796) (xy 36.390834 -260.529832) (xy 36.382417 -260.551005)
			(xy 36.372411 -260.59545) (xy 36.370489 -260.640967) (xy 36.376714 -260.686098) (xy 36.390885 -260.729395)
			(xy 36.412549 -260.769473) (xy 36.441011 -260.805045) (xy 36.475359 -260.834973) (xy 36.514493 -260.858298)
			(xy 36.557159 -260.874271) (xy 36.601989 -260.882382) (xy 36.624768 -260.882892) (xy 47.526956 -260.882892)
		)
		(stroke
			(width 0)
			(type solid)
		)
		(fill yes)
		(layer "In5.Cu")
		(net "GND")
	)
	(gr_poly
		(pts
			(xy 101.000052 -528.47494) (xy 101.031153 -528.474456) (xy 101.092824 -528.466343) (xy 101.152907 -528.450248)
			(xy 101.210376 -528.426447) (xy 101.264245 -528.395348) (xy 101.313594 -528.357483) (xy 101.357578 -528.3135)
			(xy 101.395444 -528.264152) (xy 101.426544 -528.210283) (xy 101.450345 -528.152815) (xy 101.466441 -528.092731)
			(xy 101.474556 -528.031061) (xy 101.475032 -527.99996) (xy 101.475032 -390.807702) (xy 101.474532 -390.78467)
			(xy 101.466228 -390.739361) (xy 101.449893 -390.696292) (xy 101.426061 -390.656872) (xy 101.395513 -390.622395)
			(xy 101.359251 -390.593989) (xy 101.318462 -390.572586) (xy 101.274483 -390.558886) (xy 101.228754 -390.553339)
			(xy 101.182775 -390.556126) (xy 101.138052 -390.567157) (xy 101.096049 -390.586069) (xy 101.058145 -390.612243)
			(xy 101.041454 -390.628124) (xy 93.804486 -397.865092) (xy 93.795342 -397.896588) (xy 93.786942 -397.924005)
			(xy 93.763063 -397.976137) (xy 93.731651 -398.024109) (xy 93.693414 -398.066839) (xy 93.649213 -398.103366)
			(xy 93.624908 -398.118584) (xy 92.359988 -399.383504) (xy 92.359988 -404.379684) (xy 92.360394 -404.394585)
			(xy 92.367309 -404.423574) (xy 92.380767 -404.450165) (xy 92.40003 -404.472904) (xy 92.411804 -404.482046)
			(xy 92.440898 -404.504047) (xy 92.494901 -404.553085) (xy 92.543608 -404.607388) (xy 92.586506 -404.666387)
			(xy 92.623146 -404.729464) (xy 92.653144 -404.795956) (xy 92.676185 -404.865167) (xy 92.692028 -404.936372)
			(xy 92.700507 -405.008824) (xy 92.701533 -405.081762) (xy 92.695095 -405.154424) (xy 92.681261 -405.226046)
			(xy 92.660176 -405.295878) (xy 92.63206 -405.363188) (xy 92.615004 -405.39543) (xy 92.596973 -405.427568)
			(xy 92.555234 -405.488303) (xy 92.507449 -405.544407) (xy 92.45413 -405.595279) (xy 92.425266 -405.618188)
			(xy 92.395459 -405.640629) (xy 92.331973 -405.679834) (xy 92.264735 -405.712184) (xy 92.194482 -405.737324)
			(xy 92.121986 -405.754978) (xy 92.04804 -405.764953) (xy 91.973457 -405.76714) (xy 91.899054 -405.761514)
			(xy 91.825648 -405.748137) (xy 91.754043 -405.727156) (xy 91.685025 -405.6988) (xy 91.619352 -405.663382)
			(xy 91.557743 -405.621289) (xy 91.500875 -405.572984) (xy 91.449371 -405.518995) (xy 91.403796 -405.459916)
			(xy 91.36465 -405.396394) (xy 91.332362 -405.329126) (xy 91.307287 -405.25885) (xy 91.298014 -405.22271)
			(xy 91.288108 -405.181816) (xy 91.246452 -405.147018) (xy 91.233869 -405.137084) (xy 91.204944 -405.12328)
			(xy 91.17349 -405.117122) (xy 91.141495 -405.118998) (xy 91.110977 -405.128789) (xy 91.083863 -405.145879)
			(xy 91.061864 -405.169187) (xy 91.046369 -405.197243) (xy 91.038356 -405.228275) (xy 91.037918 -405.2443)
			(xy 91.037664 -405.429212) (xy 91.037664 -405.614124) (xy 91.038138 -405.630218) (xy 91.0462 -405.661381)
			(xy 91.061805 -405.689534) (xy 91.083959 -405.712885) (xy 91.097354 -405.72182) (xy 91.128899 -405.742128)
			(xy 91.187962 -405.788394) (xy 91.24183 -405.840618) (xy 91.289903 -405.89822) (xy 91.33165 -405.96056)
			(xy 91.366606 -406.026946) (xy 91.394383 -406.096642) (xy 91.414673 -406.168873) (xy 91.427251 -406.242838)
			(xy 91.431977 -406.317716) (xy 91.428799 -406.392676) (xy 91.417751 -406.466885) (xy 91.398957 -406.53952)
			(xy 91.372625 -406.609774) (xy 91.339048 -406.676868) (xy 91.298597 -406.740057) (xy 91.251723 -406.798639)
			(xy 91.198946 -406.851965) (xy 91.140851 -406.899441) (xy 91.078083 -406.940542) (xy 91.01134 -406.97481)
			(xy 90.941361 -407.001866) (xy 90.868924 -407.021409) (xy 90.794833 -407.033223) (xy 90.71991 -407.037175)
			(xy 90.644987 -407.033223) (xy 90.570896 -407.021409) (xy 90.498459 -407.001866) (xy 90.42848 -406.97481)
			(xy 90.361737 -406.940542) (xy 90.298969 -406.899441) (xy 90.240874 -406.851965) (xy 90.188097 -406.798639)
			(xy 90.141223 -406.740057) (xy 90.100772 -406.676868) (xy 90.067195 -406.609774) (xy 90.040863 -406.53952)
			(xy 90.022069 -406.466885) (xy 90.011021 -406.392676) (xy 90.007843 -406.317716) (xy 90.012569 -406.242838)
			(xy 90.025147 -406.168873) (xy 90.045437 -406.096642) (xy 90.073214 -406.026946) (xy 90.10817 -405.96056)
			(xy 90.149917 -405.89822) (xy 90.19799 -405.840618) (xy 90.251858 -405.788394) (xy 90.310921 -405.742128)
			(xy 90.342466 -405.72182) (xy 90.35587 -405.712893) (xy 90.378039 -405.689545) (xy 90.393654 -405.66139)
			(xy 90.401722 -405.630222) (xy 90.402156 -405.614124) (xy 90.402156 -405.206962) (xy 90.401657 -405.190313)
			(xy 90.393028 -405.158151) (xy 90.37637 -405.129318) (xy 90.352816 -405.10578) (xy 90.323973 -405.08914)
			(xy 90.291806 -405.080533) (xy 90.275156 -405.079962) (xy 90.228928 -405.079962) (xy 90.15857 -405.138636)
			(xy 90.150188 -405.184102) (xy 90.14278 -405.221729) (xy 90.120938 -405.295244) (xy 90.091319 -405.365985)
			(xy 90.054267 -405.433132) (xy 90.010211 -405.495907) (xy 89.959662 -405.553582) (xy 89.903206 -405.605488)
			(xy 89.841497 -405.651025) (xy 89.77525 -405.689663) (xy 89.705233 -405.720956) (xy 89.632258 -405.74454)
			(xy 89.557171 -405.760143) (xy 89.480841 -405.767582) (xy 89.404154 -405.766774) (xy 89.327998 -405.757725)
			(xy 89.253256 -405.740542) (xy 89.180795 -405.715424) (xy 89.111454 -405.682661) (xy 89.046037 -405.642634)
			(xy 88.985302 -405.595806) (xy 88.929953 -405.54272) (xy 88.880632 -405.483992) (xy 88.83791 -405.420302)
			(xy 88.802283 -405.352388) (xy 88.774163 -405.281038) (xy 88.753876 -405.207078) (xy 88.741658 -405.131366)
			(xy 88.73765 -405.05478) (xy 88.739218 -405.016462) (xy 88.741718 -404.979461) (xy 88.753444 -404.906228)
			(xy 88.772722 -404.834612) (xy 88.799343 -404.765389) (xy 88.833018 -404.69931) (xy 88.873382 -404.63709)
			(xy 88.919997 -404.579406) (xy 88.972358 -404.526881) (xy 89.000838 -404.503128) (xy 89.030677 -404.47947)
			(xy 89.094525 -404.437967) (xy 89.162442 -404.403522) (xy 89.23365 -404.37653) (xy 89.307334 -404.357299)
			(xy 89.382651 -404.346049) (xy 89.458739 -404.34291) (xy 89.534726 -404.347916) (xy 89.609744 -404.361012)
			(xy 89.682934 -404.382046) (xy 89.718388 -404.39594) (xy 89.752925 -404.410534) (xy 89.819009 -404.445964)
			(xy 89.881012 -404.48813) (xy 89.938248 -404.53657) (xy 89.964514 -404.563326) (xy 89.980577 -404.579434)
			(xy 90.017328 -404.606234) (xy 90.058261 -404.626069) (xy 90.102069 -404.638306) (xy 90.147355 -404.642554)
			(xy 90.192675 -404.638677) (xy 90.236582 -404.626801) (xy 90.277676 -404.607302) (xy 90.314646 -404.580804)
			(xy 90.346312 -404.548152) (xy 90.371664 -404.510387) (xy 90.389893 -404.468714) (xy 90.400417 -404.424463)
			(xy 90.402156 -404.401782) (xy 90.402156 -399.940526) (xy 90.400449 -399.918418) (xy 90.390355 -399.875244)
			(xy 90.372929 -399.834475) (xy 90.348697 -399.797345) (xy 90.318394 -399.764979) (xy 90.282938 -399.738358)
			(xy 90.243403 -399.718288) (xy 90.200986 -399.705377) (xy 90.156974 -399.700016) (xy 90.112699 -399.702369)
			(xy 90.069502 -399.712363) (xy 90.028693 -399.729695) (xy 89.991507 -399.753841) (xy 89.974928 -399.768568)
			(xy 87.227918 -402.515578) (xy 87.227664 -403.45614) (xy 87.227664 -404.344124) (xy 87.228138 -404.360218)
			(xy 87.2362 -404.391381) (xy 87.251805 -404.419534) (xy 87.273959 -404.442885) (xy 87.287354 -404.45182)
			(xy 87.319626 -404.472624) (xy 87.379952 -404.520133) (xy 87.434813 -404.573858) (xy 87.483573 -404.633177)
			(xy 87.525665 -404.697399) (xy 87.560599 -404.765779) (xy 87.58797 -404.837522) (xy 87.60746 -404.911795)
			(xy 87.618842 -404.987733) (xy 87.621984 -405.064456) (xy 87.616849 -405.141071) (xy 87.603498 -405.216688)
			(xy 87.582085 -405.290429) (xy 87.552859 -405.361436) (xy 87.535004 -405.39543) (xy 87.516973 -405.427568)
			(xy 87.475234 -405.488303) (xy 87.427449 -405.544407) (xy 87.37413 -405.595279) (xy 87.345266 -405.618188)
			(xy 87.315459 -405.640629) (xy 87.251973 -405.679834) (xy 87.184735 -405.712184) (xy 87.114482 -405.737324)
			(xy 87.041986 -405.754978) (xy 86.96804 -405.764953) (xy 86.893457 -405.76714) (xy 86.819054 -405.761514)
			(xy 86.745648 -405.748137) (xy 86.674043 -405.727156) (xy 86.605025 -405.6988) (xy 86.539352 -405.663382)
			(xy 86.477743 -405.621289) (xy 86.420875 -405.572984) (xy 86.369371 -405.518995) (xy 86.323796 -405.459916)
			(xy 86.28465 -405.396394) (xy 86.252362 -405.329126) (xy 86.227287 -405.25885) (xy 86.218014 -405.22271)
			(xy 86.208108 -405.181816) (xy 86.166198 -405.146764) (xy 86.153603 -405.136833) (xy 86.124653 -405.123043)
			(xy 86.09318 -405.116908) (xy 86.061171 -405.118814) (xy 86.030648 -405.128642) (xy 86.003541 -405.14577)
			(xy 85.98156 -405.169117) (xy 85.966096 -405.197208) (xy 85.958125 -405.228267) (xy 85.957664 -405.2443)
			(xy 85.957664 -405.614124) (xy 85.958138 -405.630218) (xy 85.9662 -405.661381) (xy 85.981805 -405.689534)
			(xy 86.003959 -405.712885) (xy 86.017354 -405.72182) (xy 86.048839 -405.742085) (xy 86.107797 -405.788248)
			(xy 86.161581 -405.840346) (xy 86.209598 -405.897804) (xy 86.251316 -405.959986) (xy 86.286274 -406.026205)
			(xy 86.314086 -406.095729) (xy 86.334443 -406.167788) (xy 86.347122 -406.241587) (xy 86.351981 -406.316309)
			(xy 86.351628 -406.32507) (xy 87.467697 -406.32507) (xy 87.471732 -406.249366) (xy 87.483791 -406.174521)
			(xy 87.503737 -406.10138) (xy 87.531344 -406.030775) (xy 87.5663 -405.963504) (xy 87.608208 -405.900329)
			(xy 87.656594 -405.841967) (xy 87.71091 -405.789079) (xy 87.770539 -405.742264) (xy 87.834807 -405.702052)
			(xy 87.902984 -405.6689) (xy 87.9743 -405.643182) (xy 88.047945 -405.62519) (xy 88.123085 -405.615128)
			(xy 88.198869 -405.613109) (xy 88.274439 -405.619158) (xy 88.348937 -405.633205) (xy 88.42152 -405.655091)
			(xy 88.491366 -405.684568) (xy 88.557683 -405.721303) (xy 88.619719 -405.764878) (xy 88.676772 -405.8148)
			(xy 88.728196 -405.870504) (xy 88.773407 -405.931359) (xy 88.811894 -405.996674) (xy 88.84322 -406.06571)
			(xy 88.86703 -406.137685) (xy 88.883055 -406.211783) (xy 88.891114 -406.287164) (xy 88.891618 -406.32507)
			(xy 88.891114 -406.362976) (xy 88.883055 -406.438357) (xy 88.86703 -406.512455) (xy 88.84322 -406.58443)
			(xy 88.811894 -406.653466) (xy 88.773407 -406.718781) (xy 88.728196 -406.779636) (xy 88.676772 -406.83534)
			(xy 88.619719 -406.885262) (xy 88.557683 -406.928837) (xy 88.491366 -406.965572) (xy 88.42152 -406.995049)
			(xy 88.348937 -407.016935) (xy 88.274439 -407.030982) (xy 88.198869 -407.037031) (xy 88.123085 -407.035012)
			(xy 88.047945 -407.02495) (xy 87.9743 -407.006958) (xy 87.902984 -406.98124) (xy 87.834807 -406.948088)
			(xy 87.770539 -406.907876) (xy 87.71091 -406.861061) (xy 87.656594 -406.808173) (xy 87.608208 -406.749811)
			(xy 87.5663 -406.686636) (xy 87.531344 -406.619365) (xy 87.503737 -406.54876) (xy 87.483791 -406.475619)
			(xy 87.471732 -406.400774) (xy 87.467697 -406.32507) (xy 86.351628 -406.32507) (xy 86.348968 -406.391129)
			(xy 86.338115 -406.465218) (xy 86.329266 -406.5016) (xy 86.3205 -406.53431) (xy 86.297601 -406.598044)
			(xy 86.283546 -406.628854) (xy 86.265328 -406.666042) (xy 86.221528 -406.736324) (xy 86.19617 -406.769062)
			(xy 86.171665 -406.798938) (xy 86.117192 -406.853747) (xy 86.057103 -406.902334) (xy 85.992107 -406.944128)
			(xy 85.922966 -406.978638) (xy 85.850495 -407.005458) (xy 85.775546 -407.024272) (xy 85.699001 -407.034858)
			(xy 85.621759 -407.037094) (xy 85.544729 -407.030951) (xy 85.468817 -407.016503) (xy 85.394917 -406.993919)
			(xy 85.323896 -406.963465) (xy 85.256592 -406.925499) (xy 85.224874 -406.903428) (xy 85.206175 -406.890592)
			(xy 85.165246 -406.871062) (xy 85.121501 -406.859103) (xy 85.076329 -406.855094) (xy 85.031161 -406.859163)
			(xy 84.987433 -406.871181) (xy 84.94653 -406.890766) (xy 84.90975 -406.917298) (xy 84.878261 -406.949933)
			(xy 84.853061 -406.987637) (xy 84.83495 -407.029214) (xy 84.824503 -407.073344) (xy 84.822792 -407.09596)
			(xy 84.822792 -407.59507) (xy 86.197697 -407.59507) (xy 86.201732 -407.519366) (xy 86.213791 -407.444521)
			(xy 86.233737 -407.37138) (xy 86.261344 -407.300775) (xy 86.2963 -407.233504) (xy 86.338208 -407.170329)
			(xy 86.386594 -407.111967) (xy 86.44091 -407.059079) (xy 86.500539 -407.012264) (xy 86.564807 -406.972052)
			(xy 86.632984 -406.9389) (xy 86.7043 -406.913182) (xy 86.777945 -406.89519) (xy 86.853085 -406.885128)
			(xy 86.928869 -406.883109) (xy 87.004439 -406.889158) (xy 87.078937 -406.903205) (xy 87.15152 -406.925091)
			(xy 87.221366 -406.954568) (xy 87.287683 -406.991303) (xy 87.349719 -407.034878) (xy 87.406772 -407.0848)
			(xy 87.458196 -407.140504) (xy 87.503407 -407.201359) (xy 87.541894 -407.266674) (xy 87.57322 -407.33571)
			(xy 87.59703 -407.407685) (xy 87.613055 -407.481783) (xy 87.621114 -407.557164) (xy 87.621618 -407.59507)
			(xy 88.737697 -407.59507) (xy 88.741732 -407.519366) (xy 88.753791 -407.444521) (xy 88.773737 -407.37138)
			(xy 88.801344 -407.300775) (xy 88.8363 -407.233504) (xy 88.878208 -407.170329) (xy 88.926594 -407.111967)
			(xy 88.98091 -407.059079) (xy 89.040539 -407.012264) (xy 89.104807 -406.972052) (xy 89.172984 -406.9389)
			(xy 89.2443 -406.913182) (xy 89.317945 -406.89519) (xy 89.393085 -406.885128) (xy 89.468869 -406.883109)
			(xy 89.544439 -406.889158) (xy 89.618937 -406.903205) (xy 89.69152 -406.925091) (xy 89.761366 -406.954568)
			(xy 89.827683 -406.991303) (xy 89.889719 -407.034878) (xy 89.946772 -407.0848) (xy 89.998196 -407.140504)
			(xy 90.043407 -407.201359) (xy 90.081894 -407.266674) (xy 90.11322 -407.33571) (xy 90.13703 -407.407685)
			(xy 90.153055 -407.481783) (xy 90.161114 -407.557164) (xy 90.161618 -407.59507) (xy 90.161114 -407.632976)
			(xy 90.153055 -407.708357) (xy 90.13703 -407.782455) (xy 90.11322 -407.85443) (xy 90.081894 -407.923466)
			(xy 90.043407 -407.988781) (xy 89.998196 -408.049636) (xy 89.946772 -408.10534) (xy 89.889719 -408.155262)
			(xy 89.827683 -408.198837) (xy 89.761366 -408.235572) (xy 89.69152 -408.265049) (xy 89.618937 -408.286935)
			(xy 89.544439 -408.300982) (xy 89.468869 -408.307031) (xy 89.393085 -408.305012) (xy 89.317945 -408.29495)
			(xy 89.2443 -408.276958) (xy 89.172984 -408.25124) (xy 89.104807 -408.218088) (xy 89.040539 -408.177876)
			(xy 88.98091 -408.131061) (xy 88.926594 -408.078173) (xy 88.878208 -408.019811) (xy 88.8363 -407.956636)
			(xy 88.801344 -407.889365) (xy 88.773737 -407.81876) (xy 88.753791 -407.745619) (xy 88.741732 -407.670774)
			(xy 88.737697 -407.59507) (xy 87.621618 -407.59507) (xy 87.621114 -407.632976) (xy 87.613055 -407.708357)
			(xy 87.59703 -407.782455) (xy 87.57322 -407.85443) (xy 87.541894 -407.923466) (xy 87.503407 -407.988781)
			(xy 87.458196 -408.049636) (xy 87.406772 -408.10534) (xy 87.349719 -408.155262) (xy 87.287683 -408.198837)
			(xy 87.221366 -408.235572) (xy 87.15152 -408.265049) (xy 87.078937 -408.286935) (xy 87.004439 -408.300982)
			(xy 86.928869 -408.307031) (xy 86.853085 -408.305012) (xy 86.777945 -408.29495) (xy 86.7043 -408.276958)
			(xy 86.632984 -408.25124) (xy 86.564807 -408.218088) (xy 86.500539 -408.177876) (xy 86.44091 -408.131061)
			(xy 86.386594 -408.078173) (xy 86.338208 -408.019811) (xy 86.2963 -407.956636) (xy 86.261344 -407.889365)
			(xy 86.233737 -407.81876) (xy 86.213791 -407.745619) (xy 86.201732 -407.670774) (xy 86.197697 -407.59507)
			(xy 84.822792 -407.59507) (xy 84.822792 -408.09418) (xy 84.824511 -408.116798) (xy 84.83495 -408.160935)
			(xy 84.853056 -408.20252) (xy 84.878253 -408.240232) (xy 84.909742 -408.272874) (xy 84.946524 -408.299411)
			(xy 84.98743 -408.319001) (xy 85.031164 -408.331021) (xy 85.076336 -408.33509) (xy 85.121513 -408.331079)
			(xy 85.165262 -408.319115) (xy 85.206194 -408.299579) (xy 85.224874 -408.286712) (xy 85.256502 -408.264633)
			(xy 85.323666 -408.226697) (xy 85.394539 -408.196245) (xy 85.468288 -408.173636) (xy 85.54405 -408.159133)
			(xy 85.620936 -408.152908) (xy 85.698044 -408.155032) (xy 85.774471 -408.165482) (xy 85.849319 -408.184134)
			(xy 85.921712 -408.21077) (xy 85.990801 -408.245078) (xy 86.055774 -408.286655) (xy 86.115871 -408.335013)
			(xy 86.170387 -408.389586) (xy 86.218682 -408.449734) (xy 86.260191 -408.514751) (xy 86.294426 -408.583876)
			(xy 86.320986 -408.656296) (xy 86.339559 -408.731164) (xy 86.345268 -408.769312) (xy 86.349632 -408.804675)
			(xy 86.352118 -408.875889) (xy 86.347476 -408.946996) (xy 86.335753 -409.017282) (xy 86.317066 -409.086046)
			(xy 86.291602 -409.152599) (xy 86.259616 -409.216274) (xy 86.240874 -409.246578) (xy 86.230125 -409.265498)
			(xy 86.214552 -409.306128) (xy 86.206125 -409.348817) (xy 86.20509 -409.392316) (xy 86.211477 -409.435357)
			(xy 86.2251 -409.476682) (xy 86.245561 -409.515083) (xy 86.272262 -409.549439) (xy 86.304424 -409.578747)
			(xy 86.341106 -409.60215) (xy 86.381238 -409.618965) (xy 86.423647 -409.628701) (xy 86.445344 -409.630372)
			(xy 87.374476 -409.630372) (xy 87.39617 -409.628724) (xy 87.438564 -409.61896) (xy 87.478678 -409.602125)
			(xy 87.515343 -409.57871) (xy 87.547489 -409.549398) (xy 87.57418 -409.515044) (xy 87.594636 -409.47665)
			(xy 87.60826 -409.435335) (xy 87.614657 -409.392304) (xy 87.613638 -409.348812) (xy 87.605235 -409.306128)
			(xy 87.589691 -409.265496) (xy 87.578946 -409.246578) (xy 87.558981 -409.214207) (xy 87.525295 -409.146015)
			(xy 87.499073 -409.074619) (xy 87.480612 -409.000835) (xy 87.470123 -408.925503) (xy 87.467725 -408.849482)
			(xy 87.473447 -408.773639) (xy 87.487222 -408.698838) (xy 87.508893 -408.625932) (xy 87.538215 -408.555752)
			(xy 87.574851 -408.489099) (xy 87.618386 -408.426731) (xy 87.668321 -408.369361) (xy 87.724089 -408.317642)
			(xy 87.785053 -408.272163) (xy 87.850519 -408.233444) (xy 87.919739 -408.201925) (xy 87.991926 -408.177966)
			(xy 88.066255 -408.16184) (xy 88.141881 -408.15373) (xy 88.217939 -408.15373) (xy 88.293565 -408.16184)
			(xy 88.367894 -408.177966) (xy 88.440081 -408.201925) (xy 88.509301 -408.233444) (xy 88.574767 -408.272163)
			(xy 88.635731 -408.317642) (xy 88.691499 -408.369361) (xy 88.741434 -408.426731) (xy 88.784969 -408.489099)
			(xy 88.821605 -408.555752) (xy 88.850927 -408.625932) (xy 88.872598 -408.698838) (xy 88.886373 -408.773639)
			(xy 88.892095 -408.849482) (xy 88.889697 -408.925503) (xy 88.879208 -409.000835) (xy 88.860747 -409.074619)
			(xy 88.834525 -409.146015) (xy 88.800839 -409.214207) (xy 88.780874 -409.246578) (xy 88.770125 -409.265498)
			(xy 88.754552 -409.306128) (xy 88.746125 -409.348817) (xy 88.74509 -409.392316) (xy 88.751477 -409.435357)
			(xy 88.7651 -409.476682) (xy 88.785561 -409.515083) (xy 88.812262 -409.549439) (xy 88.844424 -409.578747)
			(xy 88.881106 -409.60215) (xy 88.921238 -409.618965) (xy 88.963647 -409.628701) (xy 88.985344 -409.630372)
			(xy 89.452704 -409.630372) (xy 89.469346 -409.629851) (xy 89.501484 -409.621181) (xy 89.530281 -409.604487)
			(xy 89.542366 -409.593034) (xy 89.889584 -409.245816) (xy 89.991692 -409.143708) (xy 90.001592 -409.13324)
			(xy 90.016828 -409.108794) (xy 90.02617 -409.081546) (xy 90.029138 -409.052894) (xy 90.02776 -409.038552)
			(xy 90.026236 -409.02509) (xy 90.024712 -409.01874) (xy 90.017031 -408.981694) (xy 90.008619 -408.906502)
			(xy 90.008229 -408.830841) (xy 90.015864 -408.755566) (xy 90.031438 -408.681525) (xy 90.054776 -408.609553)
			(xy 90.085615 -408.540462) (xy 90.123606 -408.475031) (xy 90.168322 -408.413997) (xy 90.219258 -408.358049)
			(xy 90.275839 -408.307818) (xy 90.337428 -408.26387) (xy 90.40333 -408.226701) (xy 90.472802 -408.19673)
			(xy 90.545061 -408.174295) (xy 90.619291 -408.159649) (xy 90.694656 -408.152957) (xy 90.770305 -408.154295)
			(xy 90.845386 -408.163647) (xy 90.919052 -408.180909) (xy 90.990472 -408.205885) (xy 91.058841 -408.238293)
			(xy 91.123388 -408.277769) (xy 91.183385 -408.323867) (xy 91.238155 -408.376068) (xy 91.28708 -408.433782)
			(xy 91.32961 -408.496359) (xy 91.365264 -408.563093) (xy 91.39364 -408.633231) (xy 91.40444 -408.66949)
			(xy 91.40444 -408.669998) (xy 91.409493 -408.685718) (xy 91.426429 -408.71405) (xy 91.45007 -408.737085)
			(xy 91.478831 -408.753282) (xy 91.510785 -408.761554) (xy 91.543793 -408.761348) (xy 91.575641 -408.752678)
			(xy 91.604198 -408.736124) (xy 91.616276 -408.724862) (xy 91.672156 -408.668982) (xy 91.672156 -408.306016)
			(xy 91.671686 -408.289921) (xy 91.663628 -408.258756) (xy 91.648022 -408.230602) (xy 91.625862 -408.207254)
			(xy 91.612466 -408.19832) (xy 91.580921 -408.178012) (xy 91.521858 -408.131746) (xy 91.46799 -408.079522)
			(xy 91.419917 -408.02192) (xy 91.37817 -407.95958) (xy 91.343214 -407.893194) (xy 91.315437 -407.823498)
			(xy 91.295147 -407.751267) (xy 91.282569 -407.677302) (xy 91.277843 -407.602424) (xy 91.281021 -407.527464)
			(xy 91.292069 -407.453255) (xy 91.310863 -407.38062) (xy 91.337195 -407.310366) (xy 91.370772 -407.243272)
			(xy 91.411223 -407.180083) (xy 91.458097 -407.121501) (xy 91.510874 -407.068175) (xy 91.568969 -407.020699)
			(xy 91.631737 -406.979598) (xy 91.69848 -406.94533) (xy 91.768459 -406.918274) (xy 91.840896 -406.898731)
			(xy 91.914987 -406.886917) (xy 91.98991 -406.882965) (xy 92.064833 -406.886917) (xy 92.138924 -406.898731)
			(xy 92.211361 -406.918274) (xy 92.28134 -406.94533) (xy 92.348083 -406.979598) (xy 92.410851 -407.020699)
			(xy 92.468946 -407.068175) (xy 92.521723 -407.121501) (xy 92.568597 -407.180083) (xy 92.609048 -407.243272)
			(xy 92.642625 -407.310366) (xy 92.668957 -407.38062) (xy 92.687751 -407.453255) (xy 92.698799 -407.527464)
			(xy 92.701977 -407.602424) (xy 92.697251 -407.677302) (xy 92.684673 -407.751267) (xy 92.664383 -407.823498)
			(xy 92.636606 -407.893194) (xy 92.60165 -407.95958) (xy 92.559903 -408.02192) (xy 92.51183 -408.079522)
			(xy 92.457962 -408.131746) (xy 92.398899 -408.178012) (xy 92.367354 -408.19832) (xy 92.35396 -408.207253)
			(xy 92.331812 -408.230607) (xy 92.316216 -408.258761) (xy 92.308163 -408.289923) (xy 92.307664 -408.306016)
			(xy 92.307664 -408.31008) (xy 93.154506 -408.31008) (xy 93.158522 -408.19381) (xy 93.170549 -408.078095)
			(xy 93.190531 -407.963485) (xy 93.218373 -407.850526) (xy 93.253942 -407.739758) (xy 93.297068 -407.631707)
			(xy 93.347545 -407.526889) (xy 93.405134 -407.425804) (xy 93.46956 -407.328932) (xy 93.540515 -407.236736)
			(xy 93.617662 -407.149655) (xy 93.700633 -407.068104) (xy 93.789033 -406.992472) (xy 93.88244 -406.923118)
			(xy 93.980409 -406.860375) (xy 94.082473 -406.804539) (xy 94.188147 -406.755878) (xy 94.296926 -406.714624)
			(xy 94.408291 -406.680973) (xy 94.521714 -406.655085) (xy 94.636651 -406.637084) (xy 94.752557 -406.627055)
			(xy 94.868879 -406.625047) (xy 94.985062 -406.631069) (xy 95.100553 -406.645092) (xy 95.214801 -406.66705)
			(xy 95.327262 -406.696837) (xy 95.4374 -406.734312) (xy 95.54469 -406.779297) (xy 95.648621 -406.831576)
			(xy 95.748697 -406.890901) (xy 95.844443 -406.956989) (xy 95.9354 -407.029525) (xy 96.021136 -407.108164)
			(xy 96.101243 -407.19253) (xy 96.175339 -407.282222) (xy 96.243069 -407.376812) (xy 96.304113 -407.47585)
			(xy 96.358178 -407.578863) (xy 96.405008 -407.68536) (xy 96.444379 -407.794835) (xy 96.476103 -407.906765)
			(xy 96.500029 -408.020617) (xy 96.516043 -408.135849) (xy 96.52407 -408.251911) (xy 96.524572 -408.31008)
			(xy 96.52407 -408.368249) (xy 96.516043 -408.484311) (xy 96.500029 -408.599543) (xy 96.476103 -408.713395)
			(xy 96.444379 -408.825325) (xy 96.405008 -408.9348) (xy 96.358178 -409.041297) (xy 96.304113 -409.14431)
			(xy 96.243069 -409.243348) (xy 96.175339 -409.337938) (xy 96.101243 -409.42763) (xy 96.021136 -409.511996)
			(xy 95.9354 -409.590635) (xy 95.844443 -409.663171) (xy 95.748697 -409.729259) (xy 95.648621 -409.788584)
			(xy 95.54469 -409.840863) (xy 95.4374 -409.885848) (xy 95.327262 -409.923323) (xy 95.214801 -409.95311)
			(xy 95.100553 -409.975068) (xy 94.985062 -409.989091) (xy 94.868879 -409.995113) (xy 94.752557 -409.993105)
			(xy 94.636651 -409.983076) (xy 94.521714 -409.965075) (xy 94.408291 -409.939187) (xy 94.296926 -409.905536)
			(xy 94.188147 -409.864282) (xy 94.082473 -409.815621) (xy 93.980409 -409.759785) (xy 93.88244 -409.697042)
			(xy 93.789033 -409.627688) (xy 93.700633 -409.552056) (xy 93.617662 -409.470505) (xy 93.540515 -409.383424)
			(xy 93.46956 -409.291228) (xy 93.405134 -409.194356) (xy 93.347545 -409.093271) (xy 93.297068 -408.988453)
			(xy 93.253942 -408.880402) (xy 93.218373 -408.769634) (xy 93.190531 -408.656675) (xy 93.170549 -408.542065)
			(xy 93.158522 -408.42635) (xy 93.154506 -408.31008) (xy 92.307664 -408.31008) (xy 92.307664 -408.93238)
			(xy 90.950796 -410.289502) (xy 90.371422 -410.868876) (xy 84.915756 -410.868876) (xy 83.584288 -409.537408)
			(xy 83.584288 -402.49856) (xy 86.848188 -399.23466) (xy 86.857332 -399.203164) (xy 86.865729 -399.175744)
			(xy 86.889602 -399.123606) (xy 86.921009 -399.075627) (xy 86.959242 -399.032889) (xy 87.00344 -398.996354)
			(xy 87.027766 -398.981168) (xy 98.70948 -387.299454) (xy 98.70948 -358.739948) (xy 94.717616 -354.748084)
			(xy 87.973154 -354.748084) (xy 87.972786 -354.773147) (xy 87.980736 -354.822629) (xy 87.998226 -354.869596)
			(xy 88.024577 -354.912226) (xy 88.041226 -354.930964) (xy 89.160858 -356.050596) (xy 89.190576 -356.059994)
			(xy 89.215317 -356.068282) (xy 89.262444 -356.090678) (xy 89.306079 -356.119287) (xy 89.345409 -356.153575)
			(xy 89.379699 -356.192903) (xy 89.408311 -356.236536) (xy 89.430709 -356.283662) (xy 89.438988 -356.308406)
			(xy 89.448386 -356.338124) (xy 93.208348 -360.098086) (xy 93.208348 -362.4961) (xy 93.20887 -362.519168)
			(xy 93.217235 -362.564539) (xy 93.233654 -362.607655) (xy 93.257587 -362.647098) (xy 93.288248 -362.681572)
			(xy 93.324628 -362.709944) (xy 93.365534 -362.731282) (xy 93.409619 -362.744884) (xy 93.455436 -362.750303)
			(xy 93.501478 -362.747362) (xy 93.546233 -362.736157) (xy 93.588229 -362.717056) (xy 93.626087 -362.690687)
			(xy 93.642688 -362.674662) (xy 93.684494 -362.633158) (xy 93.773035 -362.555437) (xy 93.86679 -362.484091)
			(xy 93.965301 -362.419471) (xy 94.068086 -362.361891) (xy 94.174643 -362.311633) (xy 94.284451 -362.268944)
			(xy 94.396974 -362.23403) (xy 94.51166 -362.207064) (xy 94.627951 -362.188177) (xy 94.745277 -362.177461)
			(xy 94.863065 -362.174968) (xy 94.980739 -362.180712) (xy 95.097724 -362.194663) (xy 95.213449 -362.216753)
			(xy 95.327347 -362.246876) (xy 95.438863 -362.284882) (xy 95.54745 -362.330587) (xy 95.652579 -362.383767)
			(xy 95.753735 -362.444163) (xy 95.850425 -362.511478) (xy 95.942174 -362.585385) (xy 96.028536 -362.665521)
			(xy 96.109088 -362.751496) (xy 96.183436 -362.842889) (xy 96.251216 -362.939252) (xy 96.312099 -363.040116)
			(xy 96.365785 -363.144988) (xy 96.412013 -363.253354) (xy 96.450556 -363.364685) (xy 96.466406 -363.421422)
			(xy 96.480989 -363.477378) (xy 96.503373 -363.590837) (xy 96.517923 -363.705564) (xy 96.52457 -363.821019)
			(xy 96.523283 -363.936658) (xy 96.514069 -364.051937) (xy 96.49697 -364.166312) (xy 96.472067 -364.279245)
			(xy 96.439477 -364.390204) (xy 96.399354 -364.498667) (xy 96.351887 -364.604122) (xy 96.2973 -364.706074)
			(xy 96.235848 -364.804042) (xy 96.167822 -364.897565) (xy 96.093543 -364.986202) (xy 96.013359 -365.069536)
			(xy 95.927649 -365.147175) (xy 95.836816 -365.218753) (xy 95.741287 -365.283932) (xy 95.641514 -365.342406)
			(xy 95.537965 -365.3939) (xy 95.431128 -365.438171) (xy 95.321506 -365.475011) (xy 95.209616 -365.504245)
			(xy 95.095985 -365.525737) (xy 94.981147 -365.539385) (xy 94.865643 -365.545125) (xy 94.750018 -365.54293)
			(xy 94.634816 -365.53281) (xy 94.520578 -365.514813) (xy 94.407845 -365.489023) (xy 94.352364 -365.472726)
			(xy 94.297489 -365.455629) (xy 94.18998 -365.414946) (xy 94.085495 -365.367029) (xy 93.984519 -365.312101)
			(xy 93.887522 -365.250416) (xy 93.794957 -365.182263) (xy 93.707253 -365.107958) (xy 93.624818 -365.027847)
			(xy 93.548037 -364.942302) (xy 93.477266 -364.851722) (xy 93.412835 -364.756528) (xy 93.355043 -364.657163)
			(xy 93.30416 -364.554089) (xy 93.260421 -364.447787) (xy 93.224032 -364.33875) (xy 93.20911 -364.283244)
			(xy 93.202211 -364.262587) (xy 93.182373 -364.223819) (xy 93.15622 -364.188999) (xy 93.124517 -364.159143)
			(xy 93.088191 -364.135124) (xy 93.048304 -364.117645) (xy 93.006022 -364.107217) (xy 92.962582 -364.104145)
			(xy 92.919254 -364.108518) (xy 92.877304 -364.120209) (xy 92.837959 -364.138875) (xy 92.80237 -364.163972)
			(xy 92.786708 -364.179104) (xy 92.276422 -364.68939) (xy 91.08059 -365.884968) (xy 86.660482 -365.884968)
			(xy 85.927946 -365.152686) (xy 85.918802 -365.143542) (xy 85.897974 -365.122714) (xy 85.842856 -365.10341)
			(xy 85.79993 -365.108744) (xy 85.79358 -365.110268) (xy 85.756523 -365.11796) (xy 85.681308 -365.126389)
			(xy 85.605623 -365.12679) (xy 85.530322 -365.119157) (xy 85.456257 -365.103579) (xy 85.384262 -365.080229)
			(xy 85.315152 -365.049372) (xy 85.249706 -365.011356) (xy 85.188662 -364.966611) (xy 85.132712 -364.915641)
			(xy 85.082485 -364.859023) (xy 85.038549 -364.797394) (xy 85.0014 -364.731452) (xy 84.971458 -364.66194)
			(xy 84.949061 -364.589644) (xy 84.93446 -364.515379) (xy 84.927823 -364.439985) (xy 84.929222 -364.364311)
			(xy 84.938643 -364.289214) (xy 84.955979 -364.21554) (xy 84.981034 -364.144121) (xy 85.013526 -364.075764)
			(xy 85.053087 -364.01124) (xy 85.099272 -363.951278) (xy 85.151558 -363.896556) (xy 85.209355 -363.847689)
			(xy 85.272011 -363.805232) (xy 85.305138 -363.786928) (xy 85.32394 -363.776384) (xy 85.358004 -363.749971)
			(xy 85.387122 -363.718187) (xy 85.410457 -363.681945) (xy 85.42734 -363.642284) (xy 85.437287 -363.600343)
			(xy 85.440013 -363.557325) (xy 85.435439 -363.514464) (xy 85.423697 -363.472989) (xy 85.405123 -363.434092)
			(xy 85.38025 -363.398887) (xy 85.365336 -363.383322) (xy 84.20608 -362.224066) (xy 84.20608 -361.447842)
			(xy 80.308958 -357.55072) (xy 45.871384 -357.55072) (xy 44.349416 -359.072688) (xy 39.523416 -359.072688)
			(xy 39.044372 -358.593644) (xy 37.947854 -357.496872) (xy 37.935706 -357.48552) (xy 37.906911 -357.468925)
			(xy 37.874809 -357.460324) (xy 37.858192 -357.459788) (xy 36.621212 -357.459788) (xy 36.599275 -357.461447)
			(xy 36.556415 -357.471356) (xy 36.5159 -357.488494) (xy 36.478939 -357.512348) (xy 36.446634 -357.542206)
			(xy 36.419949 -357.577179) (xy 36.399681 -357.616222) (xy 36.386434 -357.65817) (xy 36.380603 -357.701772)
			(xy 36.382363 -357.745727) (xy 36.39166 -357.788724) (xy 36.39947 -357.809292) (xy 36.416628 -357.849241)
			(xy 36.444345 -357.931655) (xy 36.464335 -358.016275) (xy 36.476428 -358.10238) (xy 36.48052 -358.189234)
			(xy 36.476576 -358.276094) (xy 36.464631 -358.362219) (xy 36.444785 -358.446874) (xy 36.417209 -358.529335)
			(xy 36.382138 -358.608898) (xy 36.339872 -358.684884) (xy 36.290772 -358.756643) (xy 36.235256 -358.823563)
			(xy 36.1738 -358.885072) (xy 36.106927 -358.940645) (xy 36.03521 -358.989807) (xy 35.95926 -359.032138)
			(xy 35.879727 -359.067277) (xy 35.79729 -359.094923) (xy 35.712652 -359.114841) (xy 35.626537 -359.12686)
			(xy 35.53968 -359.130878) (xy 35.452823 -359.12686) (xy 35.366708 -359.114841) (xy 35.28207 -359.094923)
			(xy 35.199633 -359.067277) (xy 35.1201 -359.032138) (xy 35.04415 -358.989807) (xy 34.972433 -358.940645)
			(xy 34.90556 -358.885072) (xy 34.844104 -358.823563) (xy 34.788588 -358.756643) (xy 34.739488 -358.684884)
			(xy 34.697222 -358.608898) (xy 34.662151 -358.529335) (xy 34.634575 -358.446874) (xy 34.614729 -358.362219)
			(xy 34.602784 -358.276094) (xy 34.59884 -358.189234) (xy 34.602932 -358.10238) (xy 34.615025 -358.016275)
			(xy 34.635015 -357.931655) (xy 34.662732 -357.849241) (xy 34.67989 -357.809292) (xy 34.687751 -357.788736)
			(xy 34.697073 -357.745727) (xy 34.698849 -357.701756) (xy 34.693028 -357.658136) (xy 34.679784 -357.61617)
			(xy 34.659511 -357.577111) (xy 34.632815 -357.542126) (xy 34.600494 -357.51226) (xy 34.563513 -357.488406)
			(xy 34.522978 -357.471275) (xy 34.480098 -357.46138) (xy 34.458148 -357.459788) (xy 31.541212 -357.459788)
			(xy 31.519275 -357.461447) (xy 31.476415 -357.471356) (xy 31.4359 -357.488494) (xy 31.398939 -357.512348)
			(xy 31.366634 -357.542206) (xy 31.339949 -357.577179) (xy 31.319681 -357.616222) (xy 31.306434 -357.65817)
			(xy 31.300603 -357.701772) (xy 31.302363 -357.745727) (xy 31.31166 -357.788724) (xy 31.31947 -357.809292)
			(xy 31.336628 -357.849241) (xy 31.364345 -357.931655) (xy 31.384335 -358.016275) (xy 31.396428 -358.10238)
			(xy 31.40052 -358.189234) (xy 31.396576 -358.276094) (xy 31.384631 -358.362219) (xy 31.364785 -358.446874)
			(xy 31.337209 -358.529335) (xy 31.302138 -358.608898) (xy 31.259872 -358.684884) (xy 31.210772 -358.756643)
			(xy 31.155256 -358.823563) (xy 31.0938 -358.885072) (xy 31.026927 -358.940645) (xy 30.95521 -358.989807)
			(xy 30.87926 -359.032138) (xy 30.799727 -359.067277) (xy 30.71729 -359.094923) (xy 30.632652 -359.114841)
			(xy 30.546537 -359.12686) (xy 30.45968 -359.130878) (xy 30.372823 -359.12686) (xy 30.286708 -359.114841)
			(xy 30.20207 -359.094923) (xy 30.119633 -359.067277) (xy 30.0401 -359.032138) (xy 29.96415 -358.989807)
			(xy 29.892433 -358.940645) (xy 29.82556 -358.885072) (xy 29.764104 -358.823563) (xy 29.708588 -358.756643)
			(xy 29.659488 -358.684884) (xy 29.617222 -358.608898) (xy 29.582151 -358.529335) (xy 29.554575 -358.446874)
			(xy 29.534729 -358.362219) (xy 29.522784 -358.276094) (xy 29.51884 -358.189234) (xy 29.522932 -358.10238)
			(xy 29.535025 -358.016275) (xy 29.555015 -357.931655) (xy 29.582732 -357.849241) (xy 29.59989 -357.809292)
			(xy 29.607751 -357.788736) (xy 29.617073 -357.745727) (xy 29.618849 -357.701756) (xy 29.613028 -357.658136)
			(xy 29.599784 -357.61617) (xy 29.579511 -357.577111) (xy 29.552815 -357.542126) (xy 29.520494 -357.51226)
			(xy 29.483513 -357.488406) (xy 29.442978 -357.471275) (xy 29.400098 -357.46138) (xy 29.378148 -357.459788)
			(xy 27.096974 -357.459788) (xy 24.43988 -354.802948) (xy 24.408384 -354.793804) (xy 24.381981 -354.78573)
			(xy 24.331653 -354.76303) (xy 24.285122 -354.733313) (xy 24.243359 -354.6972) (xy 24.207237 -354.655446)
			(xy 24.17751 -354.608921) (xy 24.154799 -354.558598) (xy 24.146764 -354.532184) (xy 24.13762 -354.500688)
			(xy 22.698964 -353.062032) (xy 22.682423 -353.047246) (xy 22.645236 -353.023056) (xy 22.604415 -353.005687)
			(xy 22.5612 -352.995665) (xy 22.516901 -352.993295) (xy 22.472863 -352.99865) (xy 22.430423 -353.011565)
			(xy 22.390867 -353.03165) (xy 22.355398 -353.058295) (xy 22.325092 -353.090692) (xy 22.300867 -353.127856)
			(xy 22.28346 -353.16866) (xy 22.273398 -353.211866) (xy 22.271736 -353.23399) (xy 22.271736 -360.550968)
			(xy 26.775916 -360.550968) (xy 26.779987 -360.495346) (xy 26.792113 -360.440909) (xy 26.812036 -360.388818)
			(xy 26.839332 -360.340183) (xy 26.873418 -360.29604) (xy 26.913567 -360.257331) (xy 26.958925 -360.22488)
			(xy 27.008525 -360.199379) (xy 27.061309 -360.181372) (xy 27.116152 -360.171242) (xy 27.171886 -360.169205)
			(xy 27.227323 -360.175305) (xy 27.28128 -360.189411) (xy 27.332609 -360.211223) (xy 27.380215 -360.240277)
			(xy 27.423083 -360.275952) (xy 27.4603 -360.317489) (xy 27.491073 -360.364002) (xy 27.514745 -360.414499)
			(xy 27.530813 -360.467906) (xy 27.538933 -360.523082) (xy 27.539442 -360.550968) (xy 27.538933 -360.578854)
			(xy 27.530813 -360.63403) (xy 27.514745 -360.687437) (xy 27.491073 -360.737934) (xy 27.46755 -360.773488)
			(xy 29.519874 -360.773488) (xy 29.519874 -360.686588) (xy 29.527892 -360.600059) (xy 29.54386 -360.514639)
			(xy 29.567641 -360.431057) (xy 29.599033 -360.350025) (xy 29.637767 -360.272236) (xy 29.683514 -360.198352)
			(xy 29.735883 -360.129005) (xy 29.794427 -360.064785) (xy 29.858647 -360.006241) (xy 29.927994 -359.953872)
			(xy 30.001878 -359.908125) (xy 30.079667 -359.869391) (xy 30.160699 -359.837999) (xy 30.244281 -359.814218)
			(xy 30.329701 -359.79825) (xy 30.41623 -359.790232) (xy 30.50313 -359.790232) (xy 30.589659 -359.79825)
			(xy 30.675079 -359.814218) (xy 30.758661 -359.837999) (xy 30.839693 -359.869391) (xy 30.917482 -359.908125)
			(xy 30.991366 -359.953872) (xy 31.060713 -360.006241) (xy 31.124933 -360.064785) (xy 31.183477 -360.129005)
			(xy 31.235846 -360.198352) (xy 31.281593 -360.272236) (xy 31.320327 -360.350025) (xy 31.351719 -360.431057)
			(xy 31.3755 -360.514639) (xy 31.391468 -360.600059) (xy 31.399486 -360.686588) (xy 31.399988 -360.730038)
			(xy 31.399486 -360.773488) (xy 34.599874 -360.773488) (xy 34.599874 -360.686588) (xy 34.607892 -360.600059)
			(xy 34.62386 -360.514639) (xy 34.647641 -360.431057) (xy 34.679033 -360.350025) (xy 34.717767 -360.272236)
			(xy 34.763514 -360.198352) (xy 34.815883 -360.129005) (xy 34.874427 -360.064785) (xy 34.938647 -360.006241)
			(xy 35.007994 -359.953872) (xy 35.081878 -359.908125) (xy 35.159667 -359.869391) (xy 35.240699 -359.837999)
			(xy 35.324281 -359.814218) (xy 35.409701 -359.79825) (xy 35.49623 -359.790232) (xy 35.58313 -359.790232)
			(xy 35.669659 -359.79825) (xy 35.755079 -359.814218) (xy 35.838661 -359.837999) (xy 35.919693 -359.869391)
			(xy 35.997482 -359.908125) (xy 36.071366 -359.953872) (xy 36.140713 -360.006241) (xy 36.204933 -360.064785)
			(xy 36.263477 -360.129005) (xy 36.315846 -360.198352) (xy 36.361593 -360.272236) (xy 36.400327 -360.350025)
			(xy 36.431719 -360.431057) (xy 36.4555 -360.514639) (xy 36.471468 -360.600059) (xy 36.479486 -360.686588)
			(xy 36.479988 -360.730038) (xy 36.479486 -360.773488) (xy 36.471468 -360.860017) (xy 36.4555 -360.945437)
			(xy 36.431719 -361.029019) (xy 36.400327 -361.110051) (xy 36.361593 -361.18784) (xy 36.315846 -361.261724)
			(xy 36.263477 -361.331071) (xy 36.204933 -361.395291) (xy 36.140713 -361.453835) (xy 36.071366 -361.506204)
			(xy 35.997482 -361.551951) (xy 35.919693 -361.590685) (xy 35.838661 -361.622077) (xy 35.755079 -361.645858)
			(xy 35.669659 -361.661826) (xy 35.58313 -361.669844) (xy 35.49623 -361.669844) (xy 35.409701 -361.661826)
			(xy 35.324281 -361.645858) (xy 35.240699 -361.622077) (xy 35.159667 -361.590685) (xy 35.081878 -361.551951)
			(xy 35.007994 -361.506204) (xy 34.938647 -361.453835) (xy 34.874427 -361.395291) (xy 34.815883 -361.331071)
			(xy 34.763514 -361.261724) (xy 34.717767 -361.18784) (xy 34.679033 -361.110051) (xy 34.647641 -361.029019)
			(xy 34.62386 -360.945437) (xy 34.607892 -360.860017) (xy 34.599874 -360.773488) (xy 31.399486 -360.773488)
			(xy 31.391468 -360.860017) (xy 31.3755 -360.945437) (xy 31.351719 -361.029019) (xy 31.320327 -361.110051)
			(xy 31.281593 -361.18784) (xy 31.235846 -361.261724) (xy 31.183477 -361.331071) (xy 31.124933 -361.395291)
			(xy 31.060713 -361.453835) (xy 30.991366 -361.506204) (xy 30.917482 -361.551951) (xy 30.839693 -361.590685)
			(xy 30.758661 -361.622077) (xy 30.675079 -361.645858) (xy 30.589659 -361.661826) (xy 30.50313 -361.669844)
			(xy 30.41623 -361.669844) (xy 30.329701 -361.661826) (xy 30.244281 -361.645858) (xy 30.160699 -361.622077)
			(xy 30.079667 -361.590685) (xy 30.001878 -361.551951) (xy 29.927994 -361.506204) (xy 29.858647 -361.453835)
			(xy 29.794427 -361.395291) (xy 29.735883 -361.331071) (xy 29.683514 -361.261724) (xy 29.637767 -361.18784)
			(xy 29.599033 -361.110051) (xy 29.567641 -361.029019) (xy 29.54386 -360.945437) (xy 29.527892 -360.860017)
			(xy 29.519874 -360.773488) (xy 27.46755 -360.773488) (xy 27.4603 -360.784447) (xy 27.423083 -360.825984)
			(xy 27.380215 -360.861659) (xy 27.332609 -360.890713) (xy 27.28128 -360.912525) (xy 27.227323 -360.926631)
			(xy 27.171886 -360.932731) (xy 27.116152 -360.930694) (xy 27.061309 -360.920564) (xy 27.008525 -360.902557)
			(xy 26.958925 -360.877056) (xy 26.913567 -360.844605) (xy 26.873418 -360.805896) (xy 26.839332 -360.761753)
			(xy 26.812036 -360.713118) (xy 26.792113 -360.661027) (xy 26.779987 -360.60659) (xy 26.775916 -360.550968)
			(xy 22.271736 -360.550968) (xy 22.271736 -363.313488) (xy 29.519874 -363.313488) (xy 29.519874 -363.226588)
			(xy 29.527892 -363.140059) (xy 29.54386 -363.054639) (xy 29.567641 -362.971057) (xy 29.599033 -362.890025)
			(xy 29.637767 -362.812236) (xy 29.683514 -362.738352) (xy 29.735883 -362.669005) (xy 29.794427 -362.604785)
			(xy 29.858647 -362.546241) (xy 29.927994 -362.493872) (xy 30.001878 -362.448125) (xy 30.079667 -362.409391)
			(xy 30.160699 -362.377999) (xy 30.244281 -362.354218) (xy 30.329701 -362.33825) (xy 30.41623 -362.330232)
			(xy 30.50313 -362.330232) (xy 30.589659 -362.33825) (xy 30.675079 -362.354218) (xy 30.758661 -362.377999)
			(xy 30.839693 -362.409391) (xy 30.917482 -362.448125) (xy 30.991366 -362.493872) (xy 31.060713 -362.546241)
			(xy 31.124933 -362.604785) (xy 31.183477 -362.669005) (xy 31.235846 -362.738352) (xy 31.281593 -362.812236)
			(xy 31.320327 -362.890025) (xy 31.351719 -362.971057) (xy 31.3755 -363.054639) (xy 31.391468 -363.140059)
			(xy 31.399486 -363.226588) (xy 31.399988 -363.270038) (xy 31.399486 -363.313488) (xy 34.599874 -363.313488)
			(xy 34.599874 -363.226588) (xy 34.607892 -363.140059) (xy 34.62386 -363.054639) (xy 34.647641 -362.971057)
			(xy 34.679033 -362.890025) (xy 34.717767 -362.812236) (xy 34.763514 -362.738352) (xy 34.815883 -362.669005)
			(xy 34.874427 -362.604785) (xy 34.938647 -362.546241) (xy 35.007994 -362.493872) (xy 35.081878 -362.448125)
			(xy 35.159667 -362.409391) (xy 35.240699 -362.377999) (xy 35.324281 -362.354218) (xy 35.409701 -362.33825)
			(xy 35.49623 -362.330232) (xy 35.58313 -362.330232) (xy 35.669659 -362.33825) (xy 35.755079 -362.354218)
			(xy 35.838661 -362.377999) (xy 35.919693 -362.409391) (xy 35.997482 -362.448125) (xy 36.071366 -362.493872)
			(xy 36.092815 -362.51007) (xy 39.818564 -362.51007) (xy 39.819058 -362.452661) (xy 39.826902 -362.338113)
			(xy 39.842544 -362.224366) (xy 39.865911 -362.111952) (xy 39.896896 -362.001394) (xy 39.935352 -361.893209)
			(xy 39.981101 -361.7879) (xy 40.03393 -361.685958) (xy 40.093592 -361.587859) (xy 40.159809 -361.49406)
			(xy 40.232272 -361.404998) (xy 40.310645 -361.321089) (xy 40.39456 -361.242723) (xy 40.483627 -361.170266)
			(xy 40.577431 -361.104056) (xy 40.675535 -361.044402) (xy 40.777481 -360.991581) (xy 40.882793 -360.945839)
			(xy 40.990981 -360.907391) (xy 41.101541 -360.876415) (xy 41.213957 -360.853056) (xy 41.327705 -360.837423)
			(xy 41.442254 -360.829588) (xy 41.557072 -360.829588) (xy 41.671621 -360.837423) (xy 41.785369 -360.853056)
			(xy 41.897785 -360.876415) (xy 42.008345 -360.907391) (xy 42.116533 -360.945839) (xy 42.221845 -360.991581)
			(xy 42.323791 -361.044402) (xy 42.421895 -361.104056) (xy 42.501239 -361.16006) (xy 63.647577 -361.16006)
			(xy 63.651612 -361.084356) (xy 63.663671 -361.009511) (xy 63.683617 -360.93637) (xy 63.711224 -360.865765)
			(xy 63.74618 -360.798494) (xy 63.788088 -360.735319) (xy 63.836474 -360.676957) (xy 63.89079 -360.624069)
			(xy 63.950419 -360.577254) (xy 64.014687 -360.537042) (xy 64.082864 -360.50389) (xy 64.15418 -360.478172)
			(xy 64.227825 -360.46018) (xy 64.302965 -360.450118) (xy 64.378749 -360.448099) (xy 64.454319 -360.454148)
			(xy 64.528817 -360.468195) (xy 64.6014 -360.490081) (xy 64.671246 -360.519558) (xy 64.737563 -360.556293)
			(xy 64.799599 -360.599868) (xy 64.856652 -360.64979) (xy 64.908076 -360.705494) (xy 64.953287 -360.766349)
			(xy 64.991774 -360.831664) (xy 65.0231 -360.9007) (xy 65.04691 -360.972675) (xy 65.062935 -361.046773)
			(xy 65.070994 -361.122154) (xy 65.071498 -361.16006) (xy 66.187577 -361.16006) (xy 66.191612 -361.084356)
			(xy 66.203671 -361.009511) (xy 66.223617 -360.93637) (xy 66.251224 -360.865765) (xy 66.28618 -360.798494)
			(xy 66.328088 -360.735319) (xy 66.376474 -360.676957) (xy 66.43079 -360.624069) (xy 66.490419 -360.577254)
			(xy 66.554687 -360.537042) (xy 66.622864 -360.50389) (xy 66.69418 -360.478172) (xy 66.767825 -360.46018)
			(xy 66.842965 -360.450118) (xy 66.918749 -360.448099) (xy 66.994319 -360.454148) (xy 67.068817 -360.468195)
			(xy 67.1414 -360.490081) (xy 67.211246 -360.519558) (xy 67.277563 -360.556293) (xy 67.339599 -360.599868)
			(xy 67.396652 -360.64979) (xy 67.448076 -360.705494) (xy 67.493287 -360.766349) (xy 67.531774 -360.831664)
			(xy 67.5631 -360.9007) (xy 67.58691 -360.972675) (xy 67.602935 -361.046773) (xy 67.610994 -361.122154)
			(xy 67.611498 -361.16006) (xy 68.727577 -361.16006) (xy 68.731612 -361.084356) (xy 68.743671 -361.009511)
			(xy 68.763617 -360.93637) (xy 68.791224 -360.865765) (xy 68.82618 -360.798494) (xy 68.868088 -360.735319)
			(xy 68.916474 -360.676957) (xy 68.97079 -360.624069) (xy 69.030419 -360.577254) (xy 69.094687 -360.537042)
			(xy 69.162864 -360.50389) (xy 69.23418 -360.478172) (xy 69.307825 -360.46018) (xy 69.382965 -360.450118)
			(xy 69.458749 -360.448099) (xy 69.534319 -360.454148) (xy 69.608817 -360.468195) (xy 69.6814 -360.490081)
			(xy 69.751246 -360.519558) (xy 69.817563 -360.556293) (xy 69.879599 -360.599868) (xy 69.936652 -360.64979)
			(xy 69.988076 -360.705494) (xy 70.033287 -360.766349) (xy 70.071774 -360.831664) (xy 70.1031 -360.9007)
			(xy 70.12691 -360.972675) (xy 70.142935 -361.046773) (xy 70.150994 -361.122154) (xy 70.151498 -361.16006)
			(xy 71.267577 -361.16006) (xy 71.271612 -361.084356) (xy 71.283671 -361.009511) (xy 71.303617 -360.93637)
			(xy 71.331224 -360.865765) (xy 71.36618 -360.798494) (xy 71.408088 -360.735319) (xy 71.456474 -360.676957)
			(xy 71.51079 -360.624069) (xy 71.570419 -360.577254) (xy 71.634687 -360.537042) (xy 71.702864 -360.50389)
			(xy 71.77418 -360.478172) (xy 71.847825 -360.46018) (xy 71.922965 -360.450118) (xy 71.998749 -360.448099)
			(xy 72.074319 -360.454148) (xy 72.148817 -360.468195) (xy 72.2214 -360.490081) (xy 72.291246 -360.519558)
			(xy 72.357563 -360.556293) (xy 72.419599 -360.599868) (xy 72.476652 -360.64979) (xy 72.528076 -360.705494)
			(xy 72.573287 -360.766349) (xy 72.611774 -360.831664) (xy 72.6431 -360.9007) (xy 72.66691 -360.972675)
			(xy 72.682935 -361.046773) (xy 72.690994 -361.122154) (xy 72.691498 -361.16006) (xy 73.807577 -361.16006)
			(xy 73.811612 -361.084356) (xy 73.823671 -361.009511) (xy 73.843617 -360.93637) (xy 73.871224 -360.865765)
			(xy 73.90618 -360.798494) (xy 73.948088 -360.735319) (xy 73.996474 -360.676957) (xy 74.05079 -360.624069)
			(xy 74.110419 -360.577254) (xy 74.174687 -360.537042) (xy 74.242864 -360.50389) (xy 74.31418 -360.478172)
			(xy 74.387825 -360.46018) (xy 74.462965 -360.450118) (xy 74.538749 -360.448099) (xy 74.614319 -360.454148)
			(xy 74.688817 -360.468195) (xy 74.7614 -360.490081) (xy 74.831246 -360.519558) (xy 74.897563 -360.556293)
			(xy 74.959599 -360.599868) (xy 75.016652 -360.64979) (xy 75.068076 -360.705494) (xy 75.113287 -360.766349)
			(xy 75.151774 -360.831664) (xy 75.1831 -360.9007) (xy 75.20691 -360.972675) (xy 75.222935 -361.046773)
			(xy 75.230994 -361.122154) (xy 75.231498 -361.16006) (xy 76.347577 -361.16006) (xy 76.351612 -361.084356)
			(xy 76.363671 -361.009511) (xy 76.383617 -360.93637) (xy 76.411224 -360.865765) (xy 76.44618 -360.798494)
			(xy 76.488088 -360.735319) (xy 76.536474 -360.676957) (xy 76.59079 -360.624069) (xy 76.650419 -360.577254)
			(xy 76.714687 -360.537042) (xy 76.782864 -360.50389) (xy 76.85418 -360.478172) (xy 76.927825 -360.46018)
			(xy 77.002965 -360.450118) (xy 77.078749 -360.448099) (xy 77.154319 -360.454148) (xy 77.228817 -360.468195)
			(xy 77.3014 -360.490081) (xy 77.371246 -360.519558) (xy 77.437563 -360.556293) (xy 77.499599 -360.599868)
			(xy 77.556652 -360.64979) (xy 77.608076 -360.705494) (xy 77.653287 -360.766349) (xy 77.691774 -360.831664)
			(xy 77.7231 -360.9007) (xy 77.74691 -360.972675) (xy 77.762935 -361.046773) (xy 77.770994 -361.122154)
			(xy 77.771498 -361.16006) (xy 78.887577 -361.16006) (xy 78.891612 -361.084356) (xy 78.903671 -361.009511)
			(xy 78.923617 -360.93637) (xy 78.951224 -360.865765) (xy 78.98618 -360.798494) (xy 79.028088 -360.735319)
			(xy 79.076474 -360.676957) (xy 79.13079 -360.624069) (xy 79.190419 -360.577254) (xy 79.254687 -360.537042)
			(xy 79.322864 -360.50389) (xy 79.39418 -360.478172) (xy 79.467825 -360.46018) (xy 79.542965 -360.450118)
			(xy 79.618749 -360.448099) (xy 79.694319 -360.454148) (xy 79.768817 -360.468195) (xy 79.8414 -360.490081)
			(xy 79.911246 -360.519558) (xy 79.977563 -360.556293) (xy 80.039599 -360.599868) (xy 80.096652 -360.64979)
			(xy 80.148076 -360.705494) (xy 80.193287 -360.766349) (xy 80.231774 -360.831664) (xy 80.2631 -360.9007)
			(xy 80.28691 -360.972675) (xy 80.302935 -361.046773) (xy 80.310994 -361.122154) (xy 80.311498 -361.16006)
			(xy 81.427577 -361.16006) (xy 81.431612 -361.084356) (xy 81.443671 -361.009511) (xy 81.463617 -360.93637)
			(xy 81.491224 -360.865765) (xy 81.52618 -360.798494) (xy 81.568088 -360.735319) (xy 81.616474 -360.676957)
			(xy 81.67079 -360.624069) (xy 81.730419 -360.577254) (xy 81.794687 -360.537042) (xy 81.862864 -360.50389)
			(xy 81.93418 -360.478172) (xy 82.007825 -360.46018) (xy 82.082965 -360.450118) (xy 82.158749 -360.448099)
			(xy 82.234319 -360.454148) (xy 82.308817 -360.468195) (xy 82.3814 -360.490081) (xy 82.451246 -360.519558)
			(xy 82.517563 -360.556293) (xy 82.579599 -360.599868) (xy 82.636652 -360.64979) (xy 82.688076 -360.705494)
			(xy 82.733287 -360.766349) (xy 82.771774 -360.831664) (xy 82.8031 -360.9007) (xy 82.82691 -360.972675)
			(xy 82.842935 -361.046773) (xy 82.850994 -361.122154) (xy 82.851498 -361.16006) (xy 82.850994 -361.197966)
			(xy 82.842935 -361.273347) (xy 82.82691 -361.347445) (xy 82.8031 -361.41942) (xy 82.771774 -361.488456)
			(xy 82.733287 -361.553771) (xy 82.688076 -361.614626) (xy 82.636652 -361.67033) (xy 82.579599 -361.720252)
			(xy 82.517563 -361.763827) (xy 82.451246 -361.800562) (xy 82.3814 -361.830039) (xy 82.308817 -361.851925)
			(xy 82.234319 -361.865972) (xy 82.158749 -361.872021) (xy 82.082965 -361.870002) (xy 82.007825 -361.85994)
			(xy 81.93418 -361.841948) (xy 81.862864 -361.81623) (xy 81.794687 -361.783078) (xy 81.730419 -361.742866)
			(xy 81.67079 -361.696051) (xy 81.616474 -361.643163) (xy 81.568088 -361.584801) (xy 81.52618 -361.521626)
			(xy 81.491224 -361.454355) (xy 81.463617 -361.38375) (xy 81.443671 -361.310609) (xy 81.431612 -361.235764)
			(xy 81.427577 -361.16006) (xy 80.311498 -361.16006) (xy 80.310994 -361.197966) (xy 80.302935 -361.273347)
			(xy 80.28691 -361.347445) (xy 80.2631 -361.41942) (xy 80.231774 -361.488456) (xy 80.193287 -361.553771)
			(xy 80.148076 -361.614626) (xy 80.096652 -361.67033) (xy 80.039599 -361.720252) (xy 79.977563 -361.763827)
			(xy 79.911246 -361.800562) (xy 79.8414 -361.830039) (xy 79.768817 -361.851925) (xy 79.694319 -361.865972)
			(xy 79.618749 -361.872021) (xy 79.542965 -361.870002) (xy 79.467825 -361.85994) (xy 79.39418 -361.841948)
			(xy 79.322864 -361.81623) (xy 79.254687 -361.783078) (xy 79.190419 -361.742866) (xy 79.13079 -361.696051)
			(xy 79.076474 -361.643163) (xy 79.028088 -361.584801) (xy 78.98618 -361.521626) (xy 78.951224 -361.454355)
			(xy 78.923617 -361.38375) (xy 78.903671 -361.310609) (xy 78.891612 -361.235764) (xy 78.887577 -361.16006)
			(xy 77.771498 -361.16006) (xy 77.770994 -361.197966) (xy 77.762935 -361.273347) (xy 77.74691 -361.347445)
			(xy 77.7231 -361.41942) (xy 77.691774 -361.488456) (xy 77.653287 -361.553771) (xy 77.608076 -361.614626)
			(xy 77.556652 -361.67033) (xy 77.499599 -361.720252) (xy 77.437563 -361.763827) (xy 77.371246 -361.800562)
			(xy 77.3014 -361.830039) (xy 77.228817 -361.851925) (xy 77.154319 -361.865972) (xy 77.078749 -361.872021)
			(xy 77.002965 -361.870002) (xy 76.927825 -361.85994) (xy 76.85418 -361.841948) (xy 76.782864 -361.81623)
			(xy 76.714687 -361.783078) (xy 76.650419 -361.742866) (xy 76.59079 -361.696051) (xy 76.536474 -361.643163)
			(xy 76.488088 -361.584801) (xy 76.44618 -361.521626) (xy 76.411224 -361.454355) (xy 76.383617 -361.38375)
			(xy 76.363671 -361.310609) (xy 76.351612 -361.235764) (xy 76.347577 -361.16006) (xy 75.231498 -361.16006)
			(xy 75.230994 -361.197966) (xy 75.222935 -361.273347) (xy 75.20691 -361.347445) (xy 75.1831 -361.41942)
			(xy 75.151774 -361.488456) (xy 75.113287 -361.553771) (xy 75.068076 -361.614626) (xy 75.016652 -361.67033)
			(xy 74.959599 -361.720252) (xy 74.897563 -361.763827) (xy 74.831246 -361.800562) (xy 74.7614 -361.830039)
			(xy 74.688817 -361.851925) (xy 74.614319 -361.865972) (xy 74.538749 -361.872021) (xy 74.462965 -361.870002)
			(xy 74.387825 -361.85994) (xy 74.31418 -361.841948) (xy 74.242864 -361.81623) (xy 74.174687 -361.783078)
			(xy 74.110419 -361.742866) (xy 74.05079 -361.696051) (xy 73.996474 -361.643163) (xy 73.948088 -361.584801)
			(xy 73.90618 -361.521626) (xy 73.871224 -361.454355) (xy 73.843617 -361.38375) (xy 73.823671 -361.310609)
			(xy 73.811612 -361.235764) (xy 73.807577 -361.16006) (xy 72.691498 -361.16006) (xy 72.690994 -361.197966)
			(xy 72.682935 -361.273347) (xy 72.66691 -361.347445) (xy 72.6431 -361.41942) (xy 72.611774 -361.488456)
			(xy 72.573287 -361.553771) (xy 72.528076 -361.614626) (xy 72.476652 -361.67033) (xy 72.419599 -361.720252)
			(xy 72.357563 -361.763827) (xy 72.291246 -361.800562) (xy 72.2214 -361.830039) (xy 72.148817 -361.851925)
			(xy 72.074319 -361.865972) (xy 71.998749 -361.872021) (xy 71.922965 -361.870002) (xy 71.847825 -361.85994)
			(xy 71.77418 -361.841948) (xy 71.702864 -361.81623) (xy 71.634687 -361.783078) (xy 71.570419 -361.742866)
			(xy 71.51079 -361.696051) (xy 71.456474 -361.643163) (xy 71.408088 -361.584801) (xy 71.36618 -361.521626)
			(xy 71.331224 -361.454355) (xy 71.303617 -361.38375) (xy 71.283671 -361.310609) (xy 71.271612 -361.235764)
			(xy 71.267577 -361.16006) (xy 70.151498 -361.16006) (xy 70.150994 -361.197966) (xy 70.142935 -361.273347)
			(xy 70.12691 -361.347445) (xy 70.1031 -361.41942) (xy 70.071774 -361.488456) (xy 70.033287 -361.553771)
			(xy 69.988076 -361.614626) (xy 69.936652 -361.67033) (xy 69.879599 -361.720252) (xy 69.817563 -361.763827)
			(xy 69.751246 -361.800562) (xy 69.6814 -361.830039) (xy 69.608817 -361.851925) (xy 69.534319 -361.865972)
			(xy 69.458749 -361.872021) (xy 69.382965 -361.870002) (xy 69.307825 -361.85994) (xy 69.23418 -361.841948)
			(xy 69.162864 -361.81623) (xy 69.094687 -361.783078) (xy 69.030419 -361.742866) (xy 68.97079 -361.696051)
			(xy 68.916474 -361.643163) (xy 68.868088 -361.584801) (xy 68.82618 -361.521626) (xy 68.791224 -361.454355)
			(xy 68.763617 -361.38375) (xy 68.743671 -361.310609) (xy 68.731612 -361.235764) (xy 68.727577 -361.16006)
			(xy 67.611498 -361.16006) (xy 67.610994 -361.197966) (xy 67.602935 -361.273347) (xy 67.58691 -361.347445)
			(xy 67.5631 -361.41942) (xy 67.531774 -361.488456) (xy 67.493287 -361.553771) (xy 67.448076 -361.614626)
			(xy 67.396652 -361.67033) (xy 67.339599 -361.720252) (xy 67.277563 -361.763827) (xy 67.211246 -361.800562)
			(xy 67.1414 -361.830039) (xy 67.068817 -361.851925) (xy 66.994319 -361.865972) (xy 66.918749 -361.872021)
			(xy 66.842965 -361.870002) (xy 66.767825 -361.85994) (xy 66.69418 -361.841948) (xy 66.622864 -361.81623)
			(xy 66.554687 -361.783078) (xy 66.490419 -361.742866) (xy 66.43079 -361.696051) (xy 66.376474 -361.643163)
			(xy 66.328088 -361.584801) (xy 66.28618 -361.521626) (xy 66.251224 -361.454355) (xy 66.223617 -361.38375)
			(xy 66.203671 -361.310609) (xy 66.191612 -361.235764) (xy 66.187577 -361.16006) (xy 65.071498 -361.16006)
			(xy 65.070994 -361.197966) (xy 65.062935 -361.273347) (xy 65.04691 -361.347445) (xy 65.0231 -361.41942)
			(xy 64.991774 -361.488456) (xy 64.953287 -361.553771) (xy 64.908076 -361.614626) (xy 64.856652 -361.67033)
			(xy 64.799599 -361.720252) (xy 64.737563 -361.763827) (xy 64.671246 -361.800562) (xy 64.6014 -361.830039)
			(xy 64.528817 -361.851925) (xy 64.454319 -361.865972) (xy 64.378749 -361.872021) (xy 64.302965 -361.870002)
			(xy 64.227825 -361.85994) (xy 64.15418 -361.841948) (xy 64.082864 -361.81623) (xy 64.014687 -361.783078)
			(xy 63.950419 -361.742866) (xy 63.89079 -361.696051) (xy 63.836474 -361.643163) (xy 63.788088 -361.584801)
			(xy 63.74618 -361.521626) (xy 63.711224 -361.454355) (xy 63.683617 -361.38375) (xy 63.663671 -361.310609)
			(xy 63.651612 -361.235764) (xy 63.647577 -361.16006) (xy 42.501239 -361.16006) (xy 42.515699 -361.170266)
			(xy 42.604766 -361.242723) (xy 42.688681 -361.321089) (xy 42.767054 -361.404998) (xy 42.839517 -361.49406)
			(xy 42.905734 -361.587859) (xy 42.965396 -361.685958) (xy 43.018225 -361.7879) (xy 43.063974 -361.893209)
			(xy 43.10243 -362.001394) (xy 43.133415 -362.111952) (xy 43.156782 -362.224366) (xy 43.172424 -362.338113)
			(xy 43.180268 -362.452661) (xy 43.180762 -362.51007) (xy 43.180576 -362.543253) (xy 43.177909 -362.609567)
			(xy 43.175428 -362.642658) (xy 43.170272 -362.700942) (xy 43.152948 -362.816671) (xy 43.127616 -362.930914)
			(xy 43.094401 -363.043119) (xy 43.053462 -363.152742) (xy 43.004999 -363.259253) (xy 42.949245 -363.362135)
			(xy 42.886471 -363.460891) (xy 42.816981 -363.555042) (xy 42.741111 -363.644132) (xy 42.659229 -363.727729)
			(xy 42.571732 -363.80543) (xy 42.500813 -363.86008) (xy 63.647577 -363.86008) (xy 63.651612 -363.784376)
			(xy 63.663671 -363.709531) (xy 63.683617 -363.63639) (xy 63.711224 -363.565785) (xy 63.74618 -363.498514)
			(xy 63.788088 -363.435339) (xy 63.836474 -363.376977) (xy 63.89079 -363.324089) (xy 63.950419 -363.277274)
			(xy 64.014687 -363.237062) (xy 64.082864 -363.20391) (xy 64.15418 -363.178192) (xy 64.227825 -363.1602)
			(xy 64.302965 -363.150138) (xy 64.378749 -363.148119) (xy 64.454319 -363.154168) (xy 64.528817 -363.168215)
			(xy 64.6014 -363.190101) (xy 64.671246 -363.219578) (xy 64.737563 -363.256313) (xy 64.799599 -363.299888)
			(xy 64.856652 -363.34981) (xy 64.908076 -363.405514) (xy 64.953287 -363.466369) (xy 64.991774 -363.531684)
			(xy 65.0231 -363.60072) (xy 65.04691 -363.672695) (xy 65.062935 -363.746793) (xy 65.070994 -363.822174)
			(xy 65.071498 -363.86008) (xy 66.187577 -363.86008) (xy 66.191612 -363.784376) (xy 66.203671 -363.709531)
			(xy 66.223617 -363.63639) (xy 66.251224 -363.565785) (xy 66.28618 -363.498514) (xy 66.328088 -363.435339)
			(xy 66.376474 -363.376977) (xy 66.43079 -363.324089) (xy 66.490419 -363.277274) (xy 66.554687 -363.237062)
			(xy 66.622864 -363.20391) (xy 66.69418 -363.178192) (xy 66.767825 -363.1602) (xy 66.842965 -363.150138)
			(xy 66.918749 -363.148119) (xy 66.994319 -363.154168) (xy 67.068817 -363.168215) (xy 67.1414 -363.190101)
			(xy 67.211246 -363.219578) (xy 67.277563 -363.256313) (xy 67.339599 -363.299888) (xy 67.396652 -363.34981)
			(xy 67.448076 -363.405514) (xy 67.493287 -363.466369) (xy 67.531774 -363.531684) (xy 67.5631 -363.60072)
			(xy 67.58691 -363.672695) (xy 67.602935 -363.746793) (xy 67.610994 -363.822174) (xy 67.611498 -363.86008)
			(xy 68.727577 -363.86008) (xy 68.731612 -363.784376) (xy 68.743671 -363.709531) (xy 68.763617 -363.63639)
			(xy 68.791224 -363.565785) (xy 68.82618 -363.498514) (xy 68.868088 -363.435339) (xy 68.916474 -363.376977)
			(xy 68.97079 -363.324089) (xy 69.030419 -363.277274) (xy 69.094687 -363.237062) (xy 69.162864 -363.20391)
			(xy 69.23418 -363.178192) (xy 69.307825 -363.1602) (xy 69.382965 -363.150138) (xy 69.458749 -363.148119)
			(xy 69.534319 -363.154168) (xy 69.608817 -363.168215) (xy 69.6814 -363.190101) (xy 69.751246 -363.219578)
			(xy 69.817563 -363.256313) (xy 69.879599 -363.299888) (xy 69.936652 -363.34981) (xy 69.988076 -363.405514)
			(xy 70.033287 -363.466369) (xy 70.071774 -363.531684) (xy 70.1031 -363.60072) (xy 70.12691 -363.672695)
			(xy 70.142935 -363.746793) (xy 70.150994 -363.822174) (xy 70.151498 -363.86008) (xy 71.267577 -363.86008)
			(xy 71.271612 -363.784376) (xy 71.283671 -363.709531) (xy 71.303617 -363.63639) (xy 71.331224 -363.565785)
			(xy 71.36618 -363.498514) (xy 71.408088 -363.435339) (xy 71.456474 -363.376977) (xy 71.51079 -363.324089)
			(xy 71.570419 -363.277274) (xy 71.634687 -363.237062) (xy 71.702864 -363.20391) (xy 71.77418 -363.178192)
			(xy 71.847825 -363.1602) (xy 71.922965 -363.150138) (xy 71.998749 -363.148119) (xy 72.074319 -363.154168)
			(xy 72.148817 -363.168215) (xy 72.2214 -363.190101) (xy 72.291246 -363.219578) (xy 72.357563 -363.256313)
			(xy 72.419599 -363.299888) (xy 72.476652 -363.34981) (xy 72.528076 -363.405514) (xy 72.573287 -363.466369)
			(xy 72.611774 -363.531684) (xy 72.6431 -363.60072) (xy 72.66691 -363.672695) (xy 72.682935 -363.746793)
			(xy 72.690994 -363.822174) (xy 72.691498 -363.86008) (xy 73.807577 -363.86008) (xy 73.811612 -363.784376)
			(xy 73.823671 -363.709531) (xy 73.843617 -363.63639) (xy 73.871224 -363.565785) (xy 73.90618 -363.498514)
			(xy 73.948088 -363.435339) (xy 73.996474 -363.376977) (xy 74.05079 -363.324089) (xy 74.110419 -363.277274)
			(xy 74.174687 -363.237062) (xy 74.242864 -363.20391) (xy 74.31418 -363.178192) (xy 74.387825 -363.1602)
			(xy 74.462965 -363.150138) (xy 74.538749 -363.148119) (xy 74.614319 -363.154168) (xy 74.688817 -363.168215)
			(xy 74.7614 -363.190101) (xy 74.831246 -363.219578) (xy 74.897563 -363.256313) (xy 74.959599 -363.299888)
			(xy 75.016652 -363.34981) (xy 75.068076 -363.405514) (xy 75.113287 -363.466369) (xy 75.151774 -363.531684)
			(xy 75.1831 -363.60072) (xy 75.20691 -363.672695) (xy 75.222935 -363.746793) (xy 75.230994 -363.822174)
			(xy 75.231498 -363.86008) (xy 76.347577 -363.86008) (xy 76.351612 -363.784376) (xy 76.363671 -363.709531)
			(xy 76.383617 -363.63639) (xy 76.411224 -363.565785) (xy 76.44618 -363.498514) (xy 76.488088 -363.435339)
			(xy 76.536474 -363.376977) (xy 76.59079 -363.324089) (xy 76.650419 -363.277274) (xy 76.714687 -363.237062)
			(xy 76.782864 -363.20391) (xy 76.85418 -363.178192) (xy 76.927825 -363.1602) (xy 77.002965 -363.150138)
			(xy 77.078749 -363.148119) (xy 77.154319 -363.154168) (xy 77.228817 -363.168215) (xy 77.3014 -363.190101)
			(xy 77.371246 -363.219578) (xy 77.437563 -363.256313) (xy 77.499599 -363.299888) (xy 77.556652 -363.34981)
			(xy 77.608076 -363.405514) (xy 77.653287 -363.466369) (xy 77.691774 -363.531684) (xy 77.7231 -363.60072)
			(xy 77.74691 -363.672695) (xy 77.762935 -363.746793) (xy 77.770994 -363.822174) (xy 77.771498 -363.86008)
			(xy 78.887577 -363.86008) (xy 78.891612 -363.784376) (xy 78.903671 -363.709531) (xy 78.923617 -363.63639)
			(xy 78.951224 -363.565785) (xy 78.98618 -363.498514) (xy 79.028088 -363.435339) (xy 79.076474 -363.376977)
			(xy 79.13079 -363.324089) (xy 79.190419 -363.277274) (xy 79.254687 -363.237062) (xy 79.322864 -363.20391)
			(xy 79.39418 -363.178192) (xy 79.467825 -363.1602) (xy 79.542965 -363.150138) (xy 79.618749 -363.148119)
			(xy 79.694319 -363.154168) (xy 79.768817 -363.168215) (xy 79.8414 -363.190101) (xy 79.911246 -363.219578)
			(xy 79.977563 -363.256313) (xy 80.039599 -363.299888) (xy 80.096652 -363.34981) (xy 80.148076 -363.405514)
			(xy 80.193287 -363.466369) (xy 80.231774 -363.531684) (xy 80.2631 -363.60072) (xy 80.28691 -363.672695)
			(xy 80.302935 -363.746793) (xy 80.310994 -363.822174) (xy 80.311498 -363.86008) (xy 81.427577 -363.86008)
			(xy 81.431612 -363.784376) (xy 81.443671 -363.709531) (xy 81.463617 -363.63639) (xy 81.491224 -363.565785)
			(xy 81.52618 -363.498514) (xy 81.568088 -363.435339) (xy 81.616474 -363.376977) (xy 81.67079 -363.324089)
			(xy 81.730419 -363.277274) (xy 81.794687 -363.237062) (xy 81.862864 -363.20391) (xy 81.93418 -363.178192)
			(xy 82.007825 -363.1602) (xy 82.082965 -363.150138) (xy 82.158749 -363.148119) (xy 82.234319 -363.154168)
			(xy 82.308817 -363.168215) (xy 82.3814 -363.190101) (xy 82.451246 -363.219578) (xy 82.517563 -363.256313)
			(xy 82.579599 -363.299888) (xy 82.636652 -363.34981) (xy 82.688076 -363.405514) (xy 82.733287 -363.466369)
			(xy 82.771774 -363.531684) (xy 82.8031 -363.60072) (xy 82.82691 -363.672695) (xy 82.842935 -363.746793)
			(xy 82.850994 -363.822174) (xy 82.851498 -363.86008) (xy 82.850994 -363.897986) (xy 82.842935 -363.973367)
			(xy 82.82691 -364.047465) (xy 82.8031 -364.11944) (xy 82.771774 -364.188476) (xy 82.733287 -364.253791)
			(xy 82.688076 -364.314646) (xy 82.636652 -364.37035) (xy 82.579599 -364.420272) (xy 82.517563 -364.463847)
			(xy 82.451246 -364.500582) (xy 82.3814 -364.530059) (xy 82.308817 -364.551945) (xy 82.234319 -364.565992)
			(xy 82.158749 -364.572041) (xy 82.082965 -364.570022) (xy 82.007825 -364.55996) (xy 81.93418 -364.541968)
			(xy 81.862864 -364.51625) (xy 81.794687 -364.483098) (xy 81.730419 -364.442886) (xy 81.67079 -364.396071)
			(xy 81.616474 -364.343183) (xy 81.568088 -364.284821) (xy 81.52618 -364.221646) (xy 81.491224 -364.154375)
			(xy 81.463617 -364.08377) (xy 81.443671 -364.010629) (xy 81.431612 -363.935784) (xy 81.427577 -363.86008)
			(xy 80.311498 -363.86008) (xy 80.310994 -363.897986) (xy 80.302935 -363.973367) (xy 80.28691 -364.047465)
			(xy 80.2631 -364.11944) (xy 80.231774 -364.188476) (xy 80.193287 -364.253791) (xy 80.148076 -364.314646)
			(xy 80.096652 -364.37035) (xy 80.039599 -364.420272) (xy 79.977563 -364.463847) (xy 79.911246 -364.500582)
			(xy 79.8414 -364.530059) (xy 79.768817 -364.551945) (xy 79.694319 -364.565992) (xy 79.618749 -364.572041)
			(xy 79.542965 -364.570022) (xy 79.467825 -364.55996) (xy 79.39418 -364.541968) (xy 79.322864 -364.51625)
			(xy 79.254687 -364.483098) (xy 79.190419 -364.442886) (xy 79.13079 -364.396071) (xy 79.076474 -364.343183)
			(xy 79.028088 -364.284821) (xy 78.98618 -364.221646) (xy 78.951224 -364.154375) (xy 78.923617 -364.08377)
			(xy 78.903671 -364.010629) (xy 78.891612 -363.935784) (xy 78.887577 -363.86008) (xy 77.771498 -363.86008)
			(xy 77.770994 -363.897986) (xy 77.762935 -363.973367) (xy 77.74691 -364.047465) (xy 77.7231 -364.11944)
			(xy 77.691774 -364.188476) (xy 77.653287 -364.253791) (xy 77.608076 -364.314646) (xy 77.556652 -364.37035)
			(xy 77.499599 -364.420272) (xy 77.437563 -364.463847) (xy 77.371246 -364.500582) (xy 77.3014 -364.530059)
			(xy 77.228817 -364.551945) (xy 77.154319 -364.565992) (xy 77.078749 -364.572041) (xy 77.002965 -364.570022)
			(xy 76.927825 -364.55996) (xy 76.85418 -364.541968) (xy 76.782864 -364.51625) (xy 76.714687 -364.483098)
			(xy 76.650419 -364.442886) (xy 76.59079 -364.396071) (xy 76.536474 -364.343183) (xy 76.488088 -364.284821)
			(xy 76.44618 -364.221646) (xy 76.411224 -364.154375) (xy 76.383617 -364.08377) (xy 76.363671 -364.010629)
			(xy 76.351612 -363.935784) (xy 76.347577 -363.86008) (xy 75.231498 -363.86008) (xy 75.230994 -363.897986)
			(xy 75.222935 -363.973367) (xy 75.20691 -364.047465) (xy 75.1831 -364.11944) (xy 75.151774 -364.188476)
			(xy 75.113287 -364.253791) (xy 75.068076 -364.314646) (xy 75.016652 -364.37035) (xy 74.959599 -364.420272)
			(xy 74.897563 -364.463847) (xy 74.831246 -364.500582) (xy 74.7614 -364.530059) (xy 74.688817 -364.551945)
			(xy 74.614319 -364.565992) (xy 74.538749 -364.572041) (xy 74.462965 -364.570022) (xy 74.387825 -364.55996)
			(xy 74.31418 -364.541968) (xy 74.242864 -364.51625) (xy 74.174687 -364.483098) (xy 74.110419 -364.442886)
			(xy 74.05079 -364.396071) (xy 73.996474 -364.343183) (xy 73.948088 -364.284821) (xy 73.90618 -364.221646)
			(xy 73.871224 -364.154375) (xy 73.843617 -364.08377) (xy 73.823671 -364.010629) (xy 73.811612 -363.935784)
			(xy 73.807577 -363.86008) (xy 72.691498 -363.86008) (xy 72.690994 -363.897986) (xy 72.682935 -363.973367)
			(xy 72.66691 -364.047465) (xy 72.6431 -364.11944) (xy 72.611774 -364.188476) (xy 72.573287 -364.253791)
			(xy 72.528076 -364.314646) (xy 72.476652 -364.37035) (xy 72.419599 -364.420272) (xy 72.357563 -364.463847)
			(xy 72.291246 -364.500582) (xy 72.2214 -364.530059) (xy 72.148817 -364.551945) (xy 72.074319 -364.565992)
			(xy 71.998749 -364.572041) (xy 71.922965 -364.570022) (xy 71.847825 -364.55996) (xy 71.77418 -364.541968)
			(xy 71.702864 -364.51625) (xy 71.634687 -364.483098) (xy 71.570419 -364.442886) (xy 71.51079 -364.396071)
			(xy 71.456474 -364.343183) (xy 71.408088 -364.284821) (xy 71.36618 -364.221646) (xy 71.331224 -364.154375)
			(xy 71.303617 -364.08377) (xy 71.283671 -364.010629) (xy 71.271612 -363.935784) (xy 71.267577 -363.86008)
			(xy 70.151498 -363.86008) (xy 70.150994 -363.897986) (xy 70.142935 -363.973367) (xy 70.12691 -364.047465)
			(xy 70.1031 -364.11944) (xy 70.071774 -364.188476) (xy 70.033287 -364.253791) (xy 69.988076 -364.314646)
			(xy 69.936652 -364.37035) (xy 69.879599 -364.420272) (xy 69.817563 -364.463847) (xy 69.751246 -364.500582)
			(xy 69.6814 -364.530059) (xy 69.608817 -364.551945) (xy 69.534319 -364.565992) (xy 69.458749 -364.572041)
			(xy 69.382965 -364.570022) (xy 69.307825 -364.55996) (xy 69.23418 -364.541968) (xy 69.162864 -364.51625)
			(xy 69.094687 -364.483098) (xy 69.030419 -364.442886) (xy 68.97079 -364.396071) (xy 68.916474 -364.343183)
			(xy 68.868088 -364.284821) (xy 68.82618 -364.221646) (xy 68.791224 -364.154375) (xy 68.763617 -364.08377)
			(xy 68.743671 -364.010629) (xy 68.731612 -363.935784) (xy 68.727577 -363.86008) (xy 67.611498 -363.86008)
			(xy 67.610994 -363.897986) (xy 67.602935 -363.973367) (xy 67.58691 -364.047465) (xy 67.5631 -364.11944)
			(xy 67.531774 -364.188476) (xy 67.493287 -364.253791) (xy 67.448076 -364.314646) (xy 67.396652 -364.37035)
			(xy 67.339599 -364.420272) (xy 67.277563 -364.463847) (xy 67.211246 -364.500582) (xy 67.1414 -364.530059)
			(xy 67.068817 -364.551945) (xy 66.994319 -364.565992) (xy 66.918749 -364.572041) (xy 66.842965 -364.570022)
			(xy 66.767825 -364.55996) (xy 66.69418 -364.541968) (xy 66.622864 -364.51625) (xy 66.554687 -364.483098)
			(xy 66.490419 -364.442886) (xy 66.43079 -364.396071) (xy 66.376474 -364.343183) (xy 66.328088 -364.284821)
			(xy 66.28618 -364.221646) (xy 66.251224 -364.154375) (xy 66.223617 -364.08377) (xy 66.203671 -364.010629)
			(xy 66.191612 -363.935784) (xy 66.187577 -363.86008) (xy 65.071498 -363.86008) (xy 65.070994 -363.897986)
			(xy 65.062935 -363.973367) (xy 65.04691 -364.047465) (xy 65.0231 -364.11944) (xy 64.991774 -364.188476)
			(xy 64.953287 -364.253791) (xy 64.908076 -364.314646) (xy 64.856652 -364.37035) (xy 64.799599 -364.420272)
			(xy 64.737563 -364.463847) (xy 64.671246 -364.500582) (xy 64.6014 -364.530059) (xy 64.528817 -364.551945)
			(xy 64.454319 -364.565992) (xy 64.378749 -364.572041) (xy 64.302965 -364.570022) (xy 64.227825 -364.55996)
			(xy 64.15418 -364.541968) (xy 64.082864 -364.51625) (xy 64.014687 -364.483098) (xy 63.950419 -364.442886)
			(xy 63.89079 -364.396071) (xy 63.836474 -364.343183) (xy 63.788088 -364.284821) (xy 63.74618 -364.221646)
			(xy 63.711224 -364.154375) (xy 63.683617 -364.08377) (xy 63.663671 -364.010629) (xy 63.651612 -363.935784)
			(xy 63.647577 -363.86008) (xy 42.500813 -363.86008) (xy 42.479042 -363.876857) (xy 42.381609 -363.941665)
			(xy 42.279905 -363.99954) (xy 42.174422 -364.050202) (xy 42.065671 -364.093404) (xy 41.954179 -364.128939)
			(xy 41.840485 -364.156634) (xy 41.725141 -364.176354) (xy 41.608704 -364.188005) (xy 41.491739 -364.19153)
			(xy 41.374812 -364.186912) (xy 41.258489 -364.174173) (xy 41.143334 -364.153375) (xy 41.029905 -364.124618)
			(xy 40.91875 -364.088042) (xy 40.810407 -364.043825) (xy 40.705403 -363.992179) (xy 40.604244 -363.933356)
			(xy 40.507421 -363.86764) (xy 40.415403 -363.795349) (xy 40.328636 -363.716834) (xy 40.247539 -363.632474)
			(xy 40.172506 -363.542679) (xy 40.103899 -363.447883) (xy 40.042051 -363.348544) (xy 39.987262 -363.245145)
			(xy 39.939796 -363.138186) (xy 39.899884 -363.028185) (xy 39.86772 -362.915674) (xy 39.843457 -362.801199)
			(xy 39.827215 -362.685313) (xy 39.819072 -362.568579) (xy 39.818564 -362.51007) (xy 36.092815 -362.51007)
			(xy 36.140713 -362.546241) (xy 36.204933 -362.604785) (xy 36.263477 -362.669005) (xy 36.315846 -362.738352)
			(xy 36.361593 -362.812236) (xy 36.400327 -362.890025) (xy 36.431719 -362.971057) (xy 36.4555 -363.054639)
			(xy 36.471468 -363.140059) (xy 36.479486 -363.226588) (xy 36.479988 -363.270038) (xy 36.479486 -363.313488)
			(xy 36.471468 -363.400017) (xy 36.4555 -363.485437) (xy 36.431719 -363.569019) (xy 36.400327 -363.650051)
			(xy 36.361593 -363.72784) (xy 36.315846 -363.801724) (xy 36.263477 -363.871071) (xy 36.204933 -363.935291)
			(xy 36.140713 -363.993835) (xy 36.071366 -364.046204) (xy 35.997482 -364.091951) (xy 35.919693 -364.130685)
			(xy 35.838661 -364.162077) (xy 35.755079 -364.185858) (xy 35.669659 -364.201826) (xy 35.58313 -364.209844)
			(xy 35.49623 -364.209844) (xy 35.409701 -364.201826) (xy 35.324281 -364.185858) (xy 35.240699 -364.162077)
			(xy 35.159667 -364.130685) (xy 35.081878 -364.091951) (xy 35.007994 -364.046204) (xy 34.938647 -363.993835)
			(xy 34.874427 -363.935291) (xy 34.815883 -363.871071) (xy 34.763514 -363.801724) (xy 34.717767 -363.72784)
			(xy 34.679033 -363.650051) (xy 34.647641 -363.569019) (xy 34.62386 -363.485437) (xy 34.607892 -363.400017)
			(xy 34.599874 -363.313488) (xy 31.399486 -363.313488) (xy 31.391468 -363.400017) (xy 31.3755 -363.485437)
			(xy 31.351719 -363.569019) (xy 31.320327 -363.650051) (xy 31.281593 -363.72784) (xy 31.235846 -363.801724)
			(xy 31.183477 -363.871071) (xy 31.124933 -363.935291) (xy 31.060713 -363.993835) (xy 30.991366 -364.046204)
			(xy 30.917482 -364.091951) (xy 30.839693 -364.130685) (xy 30.758661 -364.162077) (xy 30.675079 -364.185858)
			(xy 30.589659 -364.201826) (xy 30.50313 -364.209844) (xy 30.41623 -364.209844) (xy 30.329701 -364.201826)
			(xy 30.244281 -364.185858) (xy 30.160699 -364.162077) (xy 30.079667 -364.130685) (xy 30.001878 -364.091951)
			(xy 29.927994 -364.046204) (xy 29.858647 -363.993835) (xy 29.794427 -363.935291) (xy 29.735883 -363.871071)
			(xy 29.683514 -363.801724) (xy 29.637767 -363.72784) (xy 29.599033 -363.650051) (xy 29.567641 -363.569019)
			(xy 29.54386 -363.485437) (xy 29.527892 -363.400017) (xy 29.519874 -363.313488) (xy 22.271736 -363.313488)
			(xy 22.271736 -364.246414) (xy 26.78633 -364.246414) (xy 26.790401 -364.190792) (xy 26.802527 -364.136355)
			(xy 26.82245 -364.084264) (xy 26.849746 -364.035629) (xy 26.883832 -363.991486) (xy 26.923981 -363.952777)
			(xy 26.969339 -363.920326) (xy 27.018939 -363.894825) (xy 27.071723 -363.876818) (xy 27.126566 -363.866688)
			(xy 27.1823 -363.864651) (xy 27.237737 -363.870751) (xy 27.291694 -363.884857) (xy 27.343023 -363.906669)
			(xy 27.390629 -363.935723) (xy 27.433497 -363.971398) (xy 27.470714 -364.012935) (xy 27.501487 -364.059448)
			(xy 27.525159 -364.109945) (xy 27.541227 -364.163352) (xy 27.549347 -364.218528) (xy 27.549856 -364.246414)
			(xy 27.549347 -364.2743) (xy 27.541227 -364.329476) (xy 27.525159 -364.382883) (xy 27.501487 -364.43338)
			(xy 27.470714 -364.479893) (xy 27.433497 -364.52143) (xy 27.390629 -364.557105) (xy 27.343023 -364.586159)
			(xy 27.291694 -364.607971) (xy 27.237737 -364.622077) (xy 27.1823 -364.628177) (xy 27.126566 -364.62614)
			(xy 27.071723 -364.61601) (xy 27.018939 -364.598003) (xy 26.969339 -364.572502) (xy 26.923981 -364.540051)
			(xy 26.883832 -364.501342) (xy 26.849746 -364.457199) (xy 26.82245 -364.408564) (xy 26.802527 -364.356473)
			(xy 26.790401 -364.302036) (xy 26.78633 -364.246414) (xy 22.271736 -364.246414) (xy 22.271736 -365.853488)
			(xy 29.519874 -365.853488) (xy 29.519874 -365.766588) (xy 29.527892 -365.680059) (xy 29.54386 -365.594639)
			(xy 29.567641 -365.511057) (xy 29.599033 -365.430025) (xy 29.637767 -365.352236) (xy 29.683514 -365.278352)
			(xy 29.735883 -365.209005) (xy 29.794427 -365.144785) (xy 29.858647 -365.086241) (xy 29.927994 -365.033872)
			(xy 30.001878 -364.988125) (xy 30.079667 -364.949391) (xy 30.160699 -364.917999) (xy 30.244281 -364.894218)
			(xy 30.329701 -364.87825) (xy 30.41623 -364.870232) (xy 30.50313 -364.870232) (xy 30.589659 -364.87825)
			(xy 30.675079 -364.894218) (xy 30.758661 -364.917999) (xy 30.839693 -364.949391) (xy 30.917482 -364.988125)
			(xy 30.991366 -365.033872) (xy 31.060713 -365.086241) (xy 31.124933 -365.144785) (xy 31.183477 -365.209005)
			(xy 31.235846 -365.278352) (xy 31.281593 -365.352236) (xy 31.320327 -365.430025) (xy 31.351719 -365.511057)
			(xy 31.3755 -365.594639) (xy 31.391468 -365.680059) (xy 31.399486 -365.766588) (xy 31.399988 -365.810038)
			(xy 31.399486 -365.853488) (xy 34.599874 -365.853488) (xy 34.599874 -365.766588) (xy 34.607892 -365.680059)
			(xy 34.62386 -365.594639) (xy 34.647641 -365.511057) (xy 34.679033 -365.430025) (xy 34.717767 -365.352236)
			(xy 34.763514 -365.278352) (xy 34.815883 -365.209005) (xy 34.874427 -365.144785) (xy 34.938647 -365.086241)
			(xy 35.007994 -365.033872) (xy 35.081878 -364.988125) (xy 35.159667 -364.949391) (xy 35.240699 -364.917999)
			(xy 35.324281 -364.894218) (xy 35.409701 -364.87825) (xy 35.49623 -364.870232) (xy 35.58313 -364.870232)
			(xy 35.669659 -364.87825) (xy 35.755079 -364.894218) (xy 35.838661 -364.917999) (xy 35.919693 -364.949391)
			(xy 35.997482 -364.988125) (xy 36.071366 -365.033872) (xy 36.140713 -365.086241) (xy 36.204933 -365.144785)
			(xy 36.263477 -365.209005) (xy 36.315846 -365.278352) (xy 36.361593 -365.352236) (xy 36.400327 -365.430025)
			(xy 36.431719 -365.511057) (xy 36.4555 -365.594639) (xy 36.471468 -365.680059) (xy 36.479486 -365.766588)
			(xy 36.479988 -365.810038) (xy 36.479486 -365.853488) (xy 36.471468 -365.940017) (xy 36.4555 -366.025437)
			(xy 36.431719 -366.109019) (xy 36.400327 -366.190051) (xy 36.361593 -366.26784) (xy 36.315846 -366.341724)
			(xy 36.263477 -366.411071) (xy 36.204933 -366.475291) (xy 36.140713 -366.533835) (xy 36.071366 -366.586204)
			(xy 35.997482 -366.631951) (xy 35.919693 -366.670685) (xy 35.838661 -366.702077) (xy 35.755079 -366.725858)
			(xy 35.669659 -366.741826) (xy 35.58313 -366.749844) (xy 35.49623 -366.749844) (xy 35.409701 -366.741826)
			(xy 35.324281 -366.725858) (xy 35.240699 -366.702077) (xy 35.159667 -366.670685) (xy 35.081878 -366.631951)
			(xy 35.007994 -366.586204) (xy 34.938647 -366.533835) (xy 34.874427 -366.475291) (xy 34.815883 -366.411071)
			(xy 34.763514 -366.341724) (xy 34.717767 -366.26784) (xy 34.679033 -366.190051) (xy 34.647641 -366.109019)
			(xy 34.62386 -366.025437) (xy 34.607892 -365.940017) (xy 34.599874 -365.853488) (xy 31.399486 -365.853488)
			(xy 31.391468 -365.940017) (xy 31.3755 -366.025437) (xy 31.351719 -366.109019) (xy 31.320327 -366.190051)
			(xy 31.281593 -366.26784) (xy 31.235846 -366.341724) (xy 31.183477 -366.411071) (xy 31.124933 -366.475291)
			(xy 31.060713 -366.533835) (xy 30.991366 -366.586204) (xy 30.917482 -366.631951) (xy 30.839693 -366.670685)
			(xy 30.758661 -366.702077) (xy 30.675079 -366.725858) (xy 30.589659 -366.741826) (xy 30.50313 -366.749844)
			(xy 30.41623 -366.749844) (xy 30.329701 -366.741826) (xy 30.244281 -366.725858) (xy 30.160699 -366.702077)
			(xy 30.079667 -366.670685) (xy 30.001878 -366.631951) (xy 29.927994 -366.586204) (xy 29.858647 -366.533835)
			(xy 29.794427 -366.475291) (xy 29.735883 -366.411071) (xy 29.683514 -366.341724) (xy 29.637767 -366.26784)
			(xy 29.599033 -366.190051) (xy 29.567641 -366.109019) (xy 29.54386 -366.025437) (xy 29.527892 -365.940017)
			(xy 29.519874 -365.853488) (xy 22.271736 -365.853488) (xy 22.271736 -366.928146) (xy 26.735784 -366.928146)
			(xy 26.739855 -366.872524) (xy 26.751981 -366.818087) (xy 26.771904 -366.765996) (xy 26.7992 -366.717361)
			(xy 26.833286 -366.673218) (xy 26.873435 -366.634509) (xy 26.918793 -366.602058) (xy 26.968393 -366.576557)
			(xy 27.021177 -366.55855) (xy 27.07602 -366.54842) (xy 27.131754 -366.546383) (xy 27.187191 -366.552483)
			(xy 27.241148 -366.566589) (xy 27.292477 -366.588401) (xy 27.340083 -366.617455) (xy 27.382951 -366.65313)
			(xy 27.420168 -366.694667) (xy 27.450941 -366.74118) (xy 27.474613 -366.791677) (xy 27.490681 -366.845084)
			(xy 27.498801 -366.90026) (xy 27.49931 -366.928146) (xy 27.498801 -366.956032) (xy 27.490681 -367.011208)
			(xy 27.474613 -367.064615) (xy 27.450941 -367.115112) (xy 27.420168 -367.161625) (xy 27.382951 -367.203162)
			(xy 27.340083 -367.238837) (xy 27.292477 -367.267891) (xy 27.241148 -367.289703) (xy 27.187191 -367.303809)
			(xy 27.131754 -367.309909) (xy 27.07602 -367.307872) (xy 27.021177 -367.297742) (xy 26.968393 -367.279735)
			(xy 26.918793 -367.254234) (xy 26.873435 -367.221783) (xy 26.833286 -367.183074) (xy 26.7992 -367.138931)
			(xy 26.771904 -367.090296) (xy 26.751981 -367.038205) (xy 26.739855 -366.983768) (xy 26.735784 -366.928146)
			(xy 22.271736 -366.928146) (xy 22.271736 -368.393488) (xy 29.519874 -368.393488) (xy 29.519874 -368.306588)
			(xy 29.527892 -368.220059) (xy 29.54386 -368.134639) (xy 29.567641 -368.051057) (xy 29.599033 -367.970025)
			(xy 29.637767 -367.892236) (xy 29.683514 -367.818352) (xy 29.735883 -367.749005) (xy 29.794427 -367.684785)
			(xy 29.858647 -367.626241) (xy 29.927994 -367.573872) (xy 30.001878 -367.528125) (xy 30.079667 -367.489391)
			(xy 30.160699 -367.457999) (xy 30.244281 -367.434218) (xy 30.329701 -367.41825) (xy 30.41623 -367.410232)
			(xy 30.50313 -367.410232) (xy 30.589659 -367.41825) (xy 30.675079 -367.434218) (xy 30.758661 -367.457999)
			(xy 30.839693 -367.489391) (xy 30.917482 -367.528125) (xy 30.991366 -367.573872) (xy 31.060713 -367.626241)
			(xy 31.124933 -367.684785) (xy 31.183477 -367.749005) (xy 31.235846 -367.818352) (xy 31.281593 -367.892236)
			(xy 31.320327 -367.970025) (xy 31.351719 -368.051057) (xy 31.3755 -368.134639) (xy 31.391468 -368.220059)
			(xy 31.399486 -368.306588) (xy 31.399988 -368.350038) (xy 31.399486 -368.393488) (xy 34.599874 -368.393488)
			(xy 34.599874 -368.306588) (xy 34.607892 -368.220059) (xy 34.62386 -368.134639) (xy 34.647641 -368.051057)
			(xy 34.679033 -367.970025) (xy 34.717767 -367.892236) (xy 34.763514 -367.818352) (xy 34.815883 -367.749005)
			(xy 34.874427 -367.684785) (xy 34.938647 -367.626241) (xy 35.007994 -367.573872) (xy 35.081878 -367.528125)
			(xy 35.159667 -367.489391) (xy 35.240699 -367.457999) (xy 35.324281 -367.434218) (xy 35.409701 -367.41825)
			(xy 35.49623 -367.410232) (xy 35.58313 -367.410232) (xy 35.669659 -367.41825) (xy 35.755079 -367.434218)
			(xy 35.838661 -367.457999) (xy 35.919693 -367.489391) (xy 35.997482 -367.528125) (xy 36.071366 -367.573872)
			(xy 36.140713 -367.626241) (xy 36.204933 -367.684785) (xy 36.263477 -367.749005) (xy 36.315846 -367.818352)
			(xy 36.361593 -367.892236) (xy 36.400327 -367.970025) (xy 36.431719 -368.051057) (xy 36.4555 -368.134639)
			(xy 36.471468 -368.220059) (xy 36.479486 -368.306588) (xy 36.479988 -368.350038) (xy 36.479486 -368.393488)
			(xy 36.471468 -368.480017) (xy 36.4555 -368.565437) (xy 36.451166 -368.58067) (xy 40.05275 -368.58067)
			(xy 40.056821 -368.525048) (xy 40.068947 -368.470611) (xy 40.08887 -368.41852) (xy 40.116166 -368.369885)
			(xy 40.150252 -368.325742) (xy 40.190401 -368.287033) (xy 40.235759 -368.254582) (xy 40.285359 -368.229081)
			(xy 40.338143 -368.211074) (xy 40.392986 -368.200944) (xy 40.44872 -368.198907) (xy 40.504157 -368.205007)
			(xy 40.558114 -368.219113) (xy 40.609443 -368.240925) (xy 40.657049 -368.269979) (xy 40.699917 -368.305654)
			(xy 40.737134 -368.347191) (xy 40.767907 -368.393704) (xy 40.791579 -368.444201) (xy 40.807647 -368.497608)
			(xy 40.815767 -368.552784) (xy 40.816276 -368.58067) (xy 40.815767 -368.608556) (xy 40.807647 -368.663732)
			(xy 40.791579 -368.717139) (xy 40.767907 -368.767636) (xy 40.737134 -368.814149) (xy 40.699917 -368.855686)
			(xy 40.657049 -368.891361) (xy 40.609443 -368.920415) (xy 40.558114 -368.942227) (xy 40.504157 -368.956333)
			(xy 40.44872 -368.962433) (xy 40.392986 -368.960396) (xy 40.338143 -368.950266) (xy 40.285359 -368.932259)
			(xy 40.235759 -368.906758) (xy 40.190401 -368.874307) (xy 40.150252 -368.835598) (xy 40.116166 -368.791455)
			(xy 40.08887 -368.74282) (xy 40.068947 -368.690729) (xy 40.056821 -368.636292) (xy 40.05275 -368.58067)
			(xy 36.451166 -368.58067) (xy 36.431719 -368.649019) (xy 36.400327 -368.730051) (xy 36.361593 -368.80784)
			(xy 36.315846 -368.881724) (xy 36.263477 -368.951071) (xy 36.204933 -369.015291) (xy 36.140713 -369.073835)
			(xy 36.071366 -369.126204) (xy 35.997482 -369.171951) (xy 35.919693 -369.210685) (xy 35.838661 -369.242077)
			(xy 35.755079 -369.265858) (xy 35.669659 -369.281826) (xy 35.58313 -369.289844) (xy 35.49623 -369.289844)
			(xy 35.409701 -369.281826) (xy 35.324281 -369.265858) (xy 35.240699 -369.242077) (xy 35.159667 -369.210685)
			(xy 35.081878 -369.171951) (xy 35.007994 -369.126204) (xy 34.938647 -369.073835) (xy 34.874427 -369.015291)
			(xy 34.815883 -368.951071) (xy 34.763514 -368.881724) (xy 34.717767 -368.80784) (xy 34.679033 -368.730051)
			(xy 34.647641 -368.649019) (xy 34.62386 -368.565437) (xy 34.607892 -368.480017) (xy 34.599874 -368.393488)
			(xy 31.399486 -368.393488) (xy 31.391468 -368.480017) (xy 31.3755 -368.565437) (xy 31.351719 -368.649019)
			(xy 31.320327 -368.730051) (xy 31.281593 -368.80784) (xy 31.235846 -368.881724) (xy 31.183477 -368.951071)
			(xy 31.124933 -369.015291) (xy 31.060713 -369.073835) (xy 30.991366 -369.126204) (xy 30.917482 -369.171951)
			(xy 30.839693 -369.210685) (xy 30.758661 -369.242077) (xy 30.675079 -369.265858) (xy 30.589659 -369.281826)
			(xy 30.50313 -369.289844) (xy 30.41623 -369.289844) (xy 30.329701 -369.281826) (xy 30.244281 -369.265858)
			(xy 30.160699 -369.242077) (xy 30.079667 -369.210685) (xy 30.001878 -369.171951) (xy 29.927994 -369.126204)
			(xy 29.858647 -369.073835) (xy 29.794427 -369.015291) (xy 29.735883 -368.951071) (xy 29.683514 -368.881724)
			(xy 29.637767 -368.80784) (xy 29.599033 -368.730051) (xy 29.567641 -368.649019) (xy 29.54386 -368.565437)
			(xy 29.527892 -368.480017) (xy 29.519874 -368.393488) (xy 22.271736 -368.393488) (xy 22.271736 -369.143534)
			(xy 23.807926 -369.143534) (xy 23.811997 -369.087912) (xy 23.824123 -369.033475) (xy 23.844046 -368.981384)
			(xy 23.871342 -368.932749) (xy 23.905428 -368.888606) (xy 23.945577 -368.849897) (xy 23.990935 -368.817446)
			(xy 24.040535 -368.791945) (xy 24.093319 -368.773938) (xy 24.148162 -368.763808) (xy 24.203896 -368.761771)
			(xy 24.259333 -368.767871) (xy 24.31329 -368.781977) (xy 24.364619 -368.803789) (xy 24.412225 -368.832843)
			(xy 24.455093 -368.868518) (xy 24.49231 -368.910055) (xy 24.523083 -368.956568) (xy 24.530952 -368.973354)
			(xy 26.797506 -368.973354) (xy 26.801577 -368.917732) (xy 26.813703 -368.863295) (xy 26.833626 -368.811204)
			(xy 26.860922 -368.762569) (xy 26.895008 -368.718426) (xy 26.935157 -368.679717) (xy 26.980515 -368.647266)
			(xy 27.030115 -368.621765) (xy 27.082899 -368.603758) (xy 27.137742 -368.593628) (xy 27.193476 -368.591591)
			(xy 27.248913 -368.597691) (xy 27.30287 -368.611797) (xy 27.354199 -368.633609) (xy 27.401805 -368.662663)
			(xy 27.444673 -368.698338) (xy 27.48189 -368.739875) (xy 27.512663 -368.786388) (xy 27.536335 -368.836885)
			(xy 27.552403 -368.890292) (xy 27.560523 -368.945468) (xy 27.561032 -368.973354) (xy 27.560523 -369.00124)
			(xy 27.552403 -369.056416) (xy 27.536335 -369.109823) (xy 27.512663 -369.16032) (xy 27.48189 -369.206833)
			(xy 27.444673 -369.24837) (xy 27.401805 -369.284045) (xy 27.354199 -369.313099) (xy 27.30287 -369.334911)
			(xy 27.248913 -369.349017) (xy 27.193476 -369.355117) (xy 27.137742 -369.35308) (xy 27.082899 -369.34295)
			(xy 27.030115 -369.324943) (xy 26.980515 -369.299442) (xy 26.935157 -369.266991) (xy 26.895008 -369.228282)
			(xy 26.860922 -369.184139) (xy 26.833626 -369.135504) (xy 26.813703 -369.083413) (xy 26.801577 -369.028976)
			(xy 26.797506 -368.973354) (xy 24.530952 -368.973354) (xy 24.546755 -369.007065) (xy 24.562823 -369.060472)
			(xy 24.570943 -369.115648) (xy 24.571452 -369.143534) (xy 24.570943 -369.17142) (xy 24.562823 -369.226596)
			(xy 24.546755 -369.280003) (xy 24.523083 -369.3305) (xy 24.49231 -369.377013) (xy 24.455093 -369.41855)
			(xy 24.412225 -369.454225) (xy 24.364619 -369.483279) (xy 24.31329 -369.505091) (xy 24.259333 -369.519197)
			(xy 24.203896 -369.525297) (xy 24.148162 -369.52326) (xy 24.093319 -369.51313) (xy 24.040535 -369.495123)
			(xy 23.990935 -369.469622) (xy 23.945577 -369.437171) (xy 23.905428 -369.398462) (xy 23.871342 -369.354319)
			(xy 23.844046 -369.305684) (xy 23.824123 -369.253593) (xy 23.811997 -369.199156) (xy 23.807926 -369.143534)
			(xy 22.271736 -369.143534) (xy 22.271736 -370.338096) (xy 23.656312 -371.722672) (xy 27.094909 -371.722672)
			(xy 27.096185 -371.659455) (xy 27.105702 -371.596946) (xy 27.123296 -371.536214) (xy 27.148667 -371.478297)
			(xy 27.181381 -371.424188) (xy 27.220878 -371.374811) (xy 27.266481 -371.331013) (xy 27.317411 -371.293541)
			(xy 27.372797 -371.263038) (xy 27.43169 -371.240025) (xy 27.493083 -371.224895) (xy 27.555925 -371.217909)
			(xy 27.619142 -371.219185) (xy 27.681652 -371.228701) (xy 27.712162 -371.237002) (xy 29.034232 -371.61978)
			(xy 29.364178 -371.61978) (xy 29.387067 -371.619363) (xy 29.432109 -371.611187) (xy 29.474958 -371.595076)
			(xy 29.514229 -371.571552) (xy 29.548652 -371.541376) (xy 29.577115 -371.505522) (xy 29.598697 -371.465151)
			(xy 29.6127 -371.421568) (xy 29.618671 -371.376181) (xy 29.616418 -371.330459) (xy 29.606013 -371.28588)
			(xy 29.59735 -371.264688) (xy 29.580545 -371.224763) (xy 29.55348 -371.142469) (xy 29.534101 -371.058034)
			(xy 29.522571 -370.972175) (xy 29.518989 -370.885619) (xy 29.523384 -370.799101) (xy 29.53572 -370.713353)
			(xy 29.555892 -370.629104) (xy 29.583728 -370.547068) (xy 29.618993 -370.467941) (xy 29.661388 -370.392394)
			(xy 29.710553 -370.321066) (xy 29.766071 -370.254564) (xy 29.827472 -370.193452) (xy 29.894234 -370.138247)
			(xy 29.965791 -370.089417) (xy 30.041537 -370.047378) (xy 30.120829 -370.012485) (xy 30.202995 -369.985034)
			(xy 30.287338 -369.965258) (xy 30.373142 -369.953325) (xy 30.45968 -369.949336) (xy 30.546218 -369.953325)
			(xy 30.632022 -369.965258) (xy 30.716365 -369.985034) (xy 30.798531 -370.012485) (xy 30.877823 -370.047378)
			(xy 30.953569 -370.089417) (xy 31.025126 -370.138247) (xy 31.091888 -370.193452) (xy 31.153289 -370.254564)
			(xy 31.208807 -370.321066) (xy 31.257972 -370.392394) (xy 31.300367 -370.467941) (xy 31.335632 -370.547068)
			(xy 31.363468 -370.629104) (xy 31.38364 -370.713353) (xy 31.395976 -370.799101) (xy 31.400371 -370.885619)
			(xy 31.39839 -370.933488) (xy 34.599874 -370.933488) (xy 34.599874 -370.846588) (xy 34.607892 -370.760059)
			(xy 34.62386 -370.674639) (xy 34.647641 -370.591057) (xy 34.679033 -370.510025) (xy 34.717767 -370.432236)
			(xy 34.763514 -370.358352) (xy 34.815883 -370.289005) (xy 34.874427 -370.224785) (xy 34.938647 -370.166241)
			(xy 35.007994 -370.113872) (xy 35.081878 -370.068125) (xy 35.159667 -370.029391) (xy 35.240699 -369.997999)
			(xy 35.324281 -369.974218) (xy 35.409701 -369.95825) (xy 35.49623 -369.950232) (xy 35.58313 -369.950232)
			(xy 35.669659 -369.95825) (xy 35.755079 -369.974218) (xy 35.838661 -369.997999) (xy 35.919693 -370.029391)
			(xy 35.997482 -370.068125) (xy 36.071366 -370.113872) (xy 36.140713 -370.166241) (xy 36.204933 -370.224785)
			(xy 36.263477 -370.289005) (xy 36.315846 -370.358352) (xy 36.361593 -370.432236) (xy 36.400327 -370.510025)
			(xy 36.431719 -370.591057) (xy 36.436287 -370.607111) (xy 74.013351 -370.607111) (xy 74.017238 -370.55275)
			(xy 74.028822 -370.499495) (xy 74.047868 -370.448431) (xy 74.073987 -370.400598) (xy 74.106649 -370.356969)
			(xy 74.145187 -370.318433) (xy 74.188818 -370.285774) (xy 74.236653 -370.259658) (xy 74.287718 -370.240615)
			(xy 74.340973 -370.229034) (xy 74.395334 -370.225151) (xy 74.449695 -370.229044) (xy 74.502948 -370.240635)
			(xy 74.55401 -370.259686) (xy 74.60184 -370.285812) (xy 74.62393 -370.301774) (xy 74.642942 -370.31537)
			(xy 74.684825 -370.336102) (xy 74.729793 -370.348828) (xy 74.77633 -370.353118) (xy 74.822867 -370.348828)
			(xy 74.867835 -370.336102) (xy 74.909718 -370.31537) (xy 74.92873 -370.301774) (xy 74.950834 -370.285841)
			(xy 74.998657 -370.259727) (xy 75.049709 -370.240685) (xy 75.102951 -370.229103) (xy 75.1573 -370.225216)
			(xy 75.211649 -370.229103) (xy 75.264891 -370.240685) (xy 75.315943 -370.259727) (xy 75.363765 -370.285841)
			(xy 75.407385 -370.318494) (xy 75.445913 -370.357023) (xy 75.478565 -370.400644) (xy 75.504677 -370.448467)
			(xy 75.523718 -370.499519) (xy 75.535298 -370.552762) (xy 75.539184 -370.607111) (xy 76.088891 -370.607111)
			(xy 76.092776 -370.552759) (xy 76.104358 -370.499513) (xy 76.123399 -370.448457) (xy 76.149513 -370.400631)
			(xy 76.182167 -370.357008) (xy 76.220698 -370.318477) (xy 76.264319 -370.285821) (xy 76.312144 -370.259705)
			(xy 76.363199 -370.240662) (xy 76.416445 -370.229078) (xy 76.470797 -370.225191) (xy 76.525149 -370.229078)
			(xy 76.578395 -370.24066) (xy 76.62945 -370.259703) (xy 76.677275 -370.285817) (xy 76.699364 -370.301774)
			(xy 76.718376 -370.31537) (xy 76.760259 -370.336102) (xy 76.805227 -370.348828) (xy 76.851764 -370.353118)
			(xy 76.898301 -370.348828) (xy 76.943269 -370.336102) (xy 76.985152 -370.31537) (xy 77.004164 -370.301774)
			(xy 77.02627 -370.285835) (xy 77.074097 -370.259711) (xy 77.125155 -370.24066) (xy 77.178405 -370.22907)
			(xy 77.232762 -370.225176) (xy 77.28712 -370.229059) (xy 77.340373 -370.240639) (xy 77.391435 -370.25968)
			(xy 77.439267 -370.285794) (xy 77.482895 -370.318451) (xy 77.521431 -370.356985) (xy 77.554091 -370.400611)
			(xy 77.580209 -370.448441) (xy 77.599254 -370.499502) (xy 77.610837 -370.552753) (xy 77.614724 -370.607111)
			(xy 77.614677 -370.607774) (xy 78.313094 -370.607774) (xy 78.316985 -370.553418) (xy 78.328574 -370.50017)
			(xy 78.347623 -370.449113) (xy 78.373744 -370.401288) (xy 78.406407 -370.357667) (xy 78.444946 -370.319139)
			(xy 78.488576 -370.286488) (xy 78.536409 -370.260379) (xy 78.587471 -370.241344) (xy 78.640722 -370.22977)
			(xy 78.695078 -370.225894) (xy 78.749433 -370.229793) (xy 78.80268 -370.241388) (xy 78.853734 -370.260444)
			(xy 78.901556 -370.286572) (xy 78.923642 -370.302536) (xy 78.942654 -370.316132) (xy 78.984537 -370.336864)
			(xy 79.029505 -370.34959) (xy 79.076042 -370.35388) (xy 79.122579 -370.34959) (xy 79.167547 -370.336864)
			(xy 79.20943 -370.316132) (xy 79.228442 -370.302536) (xy 79.250488 -370.28652) (xy 79.298313 -370.260401)
			(xy 79.349369 -370.241353) (xy 79.402616 -370.229765) (xy 79.456969 -370.225873) (xy 79.511324 -370.229757)
			(xy 79.564573 -370.241336) (xy 79.615631 -370.260375) (xy 79.663461 -370.286487) (xy 79.707087 -370.31914)
			(xy 79.745622 -370.35767) (xy 79.778282 -370.401291) (xy 79.804401 -370.449117) (xy 79.823448 -370.500173)
			(xy 79.835035 -370.55342) (xy 79.838927 -370.607774) (xy 79.835043 -370.662128) (xy 79.823463 -370.715377)
			(xy 79.804423 -370.766435) (xy 79.778311 -370.814264) (xy 79.745657 -370.85789) (xy 79.707127 -370.896425)
			(xy 79.663505 -370.929084) (xy 79.615679 -370.955203) (xy 79.564623 -370.974249) (xy 79.511376 -370.985836)
			(xy 79.457022 -370.989727) (xy 79.402668 -370.985842) (xy 79.349419 -370.974262) (xy 79.298361 -370.955221)
			(xy 79.250532 -370.929108) (xy 79.228442 -370.913152) (xy 79.20943 -370.899556) (xy 79.167547 -370.878824)
			(xy 79.122579 -370.866098) (xy 79.076042 -370.861808) (xy 79.029505 -370.866098) (xy 78.984537 -370.878824)
			(xy 78.942654 -370.899556) (xy 78.923642 -370.913152) (xy 78.901512 -370.929056) (xy 78.853686 -370.955178)
			(xy 78.802629 -370.974227) (xy 78.749381 -370.985815) (xy 78.695026 -370.989706) (xy 78.64067 -370.985822)
			(xy 78.58742 -370.974241) (xy 78.536361 -370.955199) (xy 78.488531 -370.929084) (xy 78.444906 -370.896427)
			(xy 78.406373 -370.857893) (xy 78.373716 -370.814268) (xy 78.347601 -370.766439) (xy 78.328559 -370.715379)
			(xy 78.316978 -370.662129) (xy 78.313094 -370.607774) (xy 77.614677 -370.607774) (xy 77.610834 -370.661468)
			(xy 77.599248 -370.714719) (xy 77.5802 -370.765779) (xy 77.554079 -370.813607) (xy 77.521417 -370.857232)
			(xy 77.482879 -370.895763) (xy 77.439248 -370.928417) (xy 77.391415 -370.954529) (xy 77.340352 -370.973567)
			(xy 77.287099 -370.985144) (xy 77.232741 -370.989024) (xy 77.178384 -370.985127) (xy 77.125134 -370.973534)
			(xy 77.074077 -370.95448) (xy 77.026252 -370.928353) (xy 77.004164 -370.91239) (xy 76.985152 -370.898794)
			(xy 76.943269 -370.878062) (xy 76.898301 -370.865336) (xy 76.851764 -370.861046) (xy 76.805227 -370.865336)
			(xy 76.760259 -370.878062) (xy 76.718376 -370.898794) (xy 76.699364 -370.91239) (xy 76.677294 -370.928371)
			(xy 76.629469 -370.954488) (xy 76.578415 -370.973534) (xy 76.52517 -370.985119) (xy 76.470818 -370.989009)
			(xy 76.416466 -370.985125) (xy 76.36322 -370.973544) (xy 76.312164 -370.954504) (xy 76.264337 -370.928391)
			(xy 76.220714 -370.895738) (xy 76.182181 -370.857208) (xy 76.149525 -370.813587) (xy 76.123408 -370.765763)
			(xy 76.104364 -370.714708) (xy 76.09278 -370.661463) (xy 76.088891 -370.607111) (xy 75.539184 -370.607111)
			(xy 75.535295 -370.661459) (xy 75.523712 -370.714701) (xy 75.504668 -370.765753) (xy 75.478553 -370.813575)
			(xy 75.445898 -370.857193) (xy 75.407368 -370.89572) (xy 75.363747 -370.928371) (xy 75.315923 -370.954482)
			(xy 75.26487 -370.973521) (xy 75.211627 -370.9851) (xy 75.157278 -370.988984) (xy 75.10293 -370.985094)
			(xy 75.049688 -370.973508) (xy 74.998637 -370.954464) (xy 74.950816 -370.928347) (xy 74.92873 -370.91239)
			(xy 74.909718 -370.898794) (xy 74.867835 -370.878062) (xy 74.822867 -370.865336) (xy 74.77633 -370.861046)
			(xy 74.729793 -370.865336) (xy 74.684825 -370.878062) (xy 74.642942 -370.898794) (xy 74.62393 -370.91239)
			(xy 74.601858 -370.928377) (xy 74.554029 -370.954505) (xy 74.502969 -370.973559) (xy 74.449716 -370.985153)
			(xy 74.395356 -370.989049) (xy 74.340994 -370.985169) (xy 74.287738 -370.973591) (xy 74.236672 -370.954551)
			(xy 74.188836 -370.928437) (xy 74.145203 -370.895781) (xy 74.106663 -370.857247) (xy 74.073999 -370.81362)
			(xy 74.047877 -370.765788) (xy 74.028828 -370.714726) (xy 74.017241 -370.661472) (xy 74.013351 -370.607111)
			(xy 36.436287 -370.607111) (xy 36.4555 -370.674639) (xy 36.471468 -370.760059) (xy 36.479486 -370.846588)
			(xy 36.479988 -370.890038) (xy 36.479486 -370.933488) (xy 36.471468 -371.020017) (xy 36.4555 -371.105437)
			(xy 36.431719 -371.189019) (xy 36.400327 -371.270051) (xy 36.361593 -371.34784) (xy 36.315846 -371.421724)
			(xy 36.263477 -371.491071) (xy 36.204933 -371.555291) (xy 36.140713 -371.613835) (xy 36.071366 -371.666204)
			(xy 35.997482 -371.711951) (xy 35.919693 -371.750685) (xy 35.838661 -371.782077) (xy 35.755079 -371.805858)
			(xy 35.669659 -371.821826) (xy 35.58313 -371.829844) (xy 35.49623 -371.829844) (xy 35.409701 -371.821826)
			(xy 35.324281 -371.805858) (xy 35.240699 -371.782077) (xy 35.159667 -371.750685) (xy 35.081878 -371.711951)
			(xy 35.007994 -371.666204) (xy 34.938647 -371.613835) (xy 34.874427 -371.555291) (xy 34.815883 -371.491071)
			(xy 34.763514 -371.421724) (xy 34.717767 -371.34784) (xy 34.679033 -371.270051) (xy 34.647641 -371.189019)
			(xy 34.62386 -371.105437) (xy 34.607892 -371.020017) (xy 34.599874 -370.933488) (xy 31.39839 -370.933488)
			(xy 31.396789 -370.972175) (xy 31.385259 -371.058034) (xy 31.36588 -371.142469) (xy 31.338815 -371.224763)
			(xy 31.32201 -371.264688) (xy 31.313382 -371.285895) (xy 31.302955 -371.33047) (xy 31.300684 -371.376191)
			(xy 31.306643 -371.421579) (xy 31.320639 -371.465165) (xy 31.342219 -371.505537) (xy 31.370684 -371.541388)
			(xy 31.405113 -371.571559) (xy 31.444391 -371.595071) (xy 31.487247 -371.611165) (xy 31.532293 -371.619318)
			(xy 31.555182 -371.61978) (xy 32.190436 -371.61978) (xy 32.934232 -372.363672) (xy 74.013402 -372.363672)
			(xy 74.017294 -372.309319) (xy 74.028882 -372.256073) (xy 74.04793 -372.205018) (xy 74.074051 -372.157194)
			(xy 74.106712 -372.113574) (xy 74.14525 -372.075047) (xy 74.188878 -372.042397) (xy 74.236709 -372.016289)
			(xy 74.287769 -371.997254) (xy 74.341018 -371.98568) (xy 74.395373 -371.981802) (xy 74.449726 -371.9857)
			(xy 74.502971 -371.997295) (xy 74.554023 -372.016349) (xy 74.601844 -372.042475) (xy 74.62393 -372.058438)
			(xy 74.642942 -372.072034) (xy 74.684825 -372.092766) (xy 74.729793 -372.105492) (xy 74.77633 -372.109782)
			(xy 74.822867 -372.105492) (xy 74.867835 -372.092766) (xy 74.909718 -372.072034) (xy 74.92873 -372.058438)
			(xy 74.950774 -372.042419) (xy 74.9986 -372.016297) (xy 75.049657 -371.997247) (xy 75.102906 -371.985658)
			(xy 75.157261 -371.981765) (xy 75.211618 -371.985647) (xy 75.264869 -371.997225) (xy 75.315929 -372.016265)
			(xy 75.363761 -372.042377) (xy 75.407389 -372.075031) (xy 75.445926 -372.113561) (xy 75.478587 -372.157184)
			(xy 75.504708 -372.20501) (xy 75.523756 -372.256068) (xy 75.535344 -372.309317) (xy 75.539235 -372.363672)
			(xy 76.088942 -372.363672) (xy 76.092833 -372.309328) (xy 76.104418 -372.25609) (xy 76.123462 -372.205043)
			(xy 76.149577 -372.157226) (xy 76.182231 -372.113613) (xy 76.22076 -372.07509) (xy 76.264379 -372.042443)
			(xy 76.312201 -372.016336) (xy 76.363251 -371.9973) (xy 76.41649 -371.985724) (xy 76.470835 -371.981842)
			(xy 76.52518 -371.985734) (xy 76.578417 -371.99732) (xy 76.629463 -372.016365) (xy 76.67728 -372.042481)
			(xy 76.699364 -372.058438) (xy 76.718376 -372.072034) (xy 76.760259 -372.092766) (xy 76.805227 -372.105492)
			(xy 76.851764 -372.109782) (xy 76.898301 -372.105492) (xy 76.943269 -372.092766) (xy 76.985152 -372.072034)
			(xy 77.004164 -372.058438) (xy 77.02621 -372.042413) (xy 77.074041 -372.016281) (xy 77.125104 -371.997222)
			(xy 77.17836 -371.985625) (xy 77.232724 -371.981725) (xy 77.28709 -371.985603) (xy 77.34035 -371.997179)
			(xy 77.391421 -372.016217) (xy 77.439262 -372.042331) (xy 77.4829 -372.074987) (xy 77.521445 -372.113522)
			(xy 77.554113 -372.157151) (xy 77.58024 -372.204985) (xy 77.599292 -372.25605) (xy 77.610882 -372.309308)
			(xy 77.614775 -372.363672) (xy 77.614716 -372.364495) (xy 78.313065 -372.364495) (xy 78.316954 -372.310136)
			(xy 78.32854 -372.256883) (xy 78.347587 -372.205821) (xy 78.373708 -372.15799) (xy 78.406371 -372.114364)
			(xy 78.444911 -372.075831) (xy 78.488542 -372.043175) (xy 78.536377 -372.017062) (xy 78.587442 -371.998022)
			(xy 78.640696 -371.986445) (xy 78.695057 -371.982565) (xy 78.749416 -371.986461) (xy 78.802667 -371.998054)
			(xy 78.853726 -372.017109) (xy 78.901553 -372.043236) (xy 78.923642 -372.0592) (xy 78.942654 -372.072796)
			(xy 78.984537 -372.093528) (xy 79.029505 -372.106254) (xy 79.076042 -372.110544) (xy 79.122579 -372.106254)
			(xy 79.167547 -372.093528) (xy 79.20943 -372.072796) (xy 79.228442 -372.0592) (xy 79.250522 -372.043233)
			(xy 79.298345 -372.017118) (xy 79.349398 -371.998075) (xy 79.402641 -371.986491) (xy 79.456991 -371.982602)
			(xy 79.511341 -371.986488) (xy 79.564585 -371.998069) (xy 79.615639 -372.01711) (xy 79.663463 -372.043223)
			(xy 79.707085 -372.075876) (xy 79.745615 -372.114405) (xy 79.778269 -372.158025) (xy 79.804384 -372.205849)
			(xy 79.823427 -372.256902) (xy 79.83501 -372.310145) (xy 79.838898 -372.364495) (xy 79.835011 -372.418845)
			(xy 79.823429 -372.472089) (xy 79.804388 -372.523143) (xy 79.778275 -372.570967) (xy 79.745621 -372.614588)
			(xy 79.707092 -372.653117) (xy 79.663471 -372.685772) (xy 79.615648 -372.711886) (xy 79.564594 -372.730928)
			(xy 79.511351 -372.74251) (xy 79.457001 -372.746398) (xy 79.402651 -372.742511) (xy 79.349407 -372.730928)
			(xy 79.298354 -372.711886) (xy 79.25053 -372.685772) (xy 79.228442 -372.669816) (xy 79.20943 -372.65622)
			(xy 79.167547 -372.635488) (xy 79.122579 -372.622762) (xy 79.076042 -372.618472) (xy 79.029505 -372.622762)
			(xy 78.984537 -372.635488) (xy 78.942654 -372.65622) (xy 78.923642 -372.669816) (xy 78.901545 -372.685769)
			(xy 78.853717 -372.711895) (xy 78.802658 -372.730948) (xy 78.749406 -372.74254) (xy 78.695047 -372.746435)
			(xy 78.640687 -372.742554) (xy 78.587433 -372.730975) (xy 78.536368 -372.711934) (xy 78.488534 -372.68582)
			(xy 78.444903 -372.653163) (xy 78.406365 -372.614629) (xy 78.373703 -372.571002) (xy 78.347583 -372.52317)
			(xy 78.328537 -372.472108) (xy 78.316952 -372.418855) (xy 78.313065 -372.364495) (xy 77.614716 -372.364495)
			(xy 77.61089 -372.418038) (xy 77.599308 -372.471297) (xy 77.580263 -372.522365) (xy 77.554143 -372.570203)
			(xy 77.521481 -372.613836) (xy 77.482941 -372.652377) (xy 77.439308 -372.68504) (xy 77.391471 -372.71116)
			(xy 77.340403 -372.730206) (xy 77.287144 -372.741789) (xy 77.232779 -372.745675) (xy 77.178414 -372.741783)
			(xy 77.125157 -372.730194) (xy 77.074091 -372.711142) (xy 77.026256 -372.685017) (xy 77.004164 -372.669054)
			(xy 76.985152 -372.655458) (xy 76.943269 -372.634726) (xy 76.898301 -372.622) (xy 76.851764 -372.61771)
			(xy 76.805227 -372.622) (xy 76.760259 -372.634726) (xy 76.718376 -372.655458) (xy 76.699364 -372.669054)
			(xy 76.677234 -372.684949) (xy 76.629413 -372.711058) (xy 76.578364 -372.730095) (xy 76.525125 -372.741674)
			(xy 76.47078 -372.745558) (xy 76.416435 -372.741668) (xy 76.363198 -372.730084) (xy 76.31215 -372.711041)
			(xy 76.264333 -372.684927) (xy 76.220718 -372.652274) (xy 76.182195 -372.613746) (xy 76.149547 -372.570127)
			(xy 76.123439 -372.522306) (xy 76.104402 -372.471257) (xy 76.092825 -372.418017) (xy 76.088942 -372.363672)
			(xy 75.539235 -372.363672) (xy 75.535352 -372.418029) (xy 75.523772 -372.471279) (xy 75.504731 -372.522339)
			(xy 75.478617 -372.57017) (xy 75.445962 -372.613797) (xy 75.407431 -372.652333) (xy 75.363807 -372.684993)
			(xy 75.31598 -372.711112) (xy 75.264921 -372.730159) (xy 75.211673 -372.741745) (xy 75.157317 -372.745635)
			(xy 75.10296 -372.74175) (xy 75.04971 -372.730168) (xy 74.998651 -372.711126) (xy 74.950821 -372.685011)
			(xy 74.92873 -372.669054) (xy 74.909718 -372.655458) (xy 74.867835 -372.634726) (xy 74.822867 -372.622)
			(xy 74.77633 -372.61771) (xy 74.729793 -372.622) (xy 74.684825 -372.634726) (xy 74.642942 -372.655458)
			(xy 74.62393 -372.669054) (xy 74.601798 -372.684954) (xy 74.553973 -372.711074) (xy 74.502918 -372.730121)
			(xy 74.449671 -372.741707) (xy 74.395317 -372.745598) (xy 74.340964 -372.741712) (xy 74.287716 -372.730131)
			(xy 74.236659 -372.711089) (xy 74.188831 -372.684973) (xy 74.145208 -372.652317) (xy 74.106676 -372.613784)
			(xy 74.074021 -372.57016) (xy 74.047907 -372.522332) (xy 74.028866 -372.471274) (xy 74.017286 -372.418026)
			(xy 74.013402 -372.363672) (xy 32.934232 -372.363672) (xy 34.165794 -373.595392) (xy 34.182346 -373.611251)
			(xy 34.220043 -373.637325) (xy 34.261805 -373.656216) (xy 34.306278 -373.66731) (xy 34.352019 -373.670248)
			(xy 34.397546 -373.664936) (xy 34.441382 -373.651544) (xy 34.482106 -373.630508) (xy 34.518396 -373.602509)
			(xy 34.549077 -373.568455) (xy 34.573152 -373.529452) (xy 34.589842 -373.486763) (xy 34.598606 -373.441772)
			(xy 34.599372 -373.418862) (xy 34.600387 -373.37527) (xy 34.609496 -373.288545) (xy 34.626596 -373.203035)
			(xy 34.65154 -373.119477) (xy 34.684114 -373.038587) (xy 34.724037 -372.96106) (xy 34.770967 -372.887563)
			(xy 34.8245 -372.818727) (xy 34.884177 -372.755143) (xy 34.949485 -372.697358) (xy 35.019862 -372.645867)
			(xy 35.094705 -372.601115) (xy 35.17337 -372.563484) (xy 35.255181 -372.533298) (xy 35.339435 -372.510817)
			(xy 35.42541 -372.496233) (xy 35.512365 -372.489673) (xy 35.599554 -372.491192) (xy 35.686228 -372.500777)
			(xy 35.771642 -372.518346) (xy 35.855062 -372.543748) (xy 35.935772 -372.576765) (xy 36.013079 -372.617113)
			(xy 36.086317 -372.664446) (xy 36.154859 -372.718356) (xy 36.218114 -372.778381) (xy 36.27554 -372.844005)
			(xy 36.326643 -372.914664) (xy 36.370985 -372.989751) (xy 36.408183 -373.068621) (xy 36.437919 -373.150597)
			(xy 36.459938 -373.234973) (xy 36.474049 -373.321026) (xy 36.480132 -373.408016) (xy 36.478135 -373.495196)
			(xy 36.468074 -373.581816) (xy 36.450037 -373.667132) (xy 36.424177 -373.750412) (xy 36.390718 -373.830939)
			(xy 36.370768 -373.869712) (xy 36.360914 -373.889158) (xy 36.347402 -373.930604) (xy 36.341158 -373.973747)
			(xy 36.342368 -374.017324) (xy 36.350994 -374.060055) (xy 36.366784 -374.100688) (xy 36.389275 -374.138031)
			(xy 36.417808 -374.170989) (xy 36.451545 -374.198596) (xy 36.489498 -374.220042) (xy 36.530553 -374.234698)
			(xy 36.573507 -374.242135) (xy 36.595304 -374.242584) (xy 38.019736 -374.242584) (xy 38.03637 -374.242014)
			(xy 38.068487 -374.233331) (xy 38.097269 -374.216644) (xy 38.109398 -374.205246) (xy 38.419024 -373.89562)
			(xy 42.417746 -373.89562) (xy 42.999829 -374.477703) (xy 47.298092 -374.477703) (xy 47.298092 -374.396593)
			(xy 47.306042 -374.315874) (xy 47.321865 -374.236323) (xy 47.34541 -374.158707) (xy 47.376449 -374.083771)
			(xy 47.414684 -374.012239) (xy 47.459746 -373.944799) (xy 47.511201 -373.8821) (xy 47.568554 -373.824747)
			(xy 47.631253 -373.773292) (xy 47.698693 -373.72823) (xy 47.770225 -373.689995) (xy 47.845161 -373.658956)
			(xy 47.922777 -373.635411) (xy 48.002328 -373.619588) (xy 48.083047 -373.611638) (xy 48.164157 -373.611638)
			(xy 48.244876 -373.619588) (xy 48.324427 -373.635411) (xy 48.402043 -373.658956) (xy 48.476979 -373.689995)
			(xy 48.548511 -373.72823) (xy 48.615951 -373.773292) (xy 48.67865 -373.824747) (xy 48.736003 -373.8821)
			(xy 48.787458 -373.944799) (xy 48.83252 -374.012239) (xy 48.870755 -374.083771) (xy 48.901794 -374.158707)
			(xy 48.925339 -374.236323) (xy 48.941162 -374.315874) (xy 48.949112 -374.396593) (xy 48.94961 -374.437148)
			(xy 48.949112 -374.477703) (xy 50.798212 -374.477703) (xy 50.798212 -374.396593) (xy 50.806162 -374.315874)
			(xy 50.821985 -374.236323) (xy 50.84553 -374.158707) (xy 50.876569 -374.083771) (xy 50.914804 -374.012239)
			(xy 50.959866 -373.944799) (xy 51.011321 -373.8821) (xy 51.068674 -373.824747) (xy 51.131373 -373.773292)
			(xy 51.198813 -373.72823) (xy 51.270345 -373.689995) (xy 51.345281 -373.658956) (xy 51.422897 -373.635411)
			(xy 51.502448 -373.619588) (xy 51.583167 -373.611638) (xy 51.664277 -373.611638) (xy 51.744996 -373.619588)
			(xy 51.824547 -373.635411) (xy 51.902163 -373.658956) (xy 51.977099 -373.689995) (xy 52.048631 -373.72823)
			(xy 52.116071 -373.773292) (xy 52.17877 -373.824747) (xy 52.236123 -373.8821) (xy 52.287578 -373.944799)
			(xy 52.33264 -374.012239) (xy 52.370875 -374.083771) (xy 52.390143 -374.13029) (xy 74.013378 -374.13029)
			(xy 74.017268 -374.075933) (xy 74.028854 -374.022683) (xy 74.047901 -373.971624) (xy 74.074021 -373.923796)
			(xy 74.106683 -373.880172) (xy 74.14522 -373.84164) (xy 74.18885 -373.808986) (xy 74.236683 -373.782874)
			(xy 74.287745 -373.763836) (xy 74.340997 -373.752259) (xy 74.395355 -373.748378) (xy 74.449711 -373.752274)
			(xy 74.50296 -373.763867) (xy 74.554017 -373.78292) (xy 74.601842 -373.809045) (xy 74.62393 -373.825008)
			(xy 74.642942 -373.838604) (xy 74.684825 -373.859336) (xy 74.729793 -373.872062) (xy 74.77633 -373.876352)
			(xy 74.822867 -373.872062) (xy 74.867835 -373.859336) (xy 74.909718 -373.838604) (xy 74.92873 -373.825008)
			(xy 74.950802 -373.809029) (xy 74.998627 -373.782911) (xy 75.049681 -373.763865) (xy 75.102927 -373.752279)
			(xy 75.157279 -373.748389) (xy 75.211632 -373.752273) (xy 75.264879 -373.763854) (xy 75.315936 -373.782894)
			(xy 75.363763 -373.809007) (xy 75.407387 -373.84166) (xy 75.44592 -373.88019) (xy 75.478577 -373.923812)
			(xy 75.504694 -373.971637) (xy 75.523738 -374.022692) (xy 75.535323 -374.075938) (xy 75.539211 -374.13029)
			(xy 76.088918 -374.13029) (xy 76.092806 -374.075942) (xy 76.10439 -374.022701) (xy 76.123433 -373.97165)
			(xy 76.149547 -373.923829) (xy 76.182201 -373.880211) (xy 76.220731 -373.841684) (xy 76.264351 -373.809033)
			(xy 76.312174 -373.782922) (xy 76.363227 -373.763882) (xy 76.416469 -373.752303) (xy 76.470817 -373.748418)
			(xy 76.525165 -373.752307) (xy 76.578406 -373.763892) (xy 76.629457 -373.782936) (xy 76.677278 -373.809051)
			(xy 76.699364 -373.825008) (xy 76.718376 -373.838604) (xy 76.760259 -373.859336) (xy 76.805227 -373.872062)
			(xy 76.851764 -373.876352) (xy 76.898301 -373.872062) (xy 76.943269 -373.859336) (xy 76.985152 -373.838604)
			(xy 77.004164 -373.825008) (xy 77.026238 -373.809023) (xy 77.074067 -373.782895) (xy 77.125128 -373.76384)
			(xy 77.178381 -373.752246) (xy 77.232742 -373.748349) (xy 77.287104 -373.752229) (xy 77.340361 -373.763807)
			(xy 77.391427 -373.782847) (xy 77.439264 -373.808961) (xy 77.482897 -373.841617) (xy 77.521439 -373.880151)
			(xy 77.554103 -373.923779) (xy 77.580225 -373.971611) (xy 77.599274 -374.022674) (xy 77.610861 -374.075929)
			(xy 77.614751 -374.13029) (xy 77.614692 -374.131113) (xy 78.313041 -374.131113) (xy 78.316927 -374.07675)
			(xy 78.328512 -374.023493) (xy 78.347558 -373.972427) (xy 78.373678 -373.924592) (xy 78.406341 -373.880962)
			(xy 78.444881 -373.842425) (xy 78.488514 -373.809765) (xy 78.536351 -373.783647) (xy 78.587418 -373.764604)
			(xy 78.640675 -373.753024) (xy 78.695039 -373.749141) (xy 78.749401 -373.753035) (xy 78.802657 -373.764626)
			(xy 78.85372 -373.78368) (xy 78.901551 -373.809807) (xy 78.923642 -373.82577) (xy 78.942654 -373.839366)
			(xy 78.984537 -373.860098) (xy 79.029505 -373.872824) (xy 79.076042 -373.877114) (xy 79.122579 -373.872824)
			(xy 79.167547 -373.860098) (xy 79.20943 -373.839366) (xy 79.228442 -373.82577) (xy 79.25055 -373.809843)
			(xy 79.298371 -373.783732) (xy 79.349422 -373.764692) (xy 79.402662 -373.753112) (xy 79.457009 -373.749226)
			(xy 79.511356 -373.753115) (xy 79.564596 -373.764698) (xy 79.615645 -373.78374) (xy 79.663465 -373.809853)
			(xy 79.707082 -373.842506) (xy 79.745608 -373.881034) (xy 79.778259 -373.924653) (xy 79.80437 -373.972475)
			(xy 79.823409 -374.023526) (xy 79.834989 -374.076766) (xy 79.838874 -374.131113) (xy 79.834985 -374.18546)
			(xy 79.823401 -374.2387) (xy 79.804359 -374.289749) (xy 79.778245 -374.337569) (xy 79.745591 -374.381186)
			(xy 79.707062 -374.419711) (xy 79.663443 -374.452361) (xy 79.615621 -374.478471) (xy 79.56457 -374.49751)
			(xy 79.511329 -374.509089) (xy 79.456983 -374.512974) (xy 79.402636 -374.509084) (xy 79.349396 -374.4975)
			(xy 79.298347 -374.478457) (xy 79.250528 -374.452342) (xy 79.228442 -374.436386) (xy 79.20943 -374.42279)
			(xy 79.167547 -374.402058) (xy 79.122579 -374.389332) (xy 79.076042 -374.385042) (xy 79.029505 -374.389332)
			(xy 78.984537 -374.402058) (xy 78.942654 -374.42279) (xy 78.923642 -374.436386) (xy 78.901573 -374.452379)
			(xy 78.853744 -374.478509) (xy 78.802682 -374.497566) (xy 78.749428 -374.509162) (xy 78.695065 -374.513059)
			(xy 78.640701 -374.50918) (xy 78.587443 -374.497603) (xy 78.536375 -374.478564) (xy 78.488536 -374.45245)
			(xy 78.444901 -374.419793) (xy 78.406359 -374.381258) (xy 78.373693 -374.33763) (xy 78.347569 -374.289797)
			(xy 78.328519 -374.238732) (xy 78.316931 -374.185476) (xy 78.313041 -374.131113) (xy 77.614692 -374.131113)
			(xy 77.610864 -374.184652) (xy 77.599279 -374.237907) (xy 77.580233 -374.288971) (xy 77.554113 -374.336805)
			(xy 77.521451 -374.380434) (xy 77.482912 -374.41897) (xy 77.43928 -374.451629) (xy 77.391445 -374.477745)
			(xy 77.340379 -374.496788) (xy 77.287123 -374.508368) (xy 77.232761 -374.512251) (xy 77.1784 -374.508357)
			(xy 77.125146 -374.496766) (xy 77.074084 -374.477713) (xy 77.026254 -374.451587) (xy 77.004164 -374.435624)
			(xy 76.985152 -374.422028) (xy 76.943269 -374.401296) (xy 76.898301 -374.38857) (xy 76.851764 -374.38428)
			(xy 76.805227 -374.38857) (xy 76.760259 -374.401296) (xy 76.718376 -374.422028) (xy 76.699364 -374.435624)
			(xy 76.677262 -374.451559) (xy 76.62944 -374.477672) (xy 76.578388 -374.496713) (xy 76.525146 -374.508295)
			(xy 76.470798 -374.512182) (xy 76.41645 -374.508295) (xy 76.363208 -374.496712) (xy 76.312157 -374.477671)
			(xy 76.264335 -374.451557) (xy 76.220716 -374.418904) (xy 76.182189 -374.380375) (xy 76.149537 -374.336755)
			(xy 76.123425 -374.288933) (xy 76.104384 -374.237881) (xy 76.092804 -374.184639) (xy 76.088918 -374.13029)
			(xy 75.539211 -374.13029) (xy 75.535325 -374.184643) (xy 75.523743 -374.23789) (xy 75.504702 -374.288946)
			(xy 75.478587 -374.336772) (xy 75.445932 -374.380395) (xy 75.407401 -374.418927) (xy 75.363779 -374.451583)
			(xy 75.315953 -374.477698) (xy 75.264897 -374.496741) (xy 75.211651 -374.508324) (xy 75.157299 -374.512211)
			(xy 75.102946 -374.508324) (xy 75.0497 -374.49674) (xy 74.998644 -374.477697) (xy 74.950819 -374.451581)
			(xy 74.92873 -374.435624) (xy 74.909718 -374.422028) (xy 74.867835 -374.401296) (xy 74.822867 -374.38857)
			(xy 74.77633 -374.38428) (xy 74.729793 -374.38857) (xy 74.684825 -374.401296) (xy 74.642942 -374.422028)
			(xy 74.62393 -374.435624) (xy 74.601826 -374.451565) (xy 74.553999 -374.477688) (xy 74.502942 -374.496739)
			(xy 74.449692 -374.508329) (xy 74.395336 -374.512222) (xy 74.340978 -374.508339) (xy 74.287726 -374.496759)
			(xy 74.236665 -374.477718) (xy 74.188834 -374.451603) (xy 74.145206 -374.418947) (xy 74.10667 -374.380414)
			(xy 74.074011 -374.336788) (xy 74.047893 -374.288958) (xy 74.028848 -374.237898) (xy 74.017265 -374.184648)
			(xy 74.013378 -374.13029) (xy 52.390143 -374.13029) (xy 52.401914 -374.158707) (xy 52.425459 -374.236323)
			(xy 52.441282 -374.315874) (xy 52.449232 -374.396593) (xy 52.44973 -374.437148) (xy 52.449232 -374.477703)
			(xy 52.441282 -374.558422) (xy 52.425459 -374.637973) (xy 52.401914 -374.715589) (xy 52.370875 -374.790525)
			(xy 52.33264 -374.862057) (xy 52.287578 -374.929497) (xy 52.236123 -374.992196) (xy 52.17877 -375.049549)
			(xy 52.116071 -375.101004) (xy 52.048631 -375.146066) (xy 51.977099 -375.184301) (xy 51.902163 -375.21534)
			(xy 51.824547 -375.238885) (xy 51.744996 -375.254708) (xy 51.664277 -375.262658) (xy 51.583167 -375.262658)
			(xy 51.502448 -375.254708) (xy 51.422897 -375.238885) (xy 51.345281 -375.21534) (xy 51.270345 -375.184301)
			(xy 51.198813 -375.146066) (xy 51.131373 -375.101004) (xy 51.068674 -375.049549) (xy 51.011321 -374.992196)
			(xy 50.959866 -374.929497) (xy 50.914804 -374.862057) (xy 50.876569 -374.790525) (xy 50.84553 -374.715589)
			(xy 50.821985 -374.637973) (xy 50.806162 -374.558422) (xy 50.798212 -374.477703) (xy 48.949112 -374.477703)
			(xy 48.941162 -374.558422) (xy 48.925339 -374.637973) (xy 48.901794 -374.715589) (xy 48.870755 -374.790525)
			(xy 48.83252 -374.862057) (xy 48.787458 -374.929497) (xy 48.736003 -374.992196) (xy 48.67865 -375.049549)
			(xy 48.615951 -375.101004) (xy 48.548511 -375.146066) (xy 48.476979 -375.184301) (xy 48.402043 -375.21534)
			(xy 48.324427 -375.238885) (xy 48.244876 -375.254708) (xy 48.164157 -375.262658) (xy 48.083047 -375.262658)
			(xy 48.002328 -375.254708) (xy 47.922777 -375.238885) (xy 47.845161 -375.21534) (xy 47.770225 -375.184301)
			(xy 47.698693 -375.146066) (xy 47.631253 -375.101004) (xy 47.568554 -375.049549) (xy 47.511201 -374.992196)
			(xy 47.459746 -374.929497) (xy 47.414684 -374.862057) (xy 47.376449 -374.790525) (xy 47.34541 -374.715589)
			(xy 47.321865 -374.637973) (xy 47.306042 -374.558422) (xy 47.298092 -374.477703) (xy 42.999829 -374.477703)
			(xy 44.467198 -375.945072) (xy 73.967714 -375.945072) (xy 73.971606 -375.890722) (xy 73.983193 -375.837478)
			(xy 74.00224 -375.786425) (xy 74.028359 -375.738603) (xy 74.061018 -375.694986) (xy 74.099553 -375.65646)
			(xy 74.143178 -375.623811) (xy 74.191006 -375.597703) (xy 74.242063 -375.578668) (xy 74.29531 -375.567093)
			(xy 74.349661 -375.563214) (xy 74.404012 -375.567111) (xy 74.457254 -375.578702) (xy 74.508305 -375.597754)
			(xy 74.556125 -375.623877) (xy 74.57821 -375.639838) (xy 74.597222 -375.653434) (xy 74.639105 -375.674166)
			(xy 74.684073 -375.686892) (xy 74.73061 -375.691182) (xy 74.777147 -375.686892) (xy 74.822115 -375.674166)
			(xy 74.863998 -375.653434) (xy 74.88301 -375.639838) (xy 74.905055 -375.623817) (xy 74.952882 -375.597692)
			(xy 75.003941 -375.578639) (xy 75.057192 -375.567048) (xy 75.11155 -375.563153) (xy 75.165909 -375.567034)
			(xy 75.219163 -375.578611) (xy 75.270227 -375.59765) (xy 75.318061 -375.623763) (xy 75.361692 -375.656417)
			(xy 75.400232 -375.694949) (xy 75.432895 -375.738574) (xy 75.459018 -375.786403) (xy 75.478067 -375.837463)
			(xy 75.489655 -375.890714) (xy 75.493547 -375.945072) (xy 76.043094 -375.945072) (xy 76.046986 -375.890717)
			(xy 76.058574 -375.837469) (xy 76.077623 -375.786412) (xy 76.103746 -375.738587) (xy 76.136409 -375.694966)
			(xy 76.174947 -375.656438) (xy 76.218578 -375.623787) (xy 76.266411 -375.597679) (xy 76.317473 -375.578644)
			(xy 76.370724 -375.56707) (xy 76.425081 -375.563194) (xy 76.479436 -375.567093) (xy 76.532682 -375.578689)
			(xy 76.583736 -375.597746) (xy 76.631558 -375.623874) (xy 76.653644 -375.639838) (xy 76.672656 -375.653434)
			(xy 76.714539 -375.674166) (xy 76.759507 -375.686892) (xy 76.806044 -375.691182) (xy 76.852581 -375.686892)
			(xy 76.897549 -375.674166) (xy 76.939432 -375.653434) (xy 76.958444 -375.639838) (xy 76.980488 -375.62382)
			(xy 77.028313 -375.5977) (xy 77.079369 -375.578653) (xy 77.132616 -375.567065) (xy 77.186969 -375.563173)
			(xy 77.241324 -375.567056) (xy 77.294572 -375.578635) (xy 77.345631 -375.597675) (xy 77.39346 -375.623787)
			(xy 77.437087 -375.65644) (xy 77.475622 -375.694969) (xy 77.508282 -375.738591) (xy 77.534401 -375.786416)
			(xy 77.553448 -375.837472) (xy 77.565036 -375.890719) (xy 77.568927 -375.945072) (xy 77.568868 -375.945895)
			(xy 78.222016 -375.945895) (xy 78.225904 -375.891547) (xy 78.237487 -375.838306) (xy 78.256529 -375.787255)
			(xy 78.282642 -375.739433) (xy 78.315296 -375.695815) (xy 78.353824 -375.657287) (xy 78.397444 -375.624635)
			(xy 78.445266 -375.598523) (xy 78.496318 -375.579483) (xy 78.54956 -375.567902) (xy 78.603908 -375.564016)
			(xy 78.658256 -375.567904) (xy 78.711497 -375.579488) (xy 78.762548 -375.59853) (xy 78.810369 -375.624644)
			(xy 78.832456 -375.6406) (xy 78.851468 -375.654196) (xy 78.893351 -375.674928) (xy 78.938319 -375.687654)
			(xy 78.984856 -375.691944) (xy 79.031393 -375.687654) (xy 79.076361 -375.674928) (xy 79.118244 -375.654196)
			(xy 79.137256 -375.6406) (xy 79.159338 -375.624626) (xy 79.207167 -375.598497) (xy 79.258228 -375.579441)
			(xy 79.311481 -375.567847) (xy 79.365842 -375.563951) (xy 79.420205 -375.567831) (xy 79.473461 -375.579409)
			(xy 79.524528 -375.598449) (xy 79.545908 -375.61012) (xy 86.877404 -375.61012) (xy 86.881424 -375.419469)
			(xy 86.893478 -375.229156) (xy 86.913544 -375.039521) (xy 86.941587 -374.8509) (xy 86.977556 -374.66363)
			(xy 87.021388 -374.478042) (xy 87.073005 -374.294467) (xy 87.132315 -374.113231) (xy 87.199213 -373.934656)
			(xy 87.273579 -373.759061) (xy 87.355281 -373.586756) (xy 87.444175 -373.418049) (xy 87.540101 -373.253239)
			(xy 87.64289 -373.09262) (xy 87.752359 -372.936477) (xy 87.868313 -372.785088) (xy 87.990547 -372.638721)
			(xy 88.118841 -372.497637) (xy 88.252969 -372.362088) (xy 88.392693 -372.232313) (xy 88.537763 -372.108543)
			(xy 88.687921 -371.991) (xy 88.842902 -371.879891) (xy 89.002429 -371.775414) (xy 89.166218 -371.677755)
			(xy 89.333978 -371.587088) (xy 89.505412 -371.503574) (xy 89.680214 -371.427361) (xy 89.858073 -371.358585)
			(xy 90.038674 -371.297367) (xy 90.221694 -371.243818) (xy 90.40681 -371.198032) (xy 90.593691 -371.16009)
			(xy 90.782006 -371.130061) (xy 90.971419 -371.107996) (xy 91.161593 -371.093937) (xy 91.352192 -371.087907)
			(xy 91.542875 -371.089917) (xy 91.733304 -371.099964) (xy 91.92314 -371.11803) (xy 92.112046 -371.144083)
			(xy 92.299685 -371.178076) (xy 92.485725 -371.219949) (xy 92.669834 -371.269628) (xy 92.851685 -371.327024)
			(xy 93.030955 -371.392035) (xy 93.207325 -371.464546) (xy 93.380481 -371.544427) (xy 93.550116 -371.631537)
			(xy 93.715928 -371.725721) (xy 93.877622 -371.826812) (xy 94.03491 -371.934628) (xy 94.187513 -372.04898)
			(xy 94.335161 -372.169663) (xy 94.477589 -372.296464) (xy 94.614545 -372.429155) (xy 94.745786 -372.567503)
			(xy 94.871078 -372.71126) (xy 94.990198 -372.860171) (xy 95.102934 -373.013972) (xy 95.209087 -373.172388)
			(xy 95.308467 -373.335139) (xy 95.400897 -373.501934) (xy 95.486214 -373.672478) (xy 95.564266 -373.846466)
			(xy 95.634913 -374.023591) (xy 95.698031 -374.203536) (xy 95.753507 -374.385982) (xy 95.801242 -374.570605)
			(xy 95.841152 -374.757075) (xy 95.873165 -374.945063) (xy 95.897225 -375.134233) (xy 95.913288 -375.324249)
			(xy 95.921327 -375.514773) (xy 95.92183 -375.61012) (xy 95.921327 -375.705467) (xy 95.913288 -375.895991)
			(xy 95.897225 -376.086007) (xy 95.873165 -376.275177) (xy 95.841152 -376.463165) (xy 95.801242 -376.649635)
			(xy 95.753507 -376.834258) (xy 95.698031 -377.016704) (xy 95.634913 -377.196649) (xy 95.564266 -377.373774)
			(xy 95.486214 -377.547762) (xy 95.400897 -377.718306) (xy 95.308467 -377.885101) (xy 95.209087 -378.047852)
			(xy 95.102934 -378.206268) (xy 94.990198 -378.360069) (xy 94.871078 -378.50898) (xy 94.745786 -378.652737)
			(xy 94.614545 -378.791085) (xy 94.477589 -378.923776) (xy 94.335161 -379.050577) (xy 94.187513 -379.17126)
			(xy 94.03491 -379.285612) (xy 93.877622 -379.393428) (xy 93.715928 -379.494519) (xy 93.550116 -379.588703)
			(xy 93.380481 -379.675813) (xy 93.207325 -379.755694) (xy 93.030955 -379.828205) (xy 92.851685 -379.893216)
			(xy 92.669834 -379.950612) (xy 92.485725 -380.000291) (xy 92.299685 -380.042164) (xy 92.112046 -380.076157)
			(xy 91.92314 -380.10221) (xy 91.733304 -380.120276) (xy 91.542875 -380.130323) (xy 91.352192 -380.132333)
			(xy 91.161593 -380.126303) (xy 90.971419 -380.112244) (xy 90.782006 -380.090179) (xy 90.593691 -380.06015)
			(xy 90.40681 -380.022208) (xy 90.221694 -379.976422) (xy 90.038674 -379.922873) (xy 89.858073 -379.861655)
			(xy 89.680214 -379.792879) (xy 89.505412 -379.716666) (xy 89.333978 -379.633152) (xy 89.166218 -379.542485)
			(xy 89.002429 -379.444826) (xy 88.842902 -379.340349) (xy 88.687921 -379.22924) (xy 88.537763 -379.111697)
			(xy 88.392693 -378.987927) (xy 88.252969 -378.858152) (xy 88.118841 -378.722603) (xy 87.990547 -378.581519)
			(xy 87.868313 -378.435152) (xy 87.752359 -378.283763) (xy 87.64289 -378.12762) (xy 87.540101 -377.967001)
			(xy 87.444175 -377.802191) (xy 87.355281 -377.633484) (xy 87.273579 -377.461179) (xy 87.199213 -377.285584)
			(xy 87.132315 -377.107009) (xy 87.073005 -376.925773) (xy 87.021388 -376.742198) (xy 86.977556 -376.55661)
			(xy 86.941587 -376.36934) (xy 86.913544 -376.180719) (xy 86.893478 -375.991084) (xy 86.881424 -375.800771)
			(xy 86.877404 -375.61012) (xy 79.545908 -375.61012) (xy 79.572365 -375.624563) (xy 79.615998 -375.65722)
			(xy 79.654539 -375.695755) (xy 79.687203 -375.739382) (xy 79.713325 -375.787215) (xy 79.732374 -375.838279)
			(xy 79.74396 -375.891533) (xy 79.747849 -375.945895) (xy 79.743962 -376.000257) (xy 79.732376 -376.053512)
			(xy 79.713329 -376.104576) (xy 79.687208 -376.15241) (xy 79.654545 -376.196038) (xy 79.616005 -376.234574)
			(xy 79.572373 -376.267232) (xy 79.524537 -376.293347) (xy 79.47347 -376.312389) (xy 79.420214 -376.323968)
			(xy 79.365852 -376.327849) (xy 79.31149 -376.323954) (xy 79.258237 -376.312361) (xy 79.207175 -376.293307)
			(xy 79.159346 -376.26718) (xy 79.137256 -376.251216) (xy 79.118244 -376.23762) (xy 79.076361 -376.216888)
			(xy 79.031393 -376.204162) (xy 78.984856 -376.199872) (xy 78.938319 -376.204162) (xy 78.893351 -376.216888)
			(xy 78.851468 -376.23762) (xy 78.832456 -376.251216) (xy 78.810361 -376.267161) (xy 78.762539 -376.293274)
			(xy 78.711488 -376.312315) (xy 78.658246 -376.323897) (xy 78.603898 -376.327784) (xy 78.54955 -376.323896)
			(xy 78.496309 -376.312314) (xy 78.445257 -376.293273) (xy 78.397436 -376.267159) (xy 78.353817 -376.234506)
			(xy 78.315289 -376.195978) (xy 78.282637 -376.152359) (xy 78.256525 -376.104537) (xy 78.237484 -376.053485)
			(xy 78.225903 -376.000243) (xy 78.222016 -375.945895) (xy 77.568868 -375.945895) (xy 77.565043 -375.999427)
			(xy 77.553464 -376.052675) (xy 77.534424 -376.103734) (xy 77.508312 -376.151563) (xy 77.475658 -376.195189)
			(xy 77.437129 -376.233724) (xy 77.393507 -376.266384) (xy 77.345681 -376.292502) (xy 77.294625 -376.311549)
			(xy 77.241378 -376.323136) (xy 77.187025 -376.327027) (xy 77.13267 -376.323143) (xy 77.079422 -376.311563)
			(xy 77.028363 -376.292523) (xy 76.980534 -376.26641) (xy 76.958444 -376.250454) (xy 76.939432 -376.236858)
			(xy 76.897549 -376.216126) (xy 76.852581 -376.2034) (xy 76.806044 -376.19911) (xy 76.759507 -376.2034)
			(xy 76.714539 -376.216126) (xy 76.672656 -376.236858) (xy 76.653644 -376.250454) (xy 76.631512 -376.266356)
			(xy 76.583686 -376.292477) (xy 76.532629 -376.311526) (xy 76.479381 -376.323115) (xy 76.425025 -376.327006)
			(xy 76.37067 -376.323122) (xy 76.31742 -376.311541) (xy 76.26636 -376.292499) (xy 76.218531 -376.266383)
			(xy 76.174906 -376.233726) (xy 76.136372 -376.195193) (xy 76.103716 -376.151567) (xy 76.077601 -376.103738)
			(xy 76.058559 -376.052678) (xy 76.046978 -375.999428) (xy 76.043094 -375.945072) (xy 75.493547 -375.945072)
			(xy 75.489663 -375.999431) (xy 75.478082 -376.052684) (xy 75.45904 -376.103747) (xy 75.432925 -376.15158)
			(xy 75.400268 -376.195209) (xy 75.361734 -376.233746) (xy 75.318108 -376.266407) (xy 75.270277 -376.292527)
			(xy 75.219216 -376.311573) (xy 75.165964 -376.323159) (xy 75.111605 -376.327047) (xy 75.057246 -376.32316)
			(xy 75.003994 -376.311576) (xy 74.952933 -376.292531) (xy 74.905101 -376.266413) (xy 74.88301 -376.250454)
			(xy 74.863998 -376.236858) (xy 74.822115 -376.216126) (xy 74.777147 -376.2034) (xy 74.73061 -376.19911)
			(xy 74.684073 -376.2034) (xy 74.639105 -376.216126) (xy 74.597222 -376.236858) (xy 74.57821 -376.250454)
			(xy 74.556078 -376.266353) (xy 74.508255 -376.292469) (xy 74.457201 -376.311513) (xy 74.403957 -376.323097)
			(xy 74.349606 -376.326986) (xy 74.295255 -376.323099) (xy 74.24201 -376.311517) (xy 74.190956 -376.292474)
			(xy 74.143132 -376.266359) (xy 74.099511 -376.233704) (xy 74.060982 -376.195173) (xy 74.028329 -376.15155)
			(xy 74.002217 -376.103724) (xy 73.983177 -376.052669) (xy 73.971598 -375.999424) (xy 73.967714 -375.945072)
			(xy 44.467198 -375.945072) (xy 46.22392 -377.701794) (xy 73.967685 -377.701794) (xy 73.971574 -377.647439)
			(xy 73.983159 -377.594191) (xy 74.002205 -377.543133) (xy 74.028323 -377.495306) (xy 74.060982 -377.451683)
			(xy 74.099518 -377.413152) (xy 74.143145 -377.380498) (xy 74.190975 -377.354386) (xy 74.242034 -377.335346)
			(xy 74.295284 -377.323768) (xy 74.34964 -377.319885) (xy 74.403994 -377.323779) (xy 74.457242 -377.335369)
			(xy 74.508298 -377.354419) (xy 74.556122 -377.380541) (xy 74.57821 -377.396502) (xy 74.597222 -377.410098)
			(xy 74.639105 -377.43083) (xy 74.684073 -377.443556) (xy 74.73061 -377.447846) (xy 74.777147 -377.443556)
			(xy 74.822115 -377.43083) (xy 74.863998 -377.410098) (xy 74.88301 -377.396502) (xy 74.905089 -377.380529)
			(xy 74.952914 -377.354409) (xy 75.00397 -377.335361) (xy 75.057217 -377.323773) (xy 75.111572 -377.319881)
			(xy 75.165927 -377.323765) (xy 75.219176 -377.335345) (xy 75.270234 -377.354385) (xy 75.318064 -377.380499)
			(xy 75.36169 -377.413153) (xy 75.400224 -377.451684) (xy 75.432883 -377.495307) (xy 75.459 -377.543134)
			(xy 75.478045 -377.594191) (xy 75.48963 -377.647439) (xy 75.493519 -377.701794) (xy 76.043065 -377.701794)
			(xy 76.046954 -377.647434) (xy 76.058541 -377.594181) (xy 76.077588 -377.54312) (xy 76.10371 -377.495289)
			(xy 76.136373 -377.451663) (xy 76.174912 -377.41313) (xy 76.218544 -377.380474) (xy 76.266379 -377.354361)
			(xy 76.317444 -377.335322) (xy 76.370699 -377.323745) (xy 76.425059 -377.319865) (xy 76.479418 -377.323762)
			(xy 76.532669 -377.335356) (xy 76.583728 -377.35441) (xy 76.631556 -377.380538) (xy 76.653644 -377.396502)
			(xy 76.672656 -377.410098) (xy 76.714539 -377.43083) (xy 76.759507 -377.443556) (xy 76.806044 -377.447846)
			(xy 76.852581 -377.443556) (xy 76.897549 -377.43083) (xy 76.939432 -377.410098) (xy 76.958444 -377.396502)
			(xy 76.980522 -377.380532) (xy 77.028345 -377.354417) (xy 77.079398 -377.335374) (xy 77.132641 -377.32379)
			(xy 77.186991 -377.319902) (xy 77.241341 -377.323788) (xy 77.294585 -377.335369) (xy 77.345639 -377.35441)
			(xy 77.393463 -377.380523) (xy 77.437084 -377.413176) (xy 77.475615 -377.451704) (xy 77.508269 -377.495324)
			(xy 77.534384 -377.543148) (xy 77.553427 -377.594201) (xy 77.56501 -377.647444) (xy 77.568898 -377.701794)
			(xy 77.568839 -377.702617) (xy 78.221987 -377.702617) (xy 78.225872 -377.648265) (xy 78.237453 -377.595018)
			(xy 78.256493 -377.543962) (xy 78.282606 -377.496136) (xy 78.31526 -377.452512) (xy 78.353789 -377.41398)
			(xy 78.39741 -377.381323) (xy 78.445234 -377.355206) (xy 78.496289 -377.336162) (xy 78.549534 -377.324577)
			(xy 78.603886 -377.320687) (xy 78.658238 -377.324573) (xy 78.711484 -377.336154) (xy 78.76254 -377.355195)
			(xy 78.810367 -377.381308) (xy 78.832456 -377.397264) (xy 78.851468 -377.41086) (xy 78.893351 -377.431592)
			(xy 78.938319 -377.444318) (xy 78.984856 -377.448608) (xy 79.031393 -377.444318) (xy 79.076361 -377.431592)
			(xy 79.118244 -377.41086) (xy 79.137256 -377.397264) (xy 79.159371 -377.381338) (xy 79.207198 -377.355214)
			(xy 79.258257 -377.336163) (xy 79.311506 -377.324573) (xy 79.365864 -377.32068) (xy 79.420222 -377.324562)
			(xy 79.473474 -377.336142) (xy 79.524536 -377.355184) (xy 79.572368 -377.381299) (xy 79.615996 -377.413956)
			(xy 79.654531 -377.45249) (xy 79.687191 -377.496116) (xy 79.713308 -377.543947) (xy 79.732352 -377.595007)
			(xy 79.743935 -377.648259) (xy 79.74782 -377.702617) (xy 79.74393 -377.756974) (xy 79.732343 -377.810225)
			(xy 79.713294 -377.861284) (xy 79.687172 -377.909112) (xy 79.654509 -377.952736) (xy 79.61597 -377.991266)
			(xy 79.572339 -378.023919) (xy 79.524505 -378.05003) (xy 79.473442 -378.069067) (xy 79.420189 -378.080642)
			(xy 79.36583 -378.08452) (xy 79.311473 -378.080622) (xy 79.258224 -378.069028) (xy 79.207168 -378.049972)
			(xy 79.159343 -378.023844) (xy 79.137256 -378.00788) (xy 79.118244 -377.994284) (xy 79.076361 -377.973552)
			(xy 79.031393 -377.960826) (xy 78.984856 -377.956536) (xy 78.938319 -377.960826) (xy 78.893351 -377.973552)
			(xy 78.851468 -377.994284) (xy 78.832456 -378.00788) (xy 78.810395 -378.023874) (xy 78.762571 -378.049991)
			(xy 78.711517 -378.069037) (xy 78.658272 -378.080622) (xy 78.60392 -378.084513) (xy 78.549568 -378.080628)
			(xy 78.496321 -378.069048) (xy 78.445265 -378.050008) (xy 78.397438 -378.023895) (xy 78.353814 -377.991242)
			(xy 78.315282 -377.952713) (xy 78.282624 -377.909093) (xy 78.256507 -377.861268) (xy 78.237462 -377.810214)
			(xy 78.225877 -377.756969) (xy 78.221987 -377.702617) (xy 77.568839 -377.702617) (xy 77.565012 -377.756144)
			(xy 77.55343 -377.809388) (xy 77.534389 -377.860442) (xy 77.508276 -377.908266) (xy 77.475622 -377.951887)
			(xy 77.437093 -377.990417) (xy 77.393473 -378.023071) (xy 77.34565 -378.049185) (xy 77.294597 -378.068228)
			(xy 77.241353 -378.079811) (xy 77.187003 -378.083698) (xy 77.132653 -378.079811) (xy 77.079409 -378.068229)
			(xy 77.028356 -378.049188) (xy 76.980532 -378.023074) (xy 76.958444 -378.007118) (xy 76.939432 -377.993522)
			(xy 76.897549 -377.97279) (xy 76.852581 -377.960064) (xy 76.806044 -377.955774) (xy 76.759507 -377.960064)
			(xy 76.714539 -377.97279) (xy 76.672656 -377.993522) (xy 76.653644 -378.007118) (xy 76.631545 -378.023068)
			(xy 76.583717 -378.049195) (xy 76.532658 -378.068248) (xy 76.479406 -378.07984) (xy 76.425047 -378.083735)
			(xy 76.370687 -378.079853) (xy 76.317432 -378.068274) (xy 76.266368 -378.049234) (xy 76.218534 -378.023119)
			(xy 76.174903 -377.990462) (xy 76.136365 -377.951928) (xy 76.103703 -377.908301) (xy 76.077583 -377.860469)
			(xy 76.058537 -377.809407) (xy 76.046952 -377.756154) (xy 76.043065 -377.701794) (xy 75.493519 -377.701794)
			(xy 75.489632 -377.756149) (xy 75.478049 -377.809397) (xy 75.459005 -377.860455) (xy 75.432889 -377.908283)
			(xy 75.400232 -377.951907) (xy 75.361699 -377.990439) (xy 75.318074 -378.023095) (xy 75.270245 -378.04921)
			(xy 75.219187 -378.068252) (xy 75.165938 -378.079833) (xy 75.111584 -378.083719) (xy 75.057229 -378.079829)
			(xy 75.003982 -378.068242) (xy 74.952925 -378.049196) (xy 74.905099 -378.023077) (xy 74.88301 -378.007118)
			(xy 74.863998 -377.993522) (xy 74.822115 -377.97279) (xy 74.777147 -377.960064) (xy 74.73061 -377.955774)
			(xy 74.684073 -377.960064) (xy 74.639105 -377.97279) (xy 74.597222 -377.993522) (xy 74.57821 -378.007118)
			(xy 74.556112 -378.023065) (xy 74.508287 -378.049186) (xy 74.45723 -378.068235) (xy 74.403983 -378.079823)
			(xy 74.349628 -378.083715) (xy 74.295272 -378.079831) (xy 74.242023 -378.06825) (xy 74.190964 -378.049209)
			(xy 74.143134 -378.023095) (xy 74.099509 -377.99044) (xy 74.060974 -377.951908) (xy 74.028316 -377.908284)
			(xy 74.0022 -377.860456) (xy 73.983156 -377.809398) (xy 73.971572 -377.756149) (xy 73.967685 -377.701794)
			(xy 46.22392 -377.701794) (xy 46.748954 -378.226828) (xy 56.579516 -378.226828) (xy 57.821053 -379.468412)
			(xy 73.967661 -379.468412) (xy 73.971548 -379.414053) (xy 73.983131 -379.360801) (xy 74.002175 -379.30974)
			(xy 74.028293 -379.261908) (xy 74.060952 -379.218281) (xy 74.099488 -379.179746) (xy 74.143116 -379.147088)
			(xy 74.190948 -379.120971) (xy 74.24201 -379.101928) (xy 74.295263 -379.090346) (xy 74.349622 -379.086461)
			(xy 74.40398 -379.090353) (xy 74.457231 -379.101941) (xy 74.508291 -379.120989) (xy 74.55612 -379.147111)
			(xy 74.57821 -379.163072) (xy 74.597222 -379.176668) (xy 74.639105 -379.1974) (xy 74.684073 -379.210126)
			(xy 74.73061 -379.214416) (xy 74.777147 -379.210126) (xy 74.822115 -379.1974) (xy 74.863998 -379.176668)
			(xy 74.88301 -379.163072) (xy 74.905117 -379.14714) (xy 74.95294 -379.121023) (xy 75.003994 -379.101979)
			(xy 75.057238 -379.090394) (xy 75.11159 -379.086505) (xy 75.165941 -379.090391) (xy 75.219186 -379.101973)
			(xy 75.270241 -379.121015) (xy 75.318066 -379.147129) (xy 75.361688 -379.179783) (xy 75.400218 -379.218314)
			(xy 75.432872 -379.261935) (xy 75.458986 -379.309761) (xy 75.478027 -379.360815) (xy 75.489609 -379.414061)
			(xy 75.493495 -379.468412) (xy 76.043041 -379.468412) (xy 76.046928 -379.414049) (xy 76.058512 -379.360792)
			(xy 76.077559 -379.309726) (xy 76.10368 -379.261891) (xy 76.136343 -379.218261) (xy 76.174883 -379.179724)
			(xy 76.218516 -379.147064) (xy 76.266353 -379.120947) (xy 76.31742 -379.101904) (xy 76.370677 -379.090324)
			(xy 76.425041 -379.086441) (xy 76.479404 -379.090335) (xy 76.532659 -379.101927) (xy 76.583722 -379.120981)
			(xy 76.631553 -379.147108) (xy 76.653644 -379.163072) (xy 76.672656 -379.176668) (xy 76.714539 -379.1974)
			(xy 76.759507 -379.210126) (xy 76.806044 -379.214416) (xy 76.852581 -379.210126) (xy 76.897549 -379.1974)
			(xy 76.939432 -379.176668) (xy 76.958444 -379.163072) (xy 76.98055 -379.147143) (xy 77.028371 -379.121032)
			(xy 77.079422 -379.101992) (xy 77.132662 -379.090412) (xy 77.187009 -379.086526) (xy 77.241356 -379.090414)
			(xy 77.294596 -379.101997) (xy 77.345645 -379.121039) (xy 77.393465 -379.147152) (xy 77.437082 -379.179806)
			(xy 77.475608 -379.218334) (xy 77.508259 -379.261952) (xy 77.53437 -379.309774) (xy 77.553409 -379.360825)
			(xy 77.564989 -379.414065) (xy 77.568874 -379.468412) (xy 77.568827 -379.469075) (xy 78.222043 -379.469075)
			(xy 78.225934 -379.414731) (xy 78.237519 -379.361494) (xy 78.256562 -379.310447) (xy 78.282676 -379.262631)
			(xy 78.315329 -379.219017) (xy 78.353857 -379.180495) (xy 78.397476 -379.147847) (xy 78.445296 -379.12174)
			(xy 78.496345 -379.102704) (xy 78.549584 -379.091126) (xy 78.603928 -379.087243) (xy 78.658272 -379.091134)
			(xy 78.711509 -379.102719) (xy 78.762555 -379.121763) (xy 78.810372 -379.147878) (xy 78.832456 -379.163834)
			(xy 78.851468 -379.17743) (xy 78.893351 -379.198162) (xy 78.938319 -379.210888) (xy 78.984856 -379.215178)
			(xy 79.031393 -379.210888) (xy 79.076361 -379.198162) (xy 79.118244 -379.17743) (xy 79.137256 -379.163834)
			(xy 79.159306 -379.147814) (xy 79.207137 -379.12168) (xy 79.2582 -379.102621) (xy 79.311457 -379.091023)
			(xy 79.365822 -379.087123) (xy 79.420188 -379.091001) (xy 79.473449 -379.102577) (xy 79.524521 -379.121615)
			(xy 79.572362 -379.147729) (xy 79.616 -379.180386) (xy 79.654546 -379.218921) (xy 79.687215 -379.26255)
			(xy 79.713342 -379.310385) (xy 79.732394 -379.361451) (xy 79.743984 -379.414709) (xy 79.747877 -379.469075)
			(xy 79.743991 -379.523441) (xy 79.732408 -379.5767) (xy 79.713363 -379.627769) (xy 79.687242 -379.675607)
			(xy 79.654579 -379.719241) (xy 79.616039 -379.757781) (xy 79.572405 -379.790444) (xy 79.524567 -379.816564)
			(xy 79.473498 -379.835609) (xy 79.420238 -379.847192) (xy 79.365872 -379.851077) (xy 79.311507 -379.847184)
			(xy 79.258249 -379.835593) (xy 79.207183 -379.81654) (xy 79.159348 -379.790414) (xy 79.137256 -379.77445)
			(xy 79.118244 -379.760854) (xy 79.076361 -379.740122) (xy 79.031393 -379.727396) (xy 78.984856 -379.723106)
			(xy 78.938319 -379.727396) (xy 78.893351 -379.740122) (xy 78.851468 -379.760854) (xy 78.832456 -379.77445)
			(xy 78.810329 -379.79035) (xy 78.762509 -379.816458) (xy 78.711461 -379.835495) (xy 78.658222 -379.847073)
			(xy 78.603878 -379.850957) (xy 78.549534 -379.847067) (xy 78.496297 -379.835482) (xy 78.44525 -379.816439)
			(xy 78.397433 -379.790326) (xy 78.353819 -379.757672) (xy 78.315296 -379.719145) (xy 78.282649 -379.675527)
			(xy 78.256541 -379.627707) (xy 78.237504 -379.576658) (xy 78.225927 -379.523419) (xy 78.222043 -379.469075)
			(xy 77.568827 -379.469075) (xy 77.564985 -379.522759) (xy 77.553402 -379.575998) (xy 77.53436 -379.627048)
			(xy 77.508246 -379.674868) (xy 77.475592 -379.718484) (xy 77.437064 -379.75701) (xy 77.393445 -379.78966)
			(xy 77.345623 -379.815771) (xy 77.294572 -379.83481) (xy 77.241332 -379.846389) (xy 77.186985 -379.850274)
			(xy 77.132639 -379.846385) (xy 77.079399 -379.834801) (xy 77.028349 -379.815758) (xy 76.98053 -379.789644)
			(xy 76.958444 -379.773688) (xy 76.939432 -379.760092) (xy 76.897549 -379.73936) (xy 76.852581 -379.726634)
			(xy 76.806044 -379.722344) (xy 76.759507 -379.726634) (xy 76.714539 -379.73936) (xy 76.672656 -379.760092)
			(xy 76.653644 -379.773688) (xy 76.631574 -379.789679) (xy 76.583744 -379.815809) (xy 76.532682 -379.834866)
			(xy 76.479428 -379.846461) (xy 76.425065 -379.850359) (xy 76.370701 -379.84648) (xy 76.317443 -379.834902)
			(xy 76.266375 -379.815863) (xy 76.218536 -379.789749) (xy 76.174901 -379.757092) (xy 76.136358 -379.718557)
			(xy 76.103693 -379.674929) (xy 76.077569 -379.627096) (xy 76.058519 -379.576031) (xy 76.046931 -379.522775)
			(xy 76.043041 -379.468412) (xy 75.493495 -379.468412) (xy 75.489605 -379.522763) (xy 75.478021 -379.576008)
			(xy 75.458976 -379.627061) (xy 75.432859 -379.674885) (xy 75.400202 -379.718504) (xy 75.361669 -379.757032)
			(xy 75.318046 -379.789684) (xy 75.270219 -379.815795) (xy 75.219163 -379.834834) (xy 75.165917 -379.846412)
			(xy 75.111566 -379.850295) (xy 75.057215 -379.846402) (xy 75.003971 -379.834814) (xy 74.952918 -379.815767)
			(xy 74.905096 -379.789647) (xy 74.88301 -379.773688) (xy 74.863998 -379.760092) (xy 74.822115 -379.73936)
			(xy 74.777147 -379.726634) (xy 74.73061 -379.722344) (xy 74.684073 -379.726634) (xy 74.639105 -379.73936)
			(xy 74.597222 -379.760092) (xy 74.57821 -379.773688) (xy 74.55614 -379.789676) (xy 74.508313 -379.815801)
			(xy 74.457254 -379.834853) (xy 74.404004 -379.846444) (xy 74.349646 -379.850339) (xy 74.295287 -379.846457)
			(xy 74.242033 -379.834878) (xy 74.19097 -379.815839) (xy 74.143137 -379.789725) (xy 74.099506 -379.75707)
			(xy 74.060968 -379.718537) (xy 74.028306 -379.674912) (xy 74.002185 -379.627082) (xy 73.983138 -379.576022)
			(xy 73.971551 -379.52277) (xy 73.967661 -379.468412) (xy 57.821053 -379.468412) (xy 63.30823 -384.955796)
			(xy 63.320385 -384.96714) (xy 63.349173 -384.983743) (xy 63.381276 -384.992338) (xy 63.397892 -384.99288)
			(xy 75.438254 -384.99288) (xy 75.454888 -384.992321) (xy 75.487006 -384.983634) (xy 75.515788 -384.966942)
			(xy 75.527916 -384.955542) (xy 76.298806 -384.184652) (xy 76.321539 -384.16265) (xy 76.371731 -384.124137)
			(xy 76.42652 -384.092504) (xy 76.48497 -384.068293) (xy 76.546079 -384.051919) (xy 76.608803 -384.043661)
			(xy 76.672069 -384.043661) (xy 76.734793 -384.051919) (xy 76.795902 -384.068293) (xy 76.854352 -384.092504)
			(xy 76.909141 -384.124137) (xy 76.959333 -384.16265) (xy 77.004068 -384.207385) (xy 77.042581 -384.257577)
			(xy 77.074214 -384.312366) (xy 77.098425 -384.370816) (xy 77.114799 -384.431925) (xy 77.123057 -384.494649)
			(xy 77.123057 -384.557915) (xy 77.114799 -384.620639) (xy 77.098425 -384.681748) (xy 77.074214 -384.740198)
			(xy 77.042581 -384.794987) (xy 77.004068 -384.845179) (xy 76.982066 -384.867912) (xy 76.14539 -385.704588)
			(xy 76.133929 -385.716719) (xy 76.117226 -385.745599) (xy 76.10858 -385.777822) (xy 76.108581 -385.811184)
			(xy 76.117229 -385.843406) (xy 76.133932 -385.872286) (xy 76.14539 -385.88442) (xy 77.117448 -386.856224)
			(xy 77.13945 -386.878957) (xy 77.177963 -386.929149) (xy 77.209596 -386.983938) (xy 77.233807 -387.042388)
			(xy 77.250181 -387.103497) (xy 77.258439 -387.166221) (xy 77.258439 -387.229487) (xy 77.250181 -387.292211)
			(xy 77.233807 -387.35332) (xy 77.209596 -387.41177) (xy 77.177963 -387.466559) (xy 77.13945 -387.516751)
			(xy 77.094715 -387.561486) (xy 77.044523 -387.599999) (xy 76.989734 -387.631632) (xy 76.931284 -387.655843)
			(xy 76.870175 -387.672217) (xy 76.807451 -387.680475) (xy 76.744185 -387.680475) (xy 76.681461 -387.672217)
			(xy 76.620352 -387.655843) (xy 76.561902 -387.631632) (xy 76.507113 -387.599999) (xy 76.456921 -387.561486)
			(xy 76.434188 -387.539484) (xy 75.66406 -386.769356) (xy 62.608968 -386.769356) (xy 56.001158 -380.161292)
			(xy 55.989009 -380.149941) (xy 55.960218 -380.13334) (xy 55.928113 -380.124748) (xy 55.911496 -380.124208)
			(xy 45.97781 -380.124208) (xy 41.525952 -375.672604) (xy 40.440864 -375.672604) (xy 40.409813 -375.672116)
			(xy 40.348225 -375.664129) (xy 40.288168 -375.648318) (xy 40.230632 -375.624942) (xy 40.176565 -375.594387)
			(xy 40.126858 -375.557158) (xy 40.082331 -375.513866) (xy 40.043717 -375.465227) (xy 40.011653 -375.412041)
			(xy 39.986668 -375.355185) (xy 39.969172 -375.295597) (xy 39.959456 -375.234259) (xy 39.957678 -375.172181)
			(xy 39.960296 -375.141236) (xy 39.962134 -375.117702) (xy 39.95811 -375.070675) (xy 39.945472 -375.025199)
			(xy 39.924655 -374.982839) (xy 39.896375 -374.94505) (xy 39.861604 -374.913132) (xy 39.821538 -374.888183)
			(xy 39.777554 -374.87106) (xy 39.731166 -374.862352) (xy 39.707566 -374.861836) (xy 38.819328 -374.861836)
			(xy 38.472618 -375.208292) (xy 36.620704 -375.208292) (xy 36.597468 -375.208843) (xy 36.551768 -375.217274)
			(xy 36.508363 -375.233874) (xy 36.4687 -375.25809) (xy 36.434101 -375.289114) (xy 36.405719 -375.325912)
			(xy 36.384502 -375.367257) (xy 36.371156 -375.41177) (xy 36.366127 -375.457969) (xy 36.369581 -375.504311)
			(xy 36.381404 -375.549253) (xy 36.390834 -375.570496) (xy 36.408653 -375.609583) (xy 36.437911 -375.690355)
			(xy 36.459679 -375.773459) (xy 36.473775 -375.858203) (xy 36.480083 -375.943879) (xy 36.478548 -376.029774)
			(xy 36.469184 -376.11517) (xy 36.452069 -376.199356) (xy 36.427346 -376.28163) (xy 36.395221 -376.361305)
			(xy 36.355962 -376.437718) (xy 36.309896 -376.510231) (xy 36.257407 -376.578239) (xy 36.198934 -376.641176)
			(xy 36.134962 -376.698516) (xy 36.066027 -376.749781) (xy 35.996485 -376.792236) (xy 40.137586 -376.792236)
			(xy 40.141657 -376.736614) (xy 40.153783 -376.682177) (xy 40.173706 -376.630086) (xy 40.201002 -376.581451)
			(xy 40.235088 -376.537308) (xy 40.275237 -376.498599) (xy 40.320595 -376.466148) (xy 40.370195 -376.440647)
			(xy 40.422979 -376.42264) (xy 40.477822 -376.41251) (xy 40.533556 -376.410473) (xy 40.588993 -376.416573)
			(xy 40.64295 -376.430679) (xy 40.694279 -376.452491) (xy 40.741885 -376.481545) (xy 40.784753 -376.51722)
			(xy 40.82197 -376.558757) (xy 40.852743 -376.60527) (xy 40.876415 -376.655767) (xy 40.892483 -376.709174)
			(xy 40.900603 -376.76435) (xy 40.901112 -376.792236) (xy 40.900603 -376.820122) (xy 40.892483 -376.875298)
			(xy 40.876415 -376.928705) (xy 40.852743 -376.979202) (xy 40.82197 -377.025715) (xy 40.784753 -377.067252)
			(xy 40.741885 -377.102927) (xy 40.694279 -377.131981) (xy 40.64295 -377.153793) (xy 40.588993 -377.167899)
			(xy 40.533556 -377.173999) (xy 40.477822 -377.171962) (xy 40.422979 -377.161832) (xy 40.370195 -377.143825)
			(xy 40.320595 -377.118324) (xy 40.275237 -377.085873) (xy 40.235088 -377.047164) (xy 40.201002 -377.003021)
			(xy 40.173706 -376.954386) (xy 40.153783 -376.902295) (xy 40.141657 -376.847858) (xy 40.137586 -376.792236)
			(xy 35.996485 -376.792236) (xy 35.992703 -376.794545) (xy 35.915601 -376.832433) (xy 35.835365 -376.863129)
			(xy 35.752662 -376.886378) (xy 35.668184 -376.901986) (xy 35.582634 -376.909823) (xy 35.496726 -376.909823)
			(xy 35.411176 -376.901986) (xy 35.326698 -376.886378) (xy 35.243995 -376.863129) (xy 35.163759 -376.832433)
			(xy 35.086657 -376.794545) (xy 35.013333 -376.749781) (xy 34.944398 -376.698516) (xy 34.880426 -376.641176)
			(xy 34.821953 -376.578239) (xy 34.769464 -376.510231) (xy 34.723398 -376.437718) (xy 34.684139 -376.361305)
			(xy 34.652014 -376.28163) (xy 34.627291 -376.199356) (xy 34.610176 -376.11517) (xy 34.600812 -376.029774)
			(xy 34.599277 -375.943879) (xy 34.605585 -375.858203) (xy 34.619681 -375.773459) (xy 34.641449 -375.690355)
			(xy 34.670707 -375.609583) (xy 34.688526 -375.570496) (xy 34.697979 -375.549266) (xy 34.709778 -375.504321)
			(xy 34.713214 -375.45798) (xy 34.708172 -375.411786) (xy 34.694819 -375.367277) (xy 34.673601 -375.325936)
			(xy 34.645224 -375.289139) (xy 34.610633 -375.258111) (xy 34.570979 -375.233885) (xy 34.527583 -375.217269)
			(xy 34.48189 -375.208815) (xy 34.458656 -375.208292) (xy 34.412682 -375.208292) (xy 31.790132 -372.585996)
			(xy 31.498032 -372.585996) (xy 31.47592 -372.586464) (xy 31.432359 -372.594097) (xy 31.390778 -372.609157)
			(xy 31.352431 -372.631188) (xy 31.318478 -372.659525) (xy 31.289943 -372.693312) (xy 31.267688 -372.731528)
			(xy 31.252385 -372.773021) (xy 31.244497 -372.816536) (xy 31.244261 -372.86076) (xy 31.251685 -372.904357)
			(xy 31.266544 -372.94601) (xy 31.277052 -372.965472) (xy 31.298178 -373.003643) (xy 31.334077 -373.083165)
			(xy 31.362454 -373.16567) (xy 31.383064 -373.250449) (xy 31.395732 -373.336774) (xy 31.400346 -373.423901)
			(xy 31.396869 -373.51108) (xy 31.385329 -373.597563) (xy 31.365826 -373.682604) (xy 31.338528 -373.765473)
			(xy 31.30367 -373.845456) (xy 31.261551 -373.921865) (xy 31.212534 -373.994043) (xy 31.15704 -374.061369)
			(xy 31.095548 -374.123265) (xy 31.028585 -374.179196) (xy 30.956728 -374.228683) (xy 30.880595 -374.2713)
			(xy 30.800841 -374.306679) (xy 30.718153 -374.334517) (xy 30.63324 -374.354575) (xy 30.546835 -374.366678)
			(xy 30.45968 -374.370724) (xy 30.372525 -374.366678) (xy 30.28612 -374.354575) (xy 30.201207 -374.334517)
			(xy 30.118519 -374.306679) (xy 30.038765 -374.2713) (xy 29.962632 -374.228683) (xy 29.890775 -374.179196)
			(xy 29.823812 -374.123265) (xy 29.76232 -374.061369) (xy 29.706826 -373.994043) (xy 29.657809 -373.921865)
			(xy 29.61569 -373.845456) (xy 29.580832 -373.765473) (xy 29.553534 -373.682604) (xy 29.534031 -373.597563)
			(xy 29.522491 -373.51108) (xy 29.519014 -373.423901) (xy 29.523628 -373.336774) (xy 29.536296 -373.250449)
			(xy 29.556906 -373.16567) (xy 29.585283 -373.083165) (xy 29.621182 -373.003643) (xy 29.642308 -372.965472)
			(xy 29.652807 -372.946) (xy 29.66769 -372.904347) (xy 29.675134 -372.860746) (xy 29.674912 -372.816515)
			(xy 29.667032 -372.77299) (xy 29.651732 -372.731489) (xy 29.629475 -372.693264) (xy 29.600933 -372.659474)
			(xy 29.566969 -372.631138) (xy 29.52861 -372.609113) (xy 29.487016 -372.594066) (xy 29.443445 -372.58645)
			(xy 29.421328 -372.585996) (xy 28.897072 -372.585996) (xy 27.44343 -372.16461) (xy 27.413211 -372.155303)
			(xy 27.355295 -372.129932) (xy 27.301186 -372.097218) (xy 27.25181 -372.057721) (xy 27.208011 -372.012117)
			(xy 27.17054 -371.961187) (xy 27.140037 -371.905801) (xy 27.117024 -371.846908) (xy 27.101895 -371.785515)
			(xy 27.094909 -371.722672) (xy 23.656312 -371.722672) (xy 27.947128 -376.013488) (xy 29.519874 -376.013488)
			(xy 29.519874 -375.926588) (xy 29.527892 -375.840059) (xy 29.54386 -375.754639) (xy 29.567641 -375.671057)
			(xy 29.599033 -375.590025) (xy 29.637767 -375.512236) (xy 29.683514 -375.438352) (xy 29.735883 -375.369005)
			(xy 29.794427 -375.304785) (xy 29.858647 -375.246241) (xy 29.927994 -375.193872) (xy 30.001878 -375.148125)
			(xy 30.079667 -375.109391) (xy 30.160699 -375.077999) (xy 30.244281 -375.054218) (xy 30.329701 -375.03825)
			(xy 30.41623 -375.030232) (xy 30.50313 -375.030232) (xy 30.589659 -375.03825) (xy 30.675079 -375.054218)
			(xy 30.758661 -375.077999) (xy 30.839693 -375.109391) (xy 30.917482 -375.148125) (xy 30.991366 -375.193872)
			(xy 31.060713 -375.246241) (xy 31.124933 -375.304785) (xy 31.183477 -375.369005) (xy 31.235846 -375.438352)
			(xy 31.281593 -375.512236) (xy 31.320327 -375.590025) (xy 31.351719 -375.671057) (xy 31.3755 -375.754639)
			(xy 31.391468 -375.840059) (xy 31.399486 -375.926588) (xy 31.399988 -375.970038) (xy 31.399486 -376.013488)
			(xy 31.391468 -376.100017) (xy 31.3755 -376.185437) (xy 31.351719 -376.269019) (xy 31.320327 -376.350051)
			(xy 31.281593 -376.42784) (xy 31.235846 -376.501724) (xy 31.183477 -376.571071) (xy 31.124933 -376.635291)
			(xy 31.060713 -376.693835) (xy 30.991366 -376.746204) (xy 30.917482 -376.791951) (xy 30.839693 -376.830685)
			(xy 30.758661 -376.862077) (xy 30.675079 -376.885858) (xy 30.589659 -376.901826) (xy 30.50313 -376.909844)
			(xy 30.41623 -376.909844) (xy 30.329701 -376.901826) (xy 30.244281 -376.885858) (xy 30.160699 -376.862077)
			(xy 30.079667 -376.830685) (xy 30.001878 -376.791951) (xy 29.927994 -376.746204) (xy 29.858647 -376.693835)
			(xy 29.794427 -376.635291) (xy 29.735883 -376.571071) (xy 29.683514 -376.501724) (xy 29.637767 -376.42784)
			(xy 29.599033 -376.350051) (xy 29.567641 -376.269019) (xy 29.54386 -376.185437) (xy 29.527892 -376.100017)
			(xy 29.519874 -376.013488) (xy 27.947128 -376.013488) (xy 29.59608 -377.66244) (xy 29.59608 -389.671296)
			(xy 65.896585 -389.671296) (xy 65.900473 -389.616941) (xy 65.912058 -389.563693) (xy 65.931103 -389.512636)
			(xy 65.957221 -389.464808) (xy 65.989879 -389.421185) (xy 66.028414 -389.382654) (xy 66.072041 -389.35)
			(xy 66.119871 -389.323887) (xy 66.17093 -389.304847) (xy 66.22418 -389.293267) (xy 66.278535 -389.289385)
			(xy 66.33289 -389.293277) (xy 66.386137 -389.304866) (xy 66.437193 -389.323916) (xy 66.485018 -389.350038)
			(xy 66.507106 -389.365998) (xy 66.526118 -389.379594) (xy 66.568001 -389.400326) (xy 66.612969 -389.413052)
			(xy 66.659506 -389.417342) (xy 66.706043 -389.413052) (xy 66.751011 -389.400326) (xy 66.792894 -389.379594)
			(xy 66.811906 -389.365998) (xy 66.833988 -389.35003) (xy 66.881814 -389.32391) (xy 66.93287 -389.304862)
			(xy 66.986117 -389.293274) (xy 67.040472 -389.289382) (xy 67.094827 -389.293266) (xy 67.148076 -389.304846)
			(xy 67.199135 -389.323886) (xy 67.246964 -389.35) (xy 67.29059 -389.382655) (xy 67.329124 -389.421186)
			(xy 67.361783 -389.464809) (xy 67.3879 -389.512636) (xy 67.406945 -389.563694) (xy 67.41853 -389.616942)
			(xy 67.422418 -389.671296) (xy 67.825667 -389.671296) (xy 67.829555 -389.616937) (xy 67.841141 -389.563685)
			(xy 67.860188 -389.512624) (xy 67.886309 -389.464793) (xy 67.918971 -389.421167) (xy 67.95751 -389.382634)
			(xy 68.00114 -389.349979) (xy 68.048975 -389.323865) (xy 68.100039 -389.304825) (xy 68.153292 -389.293247)
			(xy 68.207652 -389.289367) (xy 68.262011 -389.293262) (xy 68.315262 -389.304855) (xy 68.36632 -389.323908)
			(xy 68.414147 -389.350035) (xy 68.436236 -389.365998) (xy 68.455248 -389.379594) (xy 68.497131 -389.400326)
			(xy 68.542099 -389.413052) (xy 68.588636 -389.417342) (xy 68.635173 -389.413052) (xy 68.680141 -389.400326)
			(xy 68.722024 -389.379594) (xy 68.741036 -389.365998) (xy 68.76318 -389.350021) (xy 68.811092 -389.323831)
			(xy 68.86225 -389.304744) (xy 68.915608 -389.293149) (xy 68.970074 -389.289283) (xy 69.024534 -389.293227)
			(xy 69.077875 -389.304898) (xy 69.129006 -389.324059) (xy 69.176881 -389.350317) (xy 69.220521 -389.383136)
			(xy 69.259033 -389.421844) (xy 69.275706 -389.443468) (xy 69.289495 -389.461221) (xy 69.322262 -389.491988)
			(xy 69.359932 -389.51651) (xy 69.401328 -389.534023) (xy 69.445159 -389.54398) (xy 69.490058 -389.546071)
			(xy 69.534625 -389.54023) (xy 69.57747 -389.52664) (xy 69.617255 -389.505724) (xy 69.65274 -389.478135)
			(xy 69.668136 -389.461756) (xy 69.687455 -389.441144) (xy 69.731039 -389.405207) (xy 69.779446 -389.37609)
			(xy 69.831618 -389.354431) (xy 69.886414 -389.340702) (xy 69.942635 -389.335204) (xy 69.999052 -389.338058)
			(xy 70.054432 -389.3492) (xy 70.107562 -389.368388) (xy 70.157283 -389.395201) (xy 70.1802 -389.411718)
			(xy 70.199212 -389.425314) (xy 70.241095 -389.446046) (xy 70.286063 -389.458772) (xy 70.3326 -389.463062)
			(xy 70.379137 -389.458772) (xy 70.424105 -389.446046) (xy 70.465988 -389.425314) (xy 70.485 -389.411718)
			(xy 70.507064 -389.395723) (xy 70.554891 -389.369599) (xy 70.605949 -389.350548) (xy 70.659199 -389.338957)
			(xy 70.713556 -389.335063) (xy 70.767915 -389.338944) (xy 70.821167 -389.350523) (xy 70.87223 -389.369563)
			(xy 70.920063 -389.395676) (xy 70.963692 -389.428331) (xy 71.00223 -389.466863) (xy 71.034892 -389.510487)
			(xy 71.061013 -389.558316) (xy 71.08006 -389.609376) (xy 71.091647 -389.662627) (xy 71.095537 -389.716984)
			(xy 71.498786 -389.716984) (xy 71.502676 -389.662629) (xy 71.514263 -389.60938) (xy 71.533311 -389.558322)
			(xy 71.559431 -389.510495) (xy 71.592093 -389.466872) (xy 71.63063 -389.428343) (xy 71.674259 -389.39569)
			(xy 71.722091 -389.369579) (xy 71.773153 -389.350542) (xy 71.826404 -389.338966) (xy 71.880761 -389.335086)
			(xy 71.935116 -389.338983) (xy 71.988364 -389.350576) (xy 72.039419 -389.369629) (xy 72.087243 -389.395755)
			(xy 72.10933 -389.411718) (xy 72.128342 -389.425314) (xy 72.170225 -389.446046) (xy 72.215193 -389.458772)
			(xy 72.26173 -389.463062) (xy 72.308267 -389.458772) (xy 72.353235 -389.446046) (xy 72.395118 -389.425314)
			(xy 72.41413 -389.411718) (xy 72.436193 -389.395726) (xy 72.484018 -389.369606) (xy 72.535073 -389.350559)
			(xy 72.58832 -389.338972) (xy 72.642673 -389.335081) (xy 72.697027 -389.338964) (xy 72.750276 -389.350544)
			(xy 72.801334 -389.369584) (xy 72.849162 -389.395697) (xy 72.892788 -389.42835) (xy 72.931322 -389.46688)
			(xy 72.96398 -389.510502) (xy 72.990098 -389.558328) (xy 73.009144 -389.609384) (xy 73.02073 -389.662631)
			(xy 73.024619 -389.716984) (xy 73.020734 -389.771338) (xy 73.009153 -389.824586) (xy 72.990111 -389.875644)
			(xy 72.963997 -389.923471) (xy 72.931342 -389.967096) (xy 72.892811 -390.005629) (xy 72.849188 -390.038286)
			(xy 72.801362 -390.064403) (xy 72.750305 -390.083447) (xy 72.697058 -390.095031) (xy 72.642705 -390.098919)
			(xy 72.588351 -390.095032) (xy 72.535103 -390.08345) (xy 72.484046 -390.064407) (xy 72.436219 -390.038291)
			(xy 72.41413 -390.022334) (xy 72.395118 -390.008738) (xy 72.353235 -389.988006) (xy 72.308267 -389.97528)
			(xy 72.26173 -389.97099) (xy 72.215193 -389.97528) (xy 72.170225 -389.988006) (xy 72.128342 -390.008738)
			(xy 72.10933 -390.022334) (xy 72.087217 -390.038261) (xy 72.039391 -390.064384) (xy 71.988334 -390.083433)
			(xy 71.935085 -390.095022) (xy 71.88073 -390.098914) (xy 71.826373 -390.09503) (xy 71.773123 -390.08345)
			(xy 71.722063 -390.064408) (xy 71.674233 -390.038293) (xy 71.630607 -390.005637) (xy 71.592072 -389.967104)
			(xy 71.559414 -389.923479) (xy 71.533298 -389.87565) (xy 71.514254 -389.82459) (xy 71.502672 -389.771341)
			(xy 71.498786 -389.716984) (xy 71.095537 -389.716984) (xy 71.091652 -389.771342) (xy 71.080069 -389.824594)
			(xy 71.061026 -389.875655) (xy 71.034909 -389.923486) (xy 71.002251 -389.967114) (xy 70.963716 -390.005649)
			(xy 70.920089 -390.038307) (xy 70.872258 -390.064424) (xy 70.821197 -390.083468) (xy 70.767946 -390.095051)
			(xy 70.713588 -390.098937) (xy 70.65923 -390.095048) (xy 70.605979 -390.083461) (xy 70.554919 -390.064414)
			(xy 70.50709 -390.038294) (xy 70.485 -390.022334) (xy 70.465988 -390.008738) (xy 70.424105 -389.988006)
			(xy 70.379137 -389.97528) (xy 70.3326 -389.97099) (xy 70.286063 -389.97528) (xy 70.241095 -389.988006)
			(xy 70.199212 -390.008738) (xy 70.1802 -390.022334) (xy 70.158114 -390.038396) (xy 70.110193 -390.064588)
			(xy 70.059025 -390.083675) (xy 70.005657 -390.095267) (xy 69.951182 -390.099127) (xy 69.896713 -390.095176)
			(xy 69.843365 -390.083495) (xy 69.792229 -390.064323) (xy 69.744351 -390.038051) (xy 69.700711 -390.005218)
			(xy 69.662201 -389.966495) (xy 69.64553 -389.944864) (xy 69.631699 -389.927145) (xy 69.598939 -389.896375)
			(xy 69.561277 -389.871849) (xy 69.519887 -389.854332) (xy 69.47606 -389.844371) (xy 69.431165 -389.842277)
			(xy 69.386601 -389.848114) (xy 69.34376 -389.8617) (xy 69.303978 -389.882613) (xy 69.268495 -389.910199)
			(xy 69.2531 -389.926576) (xy 69.233843 -389.947247) (xy 69.190248 -389.983181) (xy 69.141831 -390.012293)
			(xy 69.08965 -390.033947) (xy 69.034847 -390.04767) (xy 68.978619 -390.053161) (xy 68.922196 -390.0503)
			(xy 68.866812 -390.03915) (xy 68.813677 -390.019955) (xy 68.763954 -389.993135) (xy 68.741036 -389.976614)
			(xy 68.722024 -389.963018) (xy 68.680141 -389.942286) (xy 68.635173 -389.92956) (xy 68.588636 -389.92527)
			(xy 68.542099 -389.92956) (xy 68.497131 -389.942286) (xy 68.455248 -389.963018) (xy 68.436236 -389.976614)
			(xy 68.414141 -389.992569) (xy 68.366314 -390.018695) (xy 68.315255 -390.037747) (xy 68.262004 -390.049339)
			(xy 68.207645 -390.053233) (xy 68.153285 -390.049352) (xy 68.100032 -390.037772) (xy 68.048968 -390.018732)
			(xy 68.001134 -389.992617) (xy 67.957504 -389.959961) (xy 67.918966 -389.921427) (xy 67.886305 -389.877801)
			(xy 67.860185 -389.82997) (xy 67.841139 -389.778908) (xy 67.829554 -389.725656) (xy 67.825667 -389.671296)
			(xy 67.422418 -389.671296) (xy 67.418531 -389.725651) (xy 67.406947 -389.778899) (xy 67.387903 -389.829957)
			(xy 67.361787 -389.877785) (xy 67.329129 -389.921409) (xy 67.290595 -389.959941) (xy 67.24697 -389.992596)
			(xy 67.199141 -390.018711) (xy 67.148083 -390.037752) (xy 67.094834 -390.049333) (xy 67.040479 -390.053218)
			(xy 66.986124 -390.049327) (xy 66.932877 -390.03774) (xy 66.88182 -390.018693) (xy 66.833994 -389.992573)
			(xy 66.811906 -389.976614) (xy 66.792894 -389.963018) (xy 66.751011 -389.942286) (xy 66.706043 -389.92956)
			(xy 66.659506 -389.92527) (xy 66.612969 -389.92956) (xy 66.568001 -389.942286) (xy 66.526118 -389.963018)
			(xy 66.507106 -389.976614) (xy 66.485012 -389.992566) (xy 66.437186 -390.018687) (xy 66.38613 -390.037736)
			(xy 66.332883 -390.049324) (xy 66.278528 -390.053215) (xy 66.224173 -390.049332) (xy 66.170923 -390.037751)
			(xy 66.119864 -390.01871) (xy 66.072035 -389.992596) (xy 66.028409 -389.959941) (xy 65.989875 -389.921409)
			(xy 65.957217 -389.877786) (xy 65.9311 -389.829958) (xy 65.912056 -389.7789) (xy 65.900472 -389.725651)
			(xy 65.896585 -389.671296) (xy 29.59608 -389.671296) (xy 29.59608 -391.428018) (xy 65.896556 -391.428018)
			(xy 65.900441 -391.373659) (xy 65.912024 -391.320406) (xy 65.931067 -391.269343) (xy 65.957185 -391.221511)
			(xy 65.989843 -391.177883) (xy 66.028379 -391.139346) (xy 66.072007 -391.106687) (xy 66.119839 -391.080569)
			(xy 66.170901 -391.061525) (xy 66.224154 -391.049942) (xy 66.278513 -391.046056) (xy 66.332872 -391.049946)
			(xy 66.386124 -391.061533) (xy 66.437185 -391.080581) (xy 66.485016 -391.106702) (xy 66.507106 -391.122662)
			(xy 66.526118 -391.136258) (xy 66.568001 -391.15699) (xy 66.612969 -391.169716) (xy 66.659506 -391.174006)
			(xy 66.706043 -391.169716) (xy 66.751011 -391.15699) (xy 66.792894 -391.136258) (xy 66.811906 -391.122662)
			(xy 66.834022 -391.106743) (xy 66.881845 -391.080627) (xy 66.932899 -391.061583) (xy 66.986143 -391.049999)
			(xy 67.040493 -391.046111) (xy 67.094844 -391.049998) (xy 67.148088 -391.06158) (xy 67.199142 -391.080622)
			(xy 67.246967 -391.106736) (xy 67.290588 -391.139391) (xy 67.329117 -391.177921) (xy 67.36177 -391.221543)
			(xy 67.387883 -391.269368) (xy 67.406924 -391.320422) (xy 67.418504 -391.373667) (xy 67.422389 -391.428018)
			(xy 67.825638 -391.428018) (xy 67.829524 -391.373655) (xy 67.841107 -391.320398) (xy 67.860153 -391.269332)
			(xy 67.886273 -391.221496) (xy 67.918935 -391.177865) (xy 67.957474 -391.139327) (xy 68.001107 -391.106666)
			(xy 68.048943 -391.080548) (xy 68.10001 -391.061504) (xy 68.153267 -391.049922) (xy 68.207631 -391.046038)
			(xy 68.261993 -391.049931) (xy 68.315249 -391.061521) (xy 68.366313 -391.080573) (xy 68.414145 -391.106699)
			(xy 68.436236 -391.122662) (xy 68.455248 -391.136258) (xy 68.497131 -391.15699) (xy 68.542099 -391.169716)
			(xy 68.588636 -391.174006) (xy 68.635173 -391.169716) (xy 68.680141 -391.15699) (xy 68.722024 -391.136258)
			(xy 68.741036 -391.122662) (xy 68.763171 -391.106671) (xy 68.811084 -391.080477) (xy 68.862244 -391.061385)
			(xy 68.915604 -391.049788) (xy 68.970072 -391.045922) (xy 69.024535 -391.049866) (xy 69.077879 -391.061539)
			(xy 69.129011 -391.080703) (xy 69.176886 -391.106966) (xy 69.220525 -391.139791) (xy 69.259035 -391.178505)
			(xy 69.275706 -391.200132) (xy 69.289496 -391.217885) (xy 69.322261 -391.248656) (xy 69.35993 -391.273182)
			(xy 69.401326 -391.290697) (xy 69.445159 -391.300656) (xy 69.490059 -391.302747) (xy 69.534627 -391.296905)
			(xy 69.577472 -391.283312) (xy 69.617257 -391.262393) (xy 69.652741 -391.234801) (xy 69.668136 -391.21842)
			(xy 69.687452 -391.197806) (xy 69.731038 -391.161872) (xy 69.779446 -391.132758) (xy 69.831618 -391.1111)
			(xy 69.886414 -391.097373) (xy 69.942634 -391.091876) (xy 69.999051 -391.094729) (xy 70.05443 -391.10587)
			(xy 70.107561 -391.125056) (xy 70.157282 -391.151866) (xy 70.1802 -391.168382) (xy 70.199212 -391.181978)
			(xy 70.241095 -391.20271) (xy 70.286063 -391.215436) (xy 70.3326 -391.219726) (xy 70.379137 -391.215436)
			(xy 70.424105 -391.20271) (xy 70.465988 -391.181978) (xy 70.485 -391.168382) (xy 70.507098 -391.152436)
			(xy 70.554922 -391.126316) (xy 70.605978 -391.107269) (xy 70.659224 -391.095682) (xy 70.713578 -391.091791)
			(xy 70.767932 -391.095676) (xy 70.82118 -391.107257) (xy 70.872237 -391.126298) (xy 70.920065 -391.152412)
			(xy 70.96369 -391.185067) (xy 71.002223 -391.223598) (xy 71.03488 -391.267221) (xy 71.060996 -391.315048)
			(xy 71.080039 -391.366105) (xy 71.091622 -391.419352) (xy 71.095509 -391.473706) (xy 71.498757 -391.473706)
			(xy 71.502645 -391.419346) (xy 71.514229 -391.366092) (xy 71.533275 -391.31503) (xy 71.559395 -391.267198)
			(xy 71.592057 -391.22357) (xy 71.630595 -391.185035) (xy 71.674225 -391.152377) (xy 71.72206 -391.126262)
			(xy 71.773124 -391.10722) (xy 71.826379 -391.09564) (xy 71.880739 -391.091757) (xy 71.935099 -391.095651)
			(xy 71.988351 -391.107242) (xy 72.039411 -391.126294) (xy 72.08724 -391.15242) (xy 72.10933 -391.168382)
			(xy 72.128342 -391.181978) (xy 72.170225 -391.20271) (xy 72.215193 -391.215436) (xy 72.26173 -391.219726)
			(xy 72.308267 -391.215436) (xy 72.353235 -391.20271) (xy 72.395118 -391.181978) (xy 72.41413 -391.168382)
			(xy 72.436227 -391.152438) (xy 72.48405 -391.126323) (xy 72.535102 -391.107281) (xy 72.588345 -391.095697)
			(xy 72.642695 -391.091809) (xy 72.697045 -391.095696) (xy 72.750288 -391.107278) (xy 72.801341 -391.126319)
			(xy 72.849165 -391.152433) (xy 72.892785 -391.185086) (xy 72.931314 -391.223616) (xy 72.963968 -391.267236)
			(xy 72.990081 -391.31506) (xy 73.009122 -391.366113) (xy 73.020704 -391.419356) (xy 73.024591 -391.473706)
			(xy 73.020702 -391.528056) (xy 73.009119 -391.581299) (xy 72.990076 -391.632351) (xy 72.963961 -391.680174)
			(xy 72.931306 -391.723793) (xy 72.892776 -391.762321) (xy 72.849155 -391.794974) (xy 72.80133 -391.821086)
			(xy 72.750277 -391.840126) (xy 72.697033 -391.851706) (xy 72.642683 -391.855591) (xy 72.588334 -391.851701)
			(xy 72.535091 -391.840116) (xy 72.484039 -391.821072) (xy 72.436217 -391.794955) (xy 72.41413 -391.778998)
			(xy 72.395118 -391.765402) (xy 72.353235 -391.74467) (xy 72.308267 -391.731944) (xy 72.26173 -391.727654)
			(xy 72.215193 -391.731944) (xy 72.170225 -391.74467) (xy 72.128342 -391.765402) (xy 72.10933 -391.778998)
			(xy 72.087251 -391.794974) (xy 72.039422 -391.821101) (xy 71.988363 -391.840154) (xy 71.935111 -391.851747)
			(xy 71.880751 -391.855643) (xy 71.82639 -391.851762) (xy 71.773136 -391.840183) (xy 71.722071 -391.821143)
			(xy 71.674235 -391.795029) (xy 71.630604 -391.762373) (xy 71.592064 -391.723839) (xy 71.559402 -391.680213)
			(xy 71.53328 -391.632381) (xy 71.514233 -391.581319) (xy 71.502647 -391.528066) (xy 71.498757 -391.473706)
			(xy 71.095509 -391.473706) (xy 71.09162 -391.52806) (xy 71.080035 -391.581307) (xy 71.060991 -391.632363)
			(xy 71.034873 -391.680189) (xy 71.002215 -391.723811) (xy 70.963681 -391.762341) (xy 70.920055 -391.794995)
			(xy 70.872227 -391.821107) (xy 70.821168 -391.840147) (xy 70.76792 -391.851726) (xy 70.713566 -391.855609)
			(xy 70.659213 -391.851716) (xy 70.605966 -391.840128) (xy 70.554912 -391.821079) (xy 70.507087 -391.794958)
			(xy 70.485 -391.778998) (xy 70.465988 -391.765402) (xy 70.424105 -391.74467) (xy 70.379137 -391.731944)
			(xy 70.3326 -391.727654) (xy 70.286063 -391.731944) (xy 70.241095 -391.74467) (xy 70.199212 -391.765402)
			(xy 70.1802 -391.778998) (xy 70.158106 -391.795047) (xy 70.110185 -391.821233) (xy 70.059018 -391.840317)
			(xy 70.005653 -391.851906) (xy 69.95118 -391.855766) (xy 69.896714 -391.851815) (xy 69.843368 -391.840136)
			(xy 69.792234 -391.820967) (xy 69.744356 -391.7947) (xy 69.700715 -391.761873) (xy 69.662203 -391.723156)
			(xy 69.64553 -391.701528) (xy 69.631699 -391.68381) (xy 69.598938 -391.653044) (xy 69.561275 -391.628521)
			(xy 69.519885 -391.611007) (xy 69.47606 -391.601047) (xy 69.431166 -391.598952) (xy 69.386603 -391.604789)
			(xy 69.343763 -391.618373) (xy 69.30398 -391.639283) (xy 69.268496 -391.666865) (xy 69.2531 -391.68324)
			(xy 69.23384 -391.70391) (xy 69.190247 -391.739846) (xy 69.141831 -391.768961) (xy 69.08965 -391.790617)
			(xy 69.034847 -391.80434) (xy 68.978618 -391.809832) (xy 68.922195 -391.806971) (xy 68.86681 -391.79582)
			(xy 68.813676 -391.776623) (xy 68.763954 -391.7498) (xy 68.741036 -391.733278) (xy 68.722024 -391.719682)
			(xy 68.680141 -391.69895) (xy 68.635173 -391.686224) (xy 68.588636 -391.681934) (xy 68.542099 -391.686224)
			(xy 68.497131 -391.69895) (xy 68.455248 -391.719682) (xy 68.436236 -391.733278) (xy 68.414175 -391.749281)
			(xy 68.366345 -391.775412) (xy 68.315283 -391.794469) (xy 68.262029 -391.806064) (xy 68.207667 -391.809962)
			(xy 68.153303 -391.806083) (xy 68.100044 -391.794506) (xy 68.048976 -391.775467) (xy 68.001137 -391.749353)
			(xy 67.957502 -391.716697) (xy 67.918959 -391.678162) (xy 67.886292 -391.634534) (xy 67.860168 -391.586701)
			(xy 67.841118 -391.535637) (xy 67.829529 -391.482381) (xy 67.825638 -391.428018) (xy 67.422389 -391.428018)
			(xy 67.418499 -391.482368) (xy 67.406913 -391.535612) (xy 67.387868 -391.586665) (xy 67.361751 -391.634487)
			(xy 67.329093 -391.678106) (xy 67.29056 -391.716633) (xy 67.246936 -391.749284) (xy 67.19911 -391.775393)
			(xy 67.148054 -391.79443) (xy 67.094808 -391.806008) (xy 67.040457 -391.809889) (xy 66.986107 -391.805995)
			(xy 66.932864 -391.794406) (xy 66.881813 -391.775358) (xy 66.833992 -391.749238) (xy 66.811906 -391.733278)
			(xy 66.792894 -391.719682) (xy 66.751011 -391.69895) (xy 66.706043 -391.686224) (xy 66.659506 -391.681934)
			(xy 66.612969 -391.686224) (xy 66.568001 -391.69895) (xy 66.526118 -391.719682) (xy 66.507106 -391.733278)
			(xy 66.485046 -391.749279) (xy 66.437218 -391.775404) (xy 66.386159 -391.794457) (xy 66.332908 -391.806049)
			(xy 66.278549 -391.809944) (xy 66.22419 -391.806063) (xy 66.170936 -391.794485) (xy 66.119872 -391.775446)
			(xy 66.072037 -391.749332) (xy 66.028406 -391.716677) (xy 65.989867 -391.678145) (xy 65.957204 -391.634519)
			(xy 65.931082 -391.58669) (xy 65.912034 -391.535629) (xy 65.900446 -391.482377) (xy 65.896556 -391.428018)
			(xy 29.59608 -391.428018) (xy 29.59608 -393.194476) (xy 65.896612 -393.194476) (xy 65.900503 -393.140125)
			(xy 65.912089 -393.086881) (xy 65.931136 -393.035828) (xy 65.957254 -392.988006) (xy 65.989913 -392.944388)
			(xy 66.028448 -392.905861) (xy 66.072073 -392.873211) (xy 66.119901 -392.847103) (xy 66.170957 -392.828067)
			(xy 66.224204 -392.816491) (xy 66.278555 -392.812612) (xy 66.332906 -392.816507) (xy 66.386149 -392.828098)
			(xy 66.4372 -392.847149) (xy 66.485021 -392.873271) (xy 66.507106 -392.889232) (xy 66.526118 -392.902828)
			(xy 66.568001 -392.92356) (xy 66.612969 -392.936286) (xy 66.659506 -392.940576) (xy 66.706043 -392.936286)
			(xy 66.751011 -392.92356) (xy 66.792894 -392.902828) (xy 66.811906 -392.889232) (xy 66.833957 -392.873219)
			(xy 66.881784 -392.847094) (xy 66.932843 -392.828041) (xy 66.986093 -392.81645) (xy 67.040451 -392.812555)
			(xy 67.094811 -392.816436) (xy 67.148064 -392.828014) (xy 67.199128 -392.847053) (xy 67.246962 -392.873166)
			(xy 67.290592 -392.905821) (xy 67.329132 -392.944353) (xy 67.361795 -392.987977) (xy 67.387917 -393.035806)
			(xy 67.406965 -393.086866) (xy 67.418554 -393.140118) (xy 67.422445 -393.194476) (xy 67.825694 -393.194476)
			(xy 67.829585 -393.140121) (xy 67.841173 -393.086873) (xy 67.860221 -393.035817) (xy 67.886343 -392.987991)
			(xy 67.919005 -392.94437) (xy 67.957543 -392.905842) (xy 68.001172 -392.87319) (xy 68.049004 -392.847081)
			(xy 68.100066 -392.828046) (xy 68.153317 -392.816471) (xy 68.207673 -392.812594) (xy 68.262027 -392.816492)
			(xy 68.315273 -392.828087) (xy 68.366328 -392.847142) (xy 68.41415 -392.873269) (xy 68.436236 -392.889232)
			(xy 68.455248 -392.902828) (xy 68.497131 -392.92356) (xy 68.542099 -392.936286) (xy 68.588636 -392.940576)
			(xy 68.635173 -392.936286) (xy 68.680141 -392.92356) (xy 68.722024 -392.902828) (xy 68.741036 -392.889232)
			(xy 68.763175 -392.873247) (xy 68.811088 -392.847055) (xy 68.862247 -392.827966) (xy 68.915606 -392.816369)
			(xy 68.970073 -392.812504) (xy 69.024535 -392.816447) (xy 69.077877 -392.82812) (xy 69.129009 -392.847283)
			(xy 69.176884 -392.873543) (xy 69.220523 -392.906365) (xy 69.259034 -392.945076) (xy 69.275706 -392.966702)
			(xy 69.289496 -392.984455) (xy 69.32226 -393.015229) (xy 69.359928 -393.039758) (xy 69.401325 -393.057276)
			(xy 69.445158 -393.067235) (xy 69.49006 -393.069326) (xy 69.534629 -393.063484) (xy 69.577474 -393.04989)
			(xy 69.617259 -393.028968) (xy 69.652742 -393.001372) (xy 69.668136 -392.98499) (xy 69.68745 -392.964375)
			(xy 69.731038 -392.928443) (xy 69.779446 -392.899331) (xy 69.831619 -392.877675) (xy 69.886414 -392.863949)
			(xy 69.942634 -392.858452) (xy 69.99905 -392.861304) (xy 70.054429 -392.872445) (xy 70.10756 -392.891629)
			(xy 70.157282 -392.918437) (xy 70.1802 -392.934952) (xy 70.199212 -392.948548) (xy 70.241095 -392.96928)
			(xy 70.286063 -392.982006) (xy 70.3326 -392.986296) (xy 70.379137 -392.982006) (xy 70.424105 -392.96928)
			(xy 70.465988 -392.948548) (xy 70.485 -392.934952) (xy 70.507126 -392.919046) (xy 70.554949 -392.89293)
			(xy 70.606002 -392.873887) (xy 70.659246 -392.862303) (xy 70.713596 -392.858415) (xy 70.767946 -392.862302)
			(xy 70.82119 -392.873885) (xy 70.872244 -392.892927) (xy 70.920068 -392.919042) (xy 70.963688 -392.951697)
			(xy 71.002216 -392.990227) (xy 71.034869 -393.033849) (xy 71.060981 -393.081674) (xy 71.080021 -393.132729)
			(xy 71.091601 -393.185973) (xy 71.095485 -393.240324) (xy 71.498733 -393.240324) (xy 71.502619 -393.18596)
			(xy 71.514201 -393.132703) (xy 71.533246 -393.081636) (xy 71.559365 -393.0338) (xy 71.592027 -392.990168)
			(xy 71.630566 -392.951629) (xy 71.674197 -392.918967) (xy 71.722033 -392.892847) (xy 71.7731 -392.873802)
			(xy 71.826357 -392.862219) (xy 71.880721 -392.858333) (xy 71.935084 -392.862225) (xy 71.988341 -392.873814)
			(xy 72.039405 -392.892865) (xy 72.087238 -392.91899) (xy 72.10933 -392.934952) (xy 72.128342 -392.948548)
			(xy 72.170225 -392.96928) (xy 72.215193 -392.982006) (xy 72.26173 -392.986296) (xy 72.308267 -392.982006)
			(xy 72.353235 -392.96928) (xy 72.395118 -392.948548) (xy 72.41413 -392.934952) (xy 72.436255 -392.919049)
			(xy 72.484076 -392.892938) (xy 72.535126 -392.873899) (xy 72.588367 -392.862319) (xy 72.642713 -392.858433)
			(xy 72.697059 -392.862322) (xy 72.750299 -392.873906) (xy 72.801348 -392.892949) (xy 72.849167 -392.919063)
			(xy 72.892783 -392.951716) (xy 72.931308 -392.990245) (xy 72.963957 -393.033864) (xy 72.990067 -393.081686)
			(xy 73.009104 -393.132737) (xy 73.020683 -393.185977) (xy 73.024567 -393.240324) (xy 73.020676 -393.29467)
			(xy 73.009091 -393.347909) (xy 72.990047 -393.398958) (xy 72.963931 -393.446776) (xy 72.931276 -393.490391)
			(xy 72.892747 -393.528915) (xy 72.849127 -393.561563) (xy 72.801304 -393.587671) (xy 72.750253 -393.606708)
			(xy 72.697012 -393.618285) (xy 72.642665 -393.622167) (xy 72.588319 -393.618275) (xy 72.53508 -393.606688)
			(xy 72.484032 -393.587642) (xy 72.436215 -393.561525) (xy 72.41413 -393.545568) (xy 72.395118 -393.531972)
			(xy 72.353235 -393.51124) (xy 72.308267 -393.498514) (xy 72.26173 -393.494224) (xy 72.215193 -393.498514)
			(xy 72.170225 -393.51124) (xy 72.128342 -393.531972) (xy 72.10933 -393.545568) (xy 72.087279 -393.561584)
			(xy 72.039449 -393.587715) (xy 71.988387 -393.606772) (xy 71.935132 -393.618368) (xy 71.880769 -393.622267)
			(xy 71.826405 -393.618388) (xy 71.773146 -393.606811) (xy 71.722077 -393.587773) (xy 71.674238 -393.561659)
			(xy 71.630602 -393.529003) (xy 71.592058 -393.490469) (xy 71.559391 -393.446841) (xy 71.533266 -393.399008)
			(xy 71.514215 -393.347943) (xy 71.502625 -393.294687) (xy 71.498733 -393.240324) (xy 71.095485 -393.240324)
			(xy 71.091594 -393.294674) (xy 71.080007 -393.347917) (xy 71.060961 -393.398969) (xy 71.034843 -393.446791)
			(xy 71.002185 -393.490409) (xy 70.963651 -393.528935) (xy 70.920027 -393.561584) (xy 70.8722 -393.587693)
			(xy 70.821144 -393.606729) (xy 70.767899 -393.618305) (xy 70.713548 -393.622184) (xy 70.659198 -393.61829)
			(xy 70.605956 -393.606699) (xy 70.554905 -393.58765) (xy 70.507085 -393.561528) (xy 70.485 -393.545568)
			(xy 70.465988 -393.531972) (xy 70.424105 -393.51124) (xy 70.379137 -393.498514) (xy 70.3326 -393.494224)
			(xy 70.286063 -393.498514) (xy 70.241095 -393.51124) (xy 70.199212 -393.531972) (xy 70.1802 -393.545568)
			(xy 70.15811 -393.561623) (xy 70.110188 -393.587812) (xy 70.059021 -393.606897) (xy 70.005655 -393.618488)
			(xy 69.951181 -393.622348) (xy 69.896713 -393.618397) (xy 69.843366 -393.606717) (xy 69.792231 -393.587546)
			(xy 69.744354 -393.561277) (xy 69.700713 -393.528447) (xy 69.662202 -393.489728) (xy 69.64553 -393.468098)
			(xy 69.631698 -393.450379) (xy 69.59894 -393.419605) (xy 69.561279 -393.395076) (xy 69.519888 -393.377557)
			(xy 69.476061 -393.367594) (xy 69.431164 -393.365499) (xy 69.3866 -393.371337) (xy 69.343758 -393.384926)
			(xy 69.303975 -393.405842) (xy 69.268494 -393.433431) (xy 69.2531 -393.44981) (xy 69.233845 -393.470483)
			(xy 69.190249 -393.506414) (xy 69.141831 -393.535524) (xy 69.08965 -393.557176) (xy 69.034847 -393.570897)
			(xy 68.978619 -393.576388) (xy 68.922197 -393.573528) (xy 68.866813 -393.562379) (xy 68.813679 -393.543186)
			(xy 68.763955 -393.516368) (xy 68.741036 -393.499848) (xy 68.722024 -393.486252) (xy 68.680141 -393.46552)
			(xy 68.635173 -393.452794) (xy 68.588636 -393.448504) (xy 68.542099 -393.452794) (xy 68.497131 -393.46552)
			(xy 68.455248 -393.486252) (xy 68.436236 -393.499848) (xy 68.414109 -393.515757) (xy 68.366284 -393.541878)
			(xy 68.315227 -393.560927) (xy 68.26198 -393.572515) (xy 68.207625 -393.576406) (xy 68.153269 -393.572522)
			(xy 68.10002 -393.560941) (xy 68.048961 -393.541899) (xy 68.001132 -393.515784) (xy 67.957507 -393.483127)
			(xy 67.918973 -393.444594) (xy 67.886317 -393.400969) (xy 67.860202 -393.35314) (xy 67.84116 -393.302081)
			(xy 67.829578 -393.248832) (xy 67.825694 -393.194476) (xy 67.422445 -393.194476) (xy 67.41856 -393.248835)
			(xy 67.406979 -393.302088) (xy 67.387937 -393.35315) (xy 67.361821 -393.400982) (xy 67.329163 -393.444611)
			(xy 67.290629 -393.483148) (xy 67.247002 -393.515808) (xy 67.199171 -393.541927) (xy 67.14811 -393.560972)
			(xy 67.094858 -393.572557) (xy 67.040499 -393.576445) (xy 66.986141 -393.572557) (xy 66.932889 -393.560972)
			(xy 66.881828 -393.541926) (xy 66.833997 -393.515807) (xy 66.811906 -393.499848) (xy 66.792894 -393.486252)
			(xy 66.751011 -393.46552) (xy 66.706043 -393.452794) (xy 66.659506 -393.448504) (xy 66.612969 -393.452794)
			(xy 66.568001 -393.46552) (xy 66.526118 -393.486252) (xy 66.507106 -393.499848) (xy 66.48498 -393.515755)
			(xy 66.437157 -393.541871) (xy 66.386103 -393.560915) (xy 66.332859 -393.5725) (xy 66.278507 -393.576388)
			(xy 66.224156 -393.572502) (xy 66.170911 -393.560919) (xy 66.119857 -393.541877) (xy 66.072032 -393.515763)
			(xy 66.028411 -393.483107) (xy 65.989882 -393.444576) (xy 65.957228 -393.400954) (xy 65.931116 -393.353128)
			(xy 65.912076 -393.302073) (xy 65.900496 -393.248827) (xy 65.896612 -393.194476) (xy 29.59608 -393.194476)
			(xy 29.59608 -395.588913) (xy 47.708556 -395.588913) (xy 47.708556 -395.507803) (xy 47.716506 -395.427084)
			(xy 47.732329 -395.347533) (xy 47.755874 -395.269917) (xy 47.786913 -395.194981) (xy 47.825148 -395.123449)
			(xy 47.87021 -395.056009) (xy 47.921665 -394.99331) (xy 47.979018 -394.935957) (xy 48.041717 -394.884502)
			(xy 48.109157 -394.83944) (xy 48.180689 -394.801205) (xy 48.255625 -394.770166) (xy 48.333241 -394.746621)
			(xy 48.412792 -394.730798) (xy 48.493511 -394.722848) (xy 48.574621 -394.722848) (xy 48.65534 -394.730798)
			(xy 48.734891 -394.746621) (xy 48.812507 -394.770166) (xy 48.887443 -394.801205) (xy 48.958975 -394.83944)
			(xy 49.026415 -394.884502) (xy 49.089114 -394.935957) (xy 49.146467 -394.99331) (xy 49.197922 -395.056009)
			(xy 49.242984 -395.123449) (xy 49.281219 -395.194981) (xy 49.312258 -395.269917) (xy 49.335803 -395.347533)
			(xy 49.351626 -395.427084) (xy 49.359576 -395.507803) (xy 49.360074 -395.548358) (xy 49.359576 -395.588913)
			(xy 51.208676 -395.588913) (xy 51.208676 -395.507803) (xy 51.216626 -395.427084) (xy 51.232449 -395.347533)
			(xy 51.255994 -395.269917) (xy 51.287033 -395.194981) (xy 51.325268 -395.123449) (xy 51.37033 -395.056009)
			(xy 51.421785 -394.99331) (xy 51.479138 -394.935957) (xy 51.541837 -394.884502) (xy 51.609277 -394.83944)
			(xy 51.680809 -394.801205) (xy 51.755745 -394.770166) (xy 51.833361 -394.746621) (xy 51.912912 -394.730798)
			(xy 51.993631 -394.722848) (xy 52.074741 -394.722848) (xy 52.15546 -394.730798) (xy 52.235011 -394.746621)
			(xy 52.312627 -394.770166) (xy 52.387563 -394.801205) (xy 52.459095 -394.83944) (xy 52.526535 -394.884502)
			(xy 52.589234 -394.935957) (xy 52.646587 -394.99331) (xy 52.698042 -395.056009) (xy 52.743104 -395.123449)
			(xy 52.781339 -395.194981) (xy 52.812378 -395.269917) (xy 52.835923 -395.347533) (xy 52.851746 -395.427084)
			(xy 52.859696 -395.507803) (xy 52.860194 -395.548358) (xy 52.859696 -395.588913) (xy 52.851746 -395.669632)
			(xy 52.835923 -395.749183) (xy 52.812378 -395.826799) (xy 52.781339 -395.901735) (xy 52.743104 -395.973267)
			(xy 52.698042 -396.040707) (xy 52.646587 -396.103406) (xy 52.589234 -396.160759) (xy 52.526535 -396.212214)
			(xy 52.459095 -396.257276) (xy 52.387563 -396.295511) (xy 52.312627 -396.32655) (xy 52.235011 -396.350095)
			(xy 52.15546 -396.365918) (xy 52.074741 -396.373868) (xy 51.993631 -396.373868) (xy 51.912912 -396.365918)
			(xy 51.833361 -396.350095) (xy 51.755745 -396.32655) (xy 51.680809 -396.295511) (xy 51.609277 -396.257276)
			(xy 51.541837 -396.212214) (xy 51.479138 -396.160759) (xy 51.421785 -396.103406) (xy 51.37033 -396.040707)
			(xy 51.325268 -395.973267) (xy 51.287033 -395.901735) (xy 51.255994 -395.826799) (xy 51.232449 -395.749183)
			(xy 51.216626 -395.669632) (xy 51.208676 -395.588913) (xy 49.359576 -395.588913) (xy 49.351626 -395.669632)
			(xy 49.335803 -395.749183) (xy 49.312258 -395.826799) (xy 49.281219 -395.901735) (xy 49.242984 -395.973267)
			(xy 49.197922 -396.040707) (xy 49.146467 -396.103406) (xy 49.089114 -396.160759) (xy 49.026415 -396.212214)
			(xy 48.958975 -396.257276) (xy 48.887443 -396.295511) (xy 48.812507 -396.32655) (xy 48.734891 -396.350095)
			(xy 48.65534 -396.365918) (xy 48.574621 -396.373868) (xy 48.493511 -396.373868) (xy 48.412792 -396.365918)
			(xy 48.333241 -396.350095) (xy 48.255625 -396.32655) (xy 48.180689 -396.295511) (xy 48.109157 -396.257276)
			(xy 48.041717 -396.212214) (xy 47.979018 -396.160759) (xy 47.921665 -396.103406) (xy 47.87021 -396.040707)
			(xy 47.825148 -395.973267) (xy 47.786913 -395.901735) (xy 47.755874 -395.826799) (xy 47.732329 -395.749183)
			(xy 47.716506 -395.669632) (xy 47.708556 -395.588913) (xy 29.59608 -395.588913) (xy 29.59608 -397.938244)
			(xy 84.320378 -397.938244) (xy 84.324449 -397.882622) (xy 84.336575 -397.828185) (xy 84.356498 -397.776094)
			(xy 84.383794 -397.727459) (xy 84.41788 -397.683316) (xy 84.458029 -397.644607) (xy 84.503387 -397.612156)
			(xy 84.552987 -397.586655) (xy 84.605771 -397.568648) (xy 84.660614 -397.558518) (xy 84.716348 -397.556481)
			(xy 84.771785 -397.562581) (xy 84.825742 -397.576687) (xy 84.877071 -397.598499) (xy 84.924677 -397.627553)
			(xy 84.967545 -397.663228) (xy 85.004762 -397.704765) (xy 85.035535 -397.751278) (xy 85.059207 -397.801775)
			(xy 85.075275 -397.855182) (xy 85.083395 -397.910358) (xy 85.083904 -397.938244) (xy 85.083395 -397.96613)
			(xy 85.075275 -398.021306) (xy 85.059207 -398.074713) (xy 85.035535 -398.12521) (xy 85.004762 -398.171723)
			(xy 84.967545 -398.21326) (xy 84.924677 -398.248935) (xy 84.877071 -398.277989) (xy 84.825742 -398.299801)
			(xy 84.771785 -398.313907) (xy 84.716348 -398.320007) (xy 84.660614 -398.31797) (xy 84.605771 -398.30784)
			(xy 84.552987 -398.289833) (xy 84.503387 -398.264332) (xy 84.458029 -398.231881) (xy 84.41788 -398.193172)
			(xy 84.383794 -398.149029) (xy 84.356498 -398.100394) (xy 84.336575 -398.048303) (xy 84.324449 -397.993866)
			(xy 84.320378 -397.938244) (xy 29.59608 -397.938244) (xy 29.59608 -399.014696) (xy 81.842862 -399.014696)
			(xy 81.846933 -398.959074) (xy 81.859059 -398.904637) (xy 81.878982 -398.852546) (xy 81.906278 -398.803911)
			(xy 81.940364 -398.759768) (xy 81.980513 -398.721059) (xy 82.025871 -398.688608) (xy 82.075471 -398.663107)
			(xy 82.128255 -398.6451) (xy 82.183098 -398.63497) (xy 82.238832 -398.632933) (xy 82.294269 -398.639033)
			(xy 82.348226 -398.653139) (xy 82.399555 -398.674951) (xy 82.447161 -398.704005) (xy 82.490029 -398.73968)
			(xy 82.527246 -398.781217) (xy 82.558019 -398.82773) (xy 82.581691 -398.878227) (xy 82.597759 -398.931634)
			(xy 82.605879 -398.98681) (xy 82.606388 -399.014696) (xy 82.605879 -399.042582) (xy 82.597759 -399.097758)
			(xy 82.581691 -399.151165) (xy 82.558019 -399.201662) (xy 82.527246 -399.248175) (xy 82.490029 -399.289712)
			(xy 82.447161 -399.325387) (xy 82.399555 -399.354441) (xy 82.348226 -399.376253) (xy 82.294269 -399.390359)
			(xy 82.238832 -399.396459) (xy 82.183098 -399.394422) (xy 82.128255 -399.384292) (xy 82.075471 -399.366285)
			(xy 82.025871 -399.340784) (xy 81.980513 -399.308333) (xy 81.940364 -399.269624) (xy 81.906278 -399.225481)
			(xy 81.878982 -399.176846) (xy 81.859059 -399.124755) (xy 81.846933 -399.070318) (xy 81.842862 -399.014696)
			(xy 29.59608 -399.014696) (xy 29.59608 -399.744438) (xy 84.952584 -399.744438) (xy 84.956655 -399.688816)
			(xy 84.968781 -399.634379) (xy 84.988704 -399.582288) (xy 85.016 -399.533653) (xy 85.050086 -399.48951)
			(xy 85.090235 -399.450801) (xy 85.135593 -399.41835) (xy 85.185193 -399.392849) (xy 85.237977 -399.374842)
			(xy 85.29282 -399.364712) (xy 85.348554 -399.362675) (xy 85.403991 -399.368775) (xy 85.457948 -399.382881)
			(xy 85.509277 -399.404693) (xy 85.556883 -399.433747) (xy 85.599751 -399.469422) (xy 85.636968 -399.510959)
			(xy 85.667741 -399.557472) (xy 85.691413 -399.607969) (xy 85.707481 -399.661376) (xy 85.715601 -399.716552)
			(xy 85.71611 -399.744438) (xy 85.715601 -399.772324) (xy 85.707481 -399.8275) (xy 85.691413 -399.880907)
			(xy 85.667741 -399.931404) (xy 85.636968 -399.977917) (xy 85.599751 -400.019454) (xy 85.556883 -400.055129)
			(xy 85.509277 -400.084183) (xy 85.457948 -400.105995) (xy 85.403991 -400.120101) (xy 85.348554 -400.126201)
			(xy 85.29282 -400.124164) (xy 85.237977 -400.114034) (xy 85.185193 -400.096027) (xy 85.135593 -400.070526)
			(xy 85.090235 -400.038075) (xy 85.050086 -399.999366) (xy 85.016 -399.955223) (xy 84.988704 -399.906588)
			(xy 84.968781 -399.854497) (xy 84.956655 -399.80006) (xy 84.952584 -399.744438) (xy 29.59608 -399.744438)
			(xy 29.59608 -400.271234) (xy 78.88554 -400.271234) (xy 78.889611 -400.215612) (xy 78.901737 -400.161175)
			(xy 78.92166 -400.109084) (xy 78.948956 -400.060449) (xy 78.983042 -400.016306) (xy 79.023191 -399.977597)
			(xy 79.068549 -399.945146) (xy 79.118149 -399.919645) (xy 79.170933 -399.901638) (xy 79.225776 -399.891508)
			(xy 79.28151 -399.889471) (xy 79.336947 -399.895571) (xy 79.390904 -399.909677) (xy 79.442233 -399.931489)
			(xy 79.489839 -399.960543) (xy 79.532707 -399.996218) (xy 79.569924 -400.037755) (xy 79.600697 -400.084268)
			(xy 79.624369 -400.134765) (xy 79.640437 -400.188172) (xy 79.648557 -400.243348) (xy 79.649066 -400.271234)
			(xy 79.648557 -400.29912) (xy 79.640437 -400.354296) (xy 79.624369 -400.407703) (xy 79.600697 -400.4582)
			(xy 79.569924 -400.504713) (xy 79.532707 -400.54625) (xy 79.489839 -400.581925) (xy 79.442233 -400.610979)
			(xy 79.390904 -400.632791) (xy 79.336947 -400.646897) (xy 79.28151 -400.652997) (xy 79.225776 -400.65096)
			(xy 79.170933 -400.64083) (xy 79.118149 -400.622823) (xy 79.068549 -400.597322) (xy 79.023191 -400.564871)
			(xy 78.983042 -400.526162) (xy 78.948956 -400.482019) (xy 78.92166 -400.433384) (xy 78.901737 -400.381293)
			(xy 78.889611 -400.326856) (xy 78.88554 -400.271234) (xy 29.59608 -400.271234) (xy 29.59608 -406.96007)
			(xy 39.818564 -406.96007) (xy 39.819058 -406.902661) (xy 39.826902 -406.788113) (xy 39.842544 -406.674366)
			(xy 39.865911 -406.561952) (xy 39.896896 -406.451394) (xy 39.935352 -406.343209) (xy 39.981101 -406.2379)
			(xy 40.03393 -406.135958) (xy 40.093592 -406.037859) (xy 40.159809 -405.94406) (xy 40.232272 -405.854998)
			(xy 40.310645 -405.771089) (xy 40.39456 -405.692723) (xy 40.483627 -405.620266) (xy 40.577431 -405.554056)
			(xy 40.675535 -405.494402) (xy 40.777481 -405.441581) (xy 40.882793 -405.395839) (xy 40.990981 -405.357391)
			(xy 41.101541 -405.326415) (xy 41.213957 -405.303056) (xy 41.327705 -405.287423) (xy 41.442254 -405.279588)
			(xy 41.557072 -405.279588) (xy 41.671621 -405.287423) (xy 41.785369 -405.303056) (xy 41.897785 -405.326415)
			(xy 42.008345 -405.357391) (xy 42.116533 -405.395839) (xy 42.221845 -405.441581) (xy 42.323791 -405.494402)
			(xy 42.421895 -405.554056) (xy 42.501239 -405.61006) (xy 63.647577 -405.61006) (xy 63.651612 -405.534356)
			(xy 63.663671 -405.459511) (xy 63.683617 -405.38637) (xy 63.711224 -405.315765) (xy 63.74618 -405.248494)
			(xy 63.788088 -405.185319) (xy 63.836474 -405.126957) (xy 63.89079 -405.074069) (xy 63.950419 -405.027254)
			(xy 64.014687 -404.987042) (xy 64.082864 -404.95389) (xy 64.15418 -404.928172) (xy 64.227825 -404.91018)
			(xy 64.302965 -404.900118) (xy 64.378749 -404.898099) (xy 64.454319 -404.904148) (xy 64.528817 -404.918195)
			(xy 64.6014 -404.940081) (xy 64.671246 -404.969558) (xy 64.737563 -405.006293) (xy 64.799599 -405.049868)
			(xy 64.856652 -405.09979) (xy 64.908076 -405.155494) (xy 64.953287 -405.216349) (xy 64.991774 -405.281664)
			(xy 65.0231 -405.3507) (xy 65.04691 -405.422675) (xy 65.062935 -405.496773) (xy 65.070994 -405.572154)
			(xy 65.071498 -405.61006) (xy 66.187577 -405.61006) (xy 66.191612 -405.534356) (xy 66.203671 -405.459511)
			(xy 66.223617 -405.38637) (xy 66.251224 -405.315765) (xy 66.28618 -405.248494) (xy 66.328088 -405.185319)
			(xy 66.376474 -405.126957) (xy 66.43079 -405.074069) (xy 66.490419 -405.027254) (xy 66.554687 -404.987042)
			(xy 66.622864 -404.95389) (xy 66.69418 -404.928172) (xy 66.767825 -404.91018) (xy 66.842965 -404.900118)
			(xy 66.918749 -404.898099) (xy 66.994319 -404.904148) (xy 67.068817 -404.918195) (xy 67.1414 -404.940081)
			(xy 67.211246 -404.969558) (xy 67.277563 -405.006293) (xy 67.339599 -405.049868) (xy 67.396652 -405.09979)
			(xy 67.448076 -405.155494) (xy 67.493287 -405.216349) (xy 67.531774 -405.281664) (xy 67.5631 -405.3507)
			(xy 67.58691 -405.422675) (xy 67.602935 -405.496773) (xy 67.610994 -405.572154) (xy 67.611498 -405.61006)
			(xy 68.727577 -405.61006) (xy 68.731612 -405.534356) (xy 68.743671 -405.459511) (xy 68.763617 -405.38637)
			(xy 68.791224 -405.315765) (xy 68.82618 -405.248494) (xy 68.868088 -405.185319) (xy 68.916474 -405.126957)
			(xy 68.97079 -405.074069) (xy 69.030419 -405.027254) (xy 69.094687 -404.987042) (xy 69.162864 -404.95389)
			(xy 69.23418 -404.928172) (xy 69.307825 -404.91018) (xy 69.382965 -404.900118) (xy 69.458749 -404.898099)
			(xy 69.534319 -404.904148) (xy 69.608817 -404.918195) (xy 69.6814 -404.940081) (xy 69.751246 -404.969558)
			(xy 69.817563 -405.006293) (xy 69.879599 -405.049868) (xy 69.936652 -405.09979) (xy 69.988076 -405.155494)
			(xy 70.033287 -405.216349) (xy 70.071774 -405.281664) (xy 70.1031 -405.3507) (xy 70.12691 -405.422675)
			(xy 70.142935 -405.496773) (xy 70.150994 -405.572154) (xy 70.151498 -405.61006) (xy 71.267577 -405.61006)
			(xy 71.271612 -405.534356) (xy 71.283671 -405.459511) (xy 71.303617 -405.38637) (xy 71.331224 -405.315765)
			(xy 71.36618 -405.248494) (xy 71.408088 -405.185319) (xy 71.456474 -405.126957) (xy 71.51079 -405.074069)
			(xy 71.570419 -405.027254) (xy 71.634687 -404.987042) (xy 71.702864 -404.95389) (xy 71.77418 -404.928172)
			(xy 71.847825 -404.91018) (xy 71.922965 -404.900118) (xy 71.998749 -404.898099) (xy 72.074319 -404.904148)
			(xy 72.148817 -404.918195) (xy 72.2214 -404.940081) (xy 72.291246 -404.969558) (xy 72.357563 -405.006293)
			(xy 72.419599 -405.049868) (xy 72.476652 -405.09979) (xy 72.528076 -405.155494) (xy 72.573287 -405.216349)
			(xy 72.611774 -405.281664) (xy 72.6431 -405.3507) (xy 72.66691 -405.422675) (xy 72.682935 -405.496773)
			(xy 72.690994 -405.572154) (xy 72.691498 -405.61006) (xy 73.807577 -405.61006) (xy 73.811612 -405.534356)
			(xy 73.823671 -405.459511) (xy 73.843617 -405.38637) (xy 73.871224 -405.315765) (xy 73.90618 -405.248494)
			(xy 73.948088 -405.185319) (xy 73.996474 -405.126957) (xy 74.05079 -405.074069) (xy 74.110419 -405.027254)
			(xy 74.174687 -404.987042) (xy 74.242864 -404.95389) (xy 74.31418 -404.928172) (xy 74.387825 -404.91018)
			(xy 74.462965 -404.900118) (xy 74.538749 -404.898099) (xy 74.614319 -404.904148) (xy 74.688817 -404.918195)
			(xy 74.7614 -404.940081) (xy 74.831246 -404.969558) (xy 74.897563 -405.006293) (xy 74.959599 -405.049868)
			(xy 75.016652 -405.09979) (xy 75.068076 -405.155494) (xy 75.113287 -405.216349) (xy 75.151774 -405.281664)
			(xy 75.1831 -405.3507) (xy 75.20691 -405.422675) (xy 75.222935 -405.496773) (xy 75.230994 -405.572154)
			(xy 75.231498 -405.61006) (xy 76.347577 -405.61006) (xy 76.351612 -405.534356) (xy 76.363671 -405.459511)
			(xy 76.383617 -405.38637) (xy 76.411224 -405.315765) (xy 76.44618 -405.248494) (xy 76.488088 -405.185319)
			(xy 76.536474 -405.126957) (xy 76.59079 -405.074069) (xy 76.650419 -405.027254) (xy 76.714687 -404.987042)
			(xy 76.782864 -404.95389) (xy 76.85418 -404.928172) (xy 76.927825 -404.91018) (xy 77.002965 -404.900118)
			(xy 77.078749 -404.898099) (xy 77.154319 -404.904148) (xy 77.228817 -404.918195) (xy 77.3014 -404.940081)
			(xy 77.371246 -404.969558) (xy 77.437563 -405.006293) (xy 77.499599 -405.049868) (xy 77.556652 -405.09979)
			(xy 77.608076 -405.155494) (xy 77.653287 -405.216349) (xy 77.691774 -405.281664) (xy 77.7231 -405.3507)
			(xy 77.74691 -405.422675) (xy 77.762935 -405.496773) (xy 77.770994 -405.572154) (xy 77.771498 -405.61006)
			(xy 78.887577 -405.61006) (xy 78.891612 -405.534356) (xy 78.903671 -405.459511) (xy 78.923617 -405.38637)
			(xy 78.951224 -405.315765) (xy 78.98618 -405.248494) (xy 79.028088 -405.185319) (xy 79.076474 -405.126957)
			(xy 79.13079 -405.074069) (xy 79.190419 -405.027254) (xy 79.254687 -404.987042) (xy 79.322864 -404.95389)
			(xy 79.39418 -404.928172) (xy 79.467825 -404.91018) (xy 79.542965 -404.900118) (xy 79.618749 -404.898099)
			(xy 79.694319 -404.904148) (xy 79.768817 -404.918195) (xy 79.8414 -404.940081) (xy 79.911246 -404.969558)
			(xy 79.977563 -405.006293) (xy 80.039599 -405.049868) (xy 80.096652 -405.09979) (xy 80.148076 -405.155494)
			(xy 80.193287 -405.216349) (xy 80.231774 -405.281664) (xy 80.2631 -405.3507) (xy 80.28691 -405.422675)
			(xy 80.302935 -405.496773) (xy 80.310994 -405.572154) (xy 80.311498 -405.61006) (xy 81.427577 -405.61006)
			(xy 81.431612 -405.534356) (xy 81.443671 -405.459511) (xy 81.463617 -405.38637) (xy 81.491224 -405.315765)
			(xy 81.52618 -405.248494) (xy 81.568088 -405.185319) (xy 81.616474 -405.126957) (xy 81.67079 -405.074069)
			(xy 81.730419 -405.027254) (xy 81.794687 -404.987042) (xy 81.862864 -404.95389) (xy 81.93418 -404.928172)
			(xy 82.007825 -404.91018) (xy 82.082965 -404.900118) (xy 82.158749 -404.898099) (xy 82.234319 -404.904148)
			(xy 82.308817 -404.918195) (xy 82.3814 -404.940081) (xy 82.451246 -404.969558) (xy 82.517563 -405.006293)
			(xy 82.579599 -405.049868) (xy 82.636652 -405.09979) (xy 82.688076 -405.155494) (xy 82.733287 -405.216349)
			(xy 82.771774 -405.281664) (xy 82.8031 -405.3507) (xy 82.82691 -405.422675) (xy 82.842935 -405.496773)
			(xy 82.850994 -405.572154) (xy 82.851498 -405.61006) (xy 82.850994 -405.647966) (xy 82.842935 -405.723347)
			(xy 82.82691 -405.797445) (xy 82.8031 -405.86942) (xy 82.771774 -405.938456) (xy 82.733287 -406.003771)
			(xy 82.688076 -406.064626) (xy 82.636652 -406.12033) (xy 82.579599 -406.170252) (xy 82.517563 -406.213827)
			(xy 82.451246 -406.250562) (xy 82.3814 -406.280039) (xy 82.308817 -406.301925) (xy 82.234319 -406.315972)
			(xy 82.158749 -406.322021) (xy 82.082965 -406.320002) (xy 82.007825 -406.30994) (xy 81.93418 -406.291948)
			(xy 81.862864 -406.26623) (xy 81.794687 -406.233078) (xy 81.730419 -406.192866) (xy 81.67079 -406.146051)
			(xy 81.616474 -406.093163) (xy 81.568088 -406.034801) (xy 81.52618 -405.971626) (xy 81.491224 -405.904355)
			(xy 81.463617 -405.83375) (xy 81.443671 -405.760609) (xy 81.431612 -405.685764) (xy 81.427577 -405.61006)
			(xy 80.311498 -405.61006) (xy 80.310994 -405.647966) (xy 80.302935 -405.723347) (xy 80.28691 -405.797445)
			(xy 80.2631 -405.86942) (xy 80.231774 -405.938456) (xy 80.193287 -406.003771) (xy 80.148076 -406.064626)
			(xy 80.096652 -406.12033) (xy 80.039599 -406.170252) (xy 79.977563 -406.213827) (xy 79.911246 -406.250562)
			(xy 79.8414 -406.280039) (xy 79.768817 -406.301925) (xy 79.694319 -406.315972) (xy 79.618749 -406.322021)
			(xy 79.542965 -406.320002) (xy 79.467825 -406.30994) (xy 79.39418 -406.291948) (xy 79.322864 -406.26623)
			(xy 79.254687 -406.233078) (xy 79.190419 -406.192866) (xy 79.13079 -406.146051) (xy 79.076474 -406.093163)
			(xy 79.028088 -406.034801) (xy 78.98618 -405.971626) (xy 78.951224 -405.904355) (xy 78.923617 -405.83375)
			(xy 78.903671 -405.760609) (xy 78.891612 -405.685764) (xy 78.887577 -405.61006) (xy 77.771498 -405.61006)
			(xy 77.770994 -405.647966) (xy 77.762935 -405.723347) (xy 77.74691 -405.797445) (xy 77.7231 -405.86942)
			(xy 77.691774 -405.938456) (xy 77.653287 -406.003771) (xy 77.608076 -406.064626) (xy 77.556652 -406.12033)
			(xy 77.499599 -406.170252) (xy 77.437563 -406.213827) (xy 77.371246 -406.250562) (xy 77.3014 -406.280039)
			(xy 77.228817 -406.301925) (xy 77.154319 -406.315972) (xy 77.078749 -406.322021) (xy 77.002965 -406.320002)
			(xy 76.927825 -406.30994) (xy 76.85418 -406.291948) (xy 76.782864 -406.26623) (xy 76.714687 -406.233078)
			(xy 76.650419 -406.192866) (xy 76.59079 -406.146051) (xy 76.536474 -406.093163) (xy 76.488088 -406.034801)
			(xy 76.44618 -405.971626) (xy 76.411224 -405.904355) (xy 76.383617 -405.83375) (xy 76.363671 -405.760609)
			(xy 76.351612 -405.685764) (xy 76.347577 -405.61006) (xy 75.231498 -405.61006) (xy 75.230994 -405.647966)
			(xy 75.222935 -405.723347) (xy 75.20691 -405.797445) (xy 75.1831 -405.86942) (xy 75.151774 -405.938456)
			(xy 75.113287 -406.003771) (xy 75.068076 -406.064626) (xy 75.016652 -406.12033) (xy 74.959599 -406.170252)
			(xy 74.897563 -406.213827) (xy 74.831246 -406.250562) (xy 74.7614 -406.280039) (xy 74.688817 -406.301925)
			(xy 74.614319 -406.315972) (xy 74.538749 -406.322021) (xy 74.462965 -406.320002) (xy 74.387825 -406.30994)
			(xy 74.31418 -406.291948) (xy 74.242864 -406.26623) (xy 74.174687 -406.233078) (xy 74.110419 -406.192866)
			(xy 74.05079 -406.146051) (xy 73.996474 -406.093163) (xy 73.948088 -406.034801) (xy 73.90618 -405.971626)
			(xy 73.871224 -405.904355) (xy 73.843617 -405.83375) (xy 73.823671 -405.760609) (xy 73.811612 -405.685764)
			(xy 73.807577 -405.61006) (xy 72.691498 -405.61006) (xy 72.690994 -405.647966) (xy 72.682935 -405.723347)
			(xy 72.66691 -405.797445) (xy 72.6431 -405.86942) (xy 72.611774 -405.938456) (xy 72.573287 -406.003771)
			(xy 72.528076 -406.064626) (xy 72.476652 -406.12033) (xy 72.419599 -406.170252) (xy 72.357563 -406.213827)
			(xy 72.291246 -406.250562) (xy 72.2214 -406.280039) (xy 72.148817 -406.301925) (xy 72.074319 -406.315972)
			(xy 71.998749 -406.322021) (xy 71.922965 -406.320002) (xy 71.847825 -406.30994) (xy 71.77418 -406.291948)
			(xy 71.702864 -406.26623) (xy 71.634687 -406.233078) (xy 71.570419 -406.192866) (xy 71.51079 -406.146051)
			(xy 71.456474 -406.093163) (xy 71.408088 -406.034801) (xy 71.36618 -405.971626) (xy 71.331224 -405.904355)
			(xy 71.303617 -405.83375) (xy 71.283671 -405.760609) (xy 71.271612 -405.685764) (xy 71.267577 -405.61006)
			(xy 70.151498 -405.61006) (xy 70.150994 -405.647966) (xy 70.142935 -405.723347) (xy 70.12691 -405.797445)
			(xy 70.1031 -405.86942) (xy 70.071774 -405.938456) (xy 70.033287 -406.003771) (xy 69.988076 -406.064626)
			(xy 69.936652 -406.12033) (xy 69.879599 -406.170252) (xy 69.817563 -406.213827) (xy 69.751246 -406.250562)
			(xy 69.6814 -406.280039) (xy 69.608817 -406.301925) (xy 69.534319 -406.315972) (xy 69.458749 -406.322021)
			(xy 69.382965 -406.320002) (xy 69.307825 -406.30994) (xy 69.23418 -406.291948) (xy 69.162864 -406.26623)
			(xy 69.094687 -406.233078) (xy 69.030419 -406.192866) (xy 68.97079 -406.146051) (xy 68.916474 -406.093163)
			(xy 68.868088 -406.034801) (xy 68.82618 -405.971626) (xy 68.791224 -405.904355) (xy 68.763617 -405.83375)
			(xy 68.743671 -405.760609) (xy 68.731612 -405.685764) (xy 68.727577 -405.61006) (xy 67.611498 -405.61006)
			(xy 67.610994 -405.647966) (xy 67.602935 -405.723347) (xy 67.58691 -405.797445) (xy 67.5631 -405.86942)
			(xy 67.531774 -405.938456) (xy 67.493287 -406.003771) (xy 67.448076 -406.064626) (xy 67.396652 -406.12033)
			(xy 67.339599 -406.170252) (xy 67.277563 -406.213827) (xy 67.211246 -406.250562) (xy 67.1414 -406.280039)
			(xy 67.068817 -406.301925) (xy 66.994319 -406.315972) (xy 66.918749 -406.322021) (xy 66.842965 -406.320002)
			(xy 66.767825 -406.30994) (xy 66.69418 -406.291948) (xy 66.622864 -406.26623) (xy 66.554687 -406.233078)
			(xy 66.490419 -406.192866) (xy 66.43079 -406.146051) (xy 66.376474 -406.093163) (xy 66.328088 -406.034801)
			(xy 66.28618 -405.971626) (xy 66.251224 -405.904355) (xy 66.223617 -405.83375) (xy 66.203671 -405.760609)
			(xy 66.191612 -405.685764) (xy 66.187577 -405.61006) (xy 65.071498 -405.61006) (xy 65.070994 -405.647966)
			(xy 65.062935 -405.723347) (xy 65.04691 -405.797445) (xy 65.0231 -405.86942) (xy 64.991774 -405.938456)
			(xy 64.953287 -406.003771) (xy 64.908076 -406.064626) (xy 64.856652 -406.12033) (xy 64.799599 -406.170252)
			(xy 64.737563 -406.213827) (xy 64.671246 -406.250562) (xy 64.6014 -406.280039) (xy 64.528817 -406.301925)
			(xy 64.454319 -406.315972) (xy 64.378749 -406.322021) (xy 64.302965 -406.320002) (xy 64.227825 -406.30994)
			(xy 64.15418 -406.291948) (xy 64.082864 -406.26623) (xy 64.014687 -406.233078) (xy 63.950419 -406.192866)
			(xy 63.89079 -406.146051) (xy 63.836474 -406.093163) (xy 63.788088 -406.034801) (xy 63.74618 -405.971626)
			(xy 63.711224 -405.904355) (xy 63.683617 -405.83375) (xy 63.663671 -405.760609) (xy 63.651612 -405.685764)
			(xy 63.647577 -405.61006) (xy 42.501239 -405.61006) (xy 42.515699 -405.620266) (xy 42.604766 -405.692723)
			(xy 42.688681 -405.771089) (xy 42.767054 -405.854998) (xy 42.839517 -405.94406) (xy 42.905734 -406.037859)
			(xy 42.965396 -406.135958) (xy 43.018225 -406.2379) (xy 43.063974 -406.343209) (xy 43.10243 -406.451394)
			(xy 43.133415 -406.561952) (xy 43.156782 -406.674366) (xy 43.172424 -406.788113) (xy 43.180268 -406.902661)
			(xy 43.180762 -406.96007) (xy 43.180576 -406.993253) (xy 43.177909 -407.059567) (xy 43.175428 -407.092658)
			(xy 43.170272 -407.150942) (xy 43.152948 -407.266671) (xy 43.127616 -407.380914) (xy 43.094401 -407.493119)
			(xy 43.053462 -407.602742) (xy 43.004999 -407.709253) (xy 42.949245 -407.812135) (xy 42.886471 -407.910891)
			(xy 42.816981 -408.005042) (xy 42.741111 -408.094132) (xy 42.659229 -408.177729) (xy 42.571732 -408.25543)
			(xy 42.500813 -408.31008) (xy 63.647577 -408.31008) (xy 63.651612 -408.234376) (xy 63.663671 -408.159531)
			(xy 63.683617 -408.08639) (xy 63.711224 -408.015785) (xy 63.74618 -407.948514) (xy 63.788088 -407.885339)
			(xy 63.836474 -407.826977) (xy 63.89079 -407.774089) (xy 63.950419 -407.727274) (xy 64.014687 -407.687062)
			(xy 64.082864 -407.65391) (xy 64.15418 -407.628192) (xy 64.227825 -407.6102) (xy 64.302965 -407.600138)
			(xy 64.378749 -407.598119) (xy 64.454319 -407.604168) (xy 64.528817 -407.618215) (xy 64.6014 -407.640101)
			(xy 64.671246 -407.669578) (xy 64.737563 -407.706313) (xy 64.799599 -407.749888) (xy 64.856652 -407.79981)
			(xy 64.908076 -407.855514) (xy 64.953287 -407.916369) (xy 64.991774 -407.981684) (xy 65.0231 -408.05072)
			(xy 65.04691 -408.122695) (xy 65.062935 -408.196793) (xy 65.070994 -408.272174) (xy 65.071498 -408.31008)
			(xy 66.187577 -408.31008) (xy 66.191612 -408.234376) (xy 66.203671 -408.159531) (xy 66.223617 -408.08639)
			(xy 66.251224 -408.015785) (xy 66.28618 -407.948514) (xy 66.328088 -407.885339) (xy 66.376474 -407.826977)
			(xy 66.43079 -407.774089) (xy 66.490419 -407.727274) (xy 66.554687 -407.687062) (xy 66.622864 -407.65391)
			(xy 66.69418 -407.628192) (xy 66.767825 -407.6102) (xy 66.842965 -407.600138) (xy 66.918749 -407.598119)
			(xy 66.994319 -407.604168) (xy 67.068817 -407.618215) (xy 67.1414 -407.640101) (xy 67.211246 -407.669578)
			(xy 67.277563 -407.706313) (xy 67.339599 -407.749888) (xy 67.396652 -407.79981) (xy 67.448076 -407.855514)
			(xy 67.493287 -407.916369) (xy 67.531774 -407.981684) (xy 67.5631 -408.05072) (xy 67.58691 -408.122695)
			(xy 67.602935 -408.196793) (xy 67.610994 -408.272174) (xy 67.611498 -408.31008) (xy 68.727577 -408.31008)
			(xy 68.731612 -408.234376) (xy 68.743671 -408.159531) (xy 68.763617 -408.08639) (xy 68.791224 -408.015785)
			(xy 68.82618 -407.948514) (xy 68.868088 -407.885339) (xy 68.916474 -407.826977) (xy 68.97079 -407.774089)
			(xy 69.030419 -407.727274) (xy 69.094687 -407.687062) (xy 69.162864 -407.65391) (xy 69.23418 -407.628192)
			(xy 69.307825 -407.6102) (xy 69.382965 -407.600138) (xy 69.458749 -407.598119) (xy 69.534319 -407.604168)
			(xy 69.608817 -407.618215) (xy 69.6814 -407.640101) (xy 69.751246 -407.669578) (xy 69.817563 -407.706313)
			(xy 69.879599 -407.749888) (xy 69.936652 -407.79981) (xy 69.988076 -407.855514) (xy 70.033287 -407.916369)
			(xy 70.071774 -407.981684) (xy 70.1031 -408.05072) (xy 70.12691 -408.122695) (xy 70.142935 -408.196793)
			(xy 70.150994 -408.272174) (xy 70.151498 -408.31008) (xy 71.267577 -408.31008) (xy 71.271612 -408.234376)
			(xy 71.283671 -408.159531) (xy 71.303617 -408.08639) (xy 71.331224 -408.015785) (xy 71.36618 -407.948514)
			(xy 71.408088 -407.885339) (xy 71.456474 -407.826977) (xy 71.51079 -407.774089) (xy 71.570419 -407.727274)
			(xy 71.634687 -407.687062) (xy 71.702864 -407.65391) (xy 71.77418 -407.628192) (xy 71.847825 -407.6102)
			(xy 71.922965 -407.600138) (xy 71.998749 -407.598119) (xy 72.074319 -407.604168) (xy 72.148817 -407.618215)
			(xy 72.2214 -407.640101) (xy 72.291246 -407.669578) (xy 72.357563 -407.706313) (xy 72.419599 -407.749888)
			(xy 72.476652 -407.79981) (xy 72.528076 -407.855514) (xy 72.573287 -407.916369) (xy 72.611774 -407.981684)
			(xy 72.6431 -408.05072) (xy 72.66691 -408.122695) (xy 72.682935 -408.196793) (xy 72.690994 -408.272174)
			(xy 72.691498 -408.31008) (xy 73.807577 -408.31008) (xy 73.811612 -408.234376) (xy 73.823671 -408.159531)
			(xy 73.843617 -408.08639) (xy 73.871224 -408.015785) (xy 73.90618 -407.948514) (xy 73.948088 -407.885339)
			(xy 73.996474 -407.826977) (xy 74.05079 -407.774089) (xy 74.110419 -407.727274) (xy 74.174687 -407.687062)
			(xy 74.242864 -407.65391) (xy 74.31418 -407.628192) (xy 74.387825 -407.6102) (xy 74.462965 -407.600138)
			(xy 74.538749 -407.598119) (xy 74.614319 -407.604168) (xy 74.688817 -407.618215) (xy 74.7614 -407.640101)
			(xy 74.831246 -407.669578) (xy 74.897563 -407.706313) (xy 74.959599 -407.749888) (xy 75.016652 -407.79981)
			(xy 75.068076 -407.855514) (xy 75.113287 -407.916369) (xy 75.151774 -407.981684) (xy 75.1831 -408.05072)
			(xy 75.20691 -408.122695) (xy 75.222935 -408.196793) (xy 75.230994 -408.272174) (xy 75.231498 -408.31008)
			(xy 76.347577 -408.31008) (xy 76.351612 -408.234376) (xy 76.363671 -408.159531) (xy 76.383617 -408.08639)
			(xy 76.411224 -408.015785) (xy 76.44618 -407.948514) (xy 76.488088 -407.885339) (xy 76.536474 -407.826977)
			(xy 76.59079 -407.774089) (xy 76.650419 -407.727274) (xy 76.714687 -407.687062) (xy 76.782864 -407.65391)
			(xy 76.85418 -407.628192) (xy 76.927825 -407.6102) (xy 77.002965 -407.600138) (xy 77.078749 -407.598119)
			(xy 77.154319 -407.604168) (xy 77.228817 -407.618215) (xy 77.3014 -407.640101) (xy 77.371246 -407.669578)
			(xy 77.437563 -407.706313) (xy 77.499599 -407.749888) (xy 77.556652 -407.79981) (xy 77.608076 -407.855514)
			(xy 77.653287 -407.916369) (xy 77.691774 -407.981684) (xy 77.7231 -408.05072) (xy 77.74691 -408.122695)
			(xy 77.762935 -408.196793) (xy 77.770994 -408.272174) (xy 77.771498 -408.31008) (xy 78.887577 -408.31008)
			(xy 78.891612 -408.234376) (xy 78.903671 -408.159531) (xy 78.923617 -408.08639) (xy 78.951224 -408.015785)
			(xy 78.98618 -407.948514) (xy 79.028088 -407.885339) (xy 79.076474 -407.826977) (xy 79.13079 -407.774089)
			(xy 79.190419 -407.727274) (xy 79.254687 -407.687062) (xy 79.322864 -407.65391) (xy 79.39418 -407.628192)
			(xy 79.467825 -407.6102) (xy 79.542965 -407.600138) (xy 79.618749 -407.598119) (xy 79.694319 -407.604168)
			(xy 79.768817 -407.618215) (xy 79.8414 -407.640101) (xy 79.911246 -407.669578) (xy 79.977563 -407.706313)
			(xy 80.039599 -407.749888) (xy 80.096652 -407.79981) (xy 80.148076 -407.855514) (xy 80.193287 -407.916369)
			(xy 80.231774 -407.981684) (xy 80.2631 -408.05072) (xy 80.28691 -408.122695) (xy 80.302935 -408.196793)
			(xy 80.310994 -408.272174) (xy 80.311498 -408.31008) (xy 81.427577 -408.31008) (xy 81.431612 -408.234376)
			(xy 81.443671 -408.159531) (xy 81.463617 -408.08639) (xy 81.491224 -408.015785) (xy 81.52618 -407.948514)
			(xy 81.568088 -407.885339) (xy 81.616474 -407.826977) (xy 81.67079 -407.774089) (xy 81.730419 -407.727274)
			(xy 81.794687 -407.687062) (xy 81.862864 -407.65391) (xy 81.93418 -407.628192) (xy 82.007825 -407.6102)
			(xy 82.082965 -407.600138) (xy 82.158749 -407.598119) (xy 82.234319 -407.604168) (xy 82.308817 -407.618215)
			(xy 82.3814 -407.640101) (xy 82.451246 -407.669578) (xy 82.517563 -407.706313) (xy 82.579599 -407.749888)
			(xy 82.636652 -407.79981) (xy 82.688076 -407.855514) (xy 82.733287 -407.916369) (xy 82.771774 -407.981684)
			(xy 82.8031 -408.05072) (xy 82.82691 -408.122695) (xy 82.842935 -408.196793) (xy 82.850994 -408.272174)
			(xy 82.851498 -408.31008) (xy 82.850994 -408.347986) (xy 82.842935 -408.423367) (xy 82.82691 -408.497465)
			(xy 82.8031 -408.56944) (xy 82.771774 -408.638476) (xy 82.733287 -408.703791) (xy 82.688076 -408.764646)
			(xy 82.636652 -408.82035) (xy 82.579599 -408.870272) (xy 82.517563 -408.913847) (xy 82.451246 -408.950582)
			(xy 82.3814 -408.980059) (xy 82.308817 -409.001945) (xy 82.234319 -409.015992) (xy 82.158749 -409.022041)
			(xy 82.082965 -409.020022) (xy 82.007825 -409.00996) (xy 81.93418 -408.991968) (xy 81.862864 -408.96625)
			(xy 81.794687 -408.933098) (xy 81.730419 -408.892886) (xy 81.67079 -408.846071) (xy 81.616474 -408.793183)
			(xy 81.568088 -408.734821) (xy 81.52618 -408.671646) (xy 81.491224 -408.604375) (xy 81.463617 -408.53377)
			(xy 81.443671 -408.460629) (xy 81.431612 -408.385784) (xy 81.427577 -408.31008) (xy 80.311498 -408.31008)
			(xy 80.310994 -408.347986) (xy 80.302935 -408.423367) (xy 80.28691 -408.497465) (xy 80.2631 -408.56944)
			(xy 80.231774 -408.638476) (xy 80.193287 -408.703791) (xy 80.148076 -408.764646) (xy 80.096652 -408.82035)
			(xy 80.039599 -408.870272) (xy 79.977563 -408.913847) (xy 79.911246 -408.950582) (xy 79.8414 -408.980059)
			(xy 79.768817 -409.001945) (xy 79.694319 -409.015992) (xy 79.618749 -409.022041) (xy 79.542965 -409.020022)
			(xy 79.467825 -409.00996) (xy 79.39418 -408.991968) (xy 79.322864 -408.96625) (xy 79.254687 -408.933098)
			(xy 79.190419 -408.892886) (xy 79.13079 -408.846071) (xy 79.076474 -408.793183) (xy 79.028088 -408.734821)
			(xy 78.98618 -408.671646) (xy 78.951224 -408.604375) (xy 78.923617 -408.53377) (xy 78.903671 -408.460629)
			(xy 78.891612 -408.385784) (xy 78.887577 -408.31008) (xy 77.771498 -408.31008) (xy 77.770994 -408.347986)
			(xy 77.762935 -408.423367) (xy 77.74691 -408.497465) (xy 77.7231 -408.56944) (xy 77.691774 -408.638476)
			(xy 77.653287 -408.703791) (xy 77.608076 -408.764646) (xy 77.556652 -408.82035) (xy 77.499599 -408.870272)
			(xy 77.437563 -408.913847) (xy 77.371246 -408.950582) (xy 77.3014 -408.980059) (xy 77.228817 -409.001945)
			(xy 77.154319 -409.015992) (xy 77.078749 -409.022041) (xy 77.002965 -409.020022) (xy 76.927825 -409.00996)
			(xy 76.85418 -408.991968) (xy 76.782864 -408.96625) (xy 76.714687 -408.933098) (xy 76.650419 -408.892886)
			(xy 76.59079 -408.846071) (xy 76.536474 -408.793183) (xy 76.488088 -408.734821) (xy 76.44618 -408.671646)
			(xy 76.411224 -408.604375) (xy 76.383617 -408.53377) (xy 76.363671 -408.460629) (xy 76.351612 -408.385784)
			(xy 76.347577 -408.31008) (xy 75.231498 -408.31008) (xy 75.230994 -408.347986) (xy 75.222935 -408.423367)
			(xy 75.20691 -408.497465) (xy 75.1831 -408.56944) (xy 75.151774 -408.638476) (xy 75.113287 -408.703791)
			(xy 75.068076 -408.764646) (xy 75.016652 -408.82035) (xy 74.959599 -408.870272) (xy 74.897563 -408.913847)
			(xy 74.831246 -408.950582) (xy 74.7614 -408.980059) (xy 74.688817 -409.001945) (xy 74.614319 -409.015992)
			(xy 74.538749 -409.022041) (xy 74.462965 -409.020022) (xy 74.387825 -409.00996) (xy 74.31418 -408.991968)
			(xy 74.242864 -408.96625) (xy 74.174687 -408.933098) (xy 74.110419 -408.892886) (xy 74.05079 -408.846071)
			(xy 73.996474 -408.793183) (xy 73.948088 -408.734821) (xy 73.90618 -408.671646) (xy 73.871224 -408.604375)
			(xy 73.843617 -408.53377) (xy 73.823671 -408.460629) (xy 73.811612 -408.385784) (xy 73.807577 -408.31008)
			(xy 72.691498 -408.31008) (xy 72.690994 -408.347986) (xy 72.682935 -408.423367) (xy 72.66691 -408.497465)
			(xy 72.6431 -408.56944) (xy 72.611774 -408.638476) (xy 72.573287 -408.703791) (xy 72.528076 -408.764646)
			(xy 72.476652 -408.82035) (xy 72.419599 -408.870272) (xy 72.357563 -408.913847) (xy 72.291246 -408.950582)
			(xy 72.2214 -408.980059) (xy 72.148817 -409.001945) (xy 72.074319 -409.015992) (xy 71.998749 -409.022041)
			(xy 71.922965 -409.020022) (xy 71.847825 -409.00996) (xy 71.77418 -408.991968) (xy 71.702864 -408.96625)
			(xy 71.634687 -408.933098) (xy 71.570419 -408.892886) (xy 71.51079 -408.846071) (xy 71.456474 -408.793183)
			(xy 71.408088 -408.734821) (xy 71.36618 -408.671646) (xy 71.331224 -408.604375) (xy 71.303617 -408.53377)
			(xy 71.283671 -408.460629) (xy 71.271612 -408.385784) (xy 71.267577 -408.31008) (xy 70.151498 -408.31008)
			(xy 70.150994 -408.347986) (xy 70.142935 -408.423367) (xy 70.12691 -408.497465) (xy 70.1031 -408.56944)
			(xy 70.071774 -408.638476) (xy 70.033287 -408.703791) (xy 69.988076 -408.764646) (xy 69.936652 -408.82035)
			(xy 69.879599 -408.870272) (xy 69.817563 -408.913847) (xy 69.751246 -408.950582) (xy 69.6814 -408.980059)
			(xy 69.608817 -409.001945) (xy 69.534319 -409.015992) (xy 69.458749 -409.022041) (xy 69.382965 -409.020022)
			(xy 69.307825 -409.00996) (xy 69.23418 -408.991968) (xy 69.162864 -408.96625) (xy 69.094687 -408.933098)
			(xy 69.030419 -408.892886) (xy 68.97079 -408.846071) (xy 68.916474 -408.793183) (xy 68.868088 -408.734821)
			(xy 68.82618 -408.671646) (xy 68.791224 -408.604375) (xy 68.763617 -408.53377) (xy 68.743671 -408.460629)
			(xy 68.731612 -408.385784) (xy 68.727577 -408.31008) (xy 67.611498 -408.31008) (xy 67.610994 -408.347986)
			(xy 67.602935 -408.423367) (xy 67.58691 -408.497465) (xy 67.5631 -408.56944) (xy 67.531774 -408.638476)
			(xy 67.493287 -408.703791) (xy 67.448076 -408.764646) (xy 67.396652 -408.82035) (xy 67.339599 -408.870272)
			(xy 67.277563 -408.913847) (xy 67.211246 -408.950582) (xy 67.1414 -408.980059) (xy 67.068817 -409.001945)
			(xy 66.994319 -409.015992) (xy 66.918749 -409.022041) (xy 66.842965 -409.020022) (xy 66.767825 -409.00996)
			(xy 66.69418 -408.991968) (xy 66.622864 -408.96625) (xy 66.554687 -408.933098) (xy 66.490419 -408.892886)
			(xy 66.43079 -408.846071) (xy 66.376474 -408.793183) (xy 66.328088 -408.734821) (xy 66.28618 -408.671646)
			(xy 66.251224 -408.604375) (xy 66.223617 -408.53377) (xy 66.203671 -408.460629) (xy 66.191612 -408.385784)
			(xy 66.187577 -408.31008) (xy 65.071498 -408.31008) (xy 65.070994 -408.347986) (xy 65.062935 -408.423367)
			(xy 65.04691 -408.497465) (xy 65.0231 -408.56944) (xy 64.991774 -408.638476) (xy 64.953287 -408.703791)
			(xy 64.908076 -408.764646) (xy 64.856652 -408.82035) (xy 64.799599 -408.870272) (xy 64.737563 -408.913847)
			(xy 64.671246 -408.950582) (xy 64.6014 -408.980059) (xy 64.528817 -409.001945) (xy 64.454319 -409.015992)
			(xy 64.378749 -409.022041) (xy 64.302965 -409.020022) (xy 64.227825 -409.00996) (xy 64.15418 -408.991968)
			(xy 64.082864 -408.96625) (xy 64.014687 -408.933098) (xy 63.950419 -408.892886) (xy 63.89079 -408.846071)
			(xy 63.836474 -408.793183) (xy 63.788088 -408.734821) (xy 63.74618 -408.671646) (xy 63.711224 -408.604375)
			(xy 63.683617 -408.53377) (xy 63.663671 -408.460629) (xy 63.651612 -408.385784) (xy 63.647577 -408.31008)
			(xy 42.500813 -408.31008) (xy 42.479042 -408.326857) (xy 42.381609 -408.391665) (xy 42.279905 -408.44954)
			(xy 42.174422 -408.500202) (xy 42.065671 -408.543404) (xy 41.954179 -408.578939) (xy 41.840485 -408.606634)
			(xy 41.725141 -408.626354) (xy 41.608704 -408.638005) (xy 41.491739 -408.64153) (xy 41.374812 -408.636912)
			(xy 41.258489 -408.624173) (xy 41.143334 -408.603375) (xy 41.029905 -408.574618) (xy 40.91875 -408.538042)
			(xy 40.810407 -408.493825) (xy 40.705403 -408.442179) (xy 40.604244 -408.383356) (xy 40.507421 -408.31764)
			(xy 40.415403 -408.245349) (xy 40.328636 -408.166834) (xy 40.247539 -408.082474) (xy 40.172506 -407.992679)
			(xy 40.103899 -407.897883) (xy 40.042051 -407.798544) (xy 39.987262 -407.695145) (xy 39.939796 -407.588186)
			(xy 39.899884 -407.478185) (xy 39.86772 -407.365674) (xy 39.843457 -407.251199) (xy 39.827215 -407.135313)
			(xy 39.819072 -407.018579) (xy 39.818564 -406.96007) (xy 29.59608 -406.96007) (xy 29.59608 -407.976832)
			(xy 29.597725 -407.998526) (xy 29.607484 -408.040921) (xy 29.624315 -408.081036) (xy 29.647727 -408.117702)
			(xy 29.677038 -408.149849) (xy 29.711393 -408.176539) (xy 29.749788 -408.196992) (xy 29.791104 -408.210614)
			(xy 29.834135 -408.217005) (xy 29.877627 -408.215979) (xy 29.920309 -408.207568) (xy 29.960937 -408.192015)
			(xy 29.979874 -408.181302) (xy 30.017157 -408.159744) (xy 30.094938 -408.122752) (xy 30.175775 -408.093029)
			(xy 30.258993 -408.070823) (xy 30.343892 -408.05632) (xy 30.429761 -408.049642) (xy 30.515882 -408.050844)
			(xy 30.601532 -408.059917) (xy 30.685993 -408.076785) (xy 30.768557 -408.101306) (xy 30.848534 -408.133275)
			(xy 30.925251 -408.172423) (xy 30.998067 -408.218424) (xy 31.066372 -408.27089) (xy 31.129592 -408.329383)
			(xy 31.187198 -408.393412) (xy 31.238707 -408.462441) (xy 31.283687 -408.535892) (xy 31.321763 -408.613148)
			(xy 31.352613 -408.693562) (xy 31.375981 -408.77646) (xy 31.391669 -408.861148) (xy 31.399548 -408.946916)
			(xy 31.399549 -409.033045) (xy 31.399508 -409.033488) (xy 34.599874 -409.033488) (xy 34.599874 -408.946588)
			(xy 34.607892 -408.860059) (xy 34.62386 -408.774639) (xy 34.647641 -408.691057) (xy 34.679033 -408.610025)
			(xy 34.717767 -408.532236) (xy 34.763514 -408.458352) (xy 34.815883 -408.389005) (xy 34.874427 -408.324785)
			(xy 34.938647 -408.266241) (xy 35.007994 -408.213872) (xy 35.081878 -408.168125) (xy 35.159667 -408.129391)
			(xy 35.240699 -408.097999) (xy 35.324281 -408.074218) (xy 35.409701 -408.05825) (xy 35.49623 -408.050232)
			(xy 35.58313 -408.050232) (xy 35.669659 -408.05825) (xy 35.755079 -408.074218) (xy 35.838661 -408.097999)
			(xy 35.919693 -408.129391) (xy 35.997482 -408.168125) (xy 36.071366 -408.213872) (xy 36.140713 -408.266241)
			(xy 36.204933 -408.324785) (xy 36.263477 -408.389005) (xy 36.315846 -408.458352) (xy 36.361593 -408.532236)
			(xy 36.400327 -408.610025) (xy 36.431719 -408.691057) (xy 36.4555 -408.774639) (xy 36.471468 -408.860059)
			(xy 36.479486 -408.946588) (xy 36.479988 -408.990038) (xy 36.479486 -409.033488) (xy 36.471468 -409.120017)
			(xy 36.4555 -409.205437) (xy 36.431719 -409.289019) (xy 36.400327 -409.370051) (xy 36.361593 -409.44784)
			(xy 36.315846 -409.521724) (xy 36.263477 -409.591071) (xy 36.204933 -409.655291) (xy 36.140713 -409.713835)
			(xy 36.071366 -409.766204) (xy 35.997482 -409.811951) (xy 35.919693 -409.850685) (xy 35.838661 -409.882077)
			(xy 35.755079 -409.905858) (xy 35.669659 -409.921826) (xy 35.58313 -409.929844) (xy 35.49623 -409.929844)
			(xy 35.409701 -409.921826) (xy 35.324281 -409.905858) (xy 35.240699 -409.882077) (xy 35.159667 -409.850685)
			(xy 35.081878 -409.811951) (xy 35.007994 -409.766204) (xy 34.938647 -409.713835) (xy 34.874427 -409.655291)
			(xy 34.815883 -409.591071) (xy 34.763514 -409.521724) (xy 34.717767 -409.44784) (xy 34.679033 -409.370051)
			(xy 34.647641 -409.289019) (xy 34.62386 -409.205437) (xy 34.607892 -409.120017) (xy 34.599874 -409.033488)
			(xy 31.399508 -409.033488) (xy 31.391675 -409.118813) (xy 31.37599 -409.203502) (xy 31.352625 -409.286401)
			(xy 31.321778 -409.366817) (xy 31.283706 -409.444074) (xy 31.238729 -409.517527) (xy 31.187222 -409.586558)
			(xy 31.129619 -409.650589) (xy 31.066401 -409.709085) (xy 30.998099 -409.761554) (xy 30.925285 -409.807558)
			(xy 30.848569 -409.846709) (xy 30.768594 -409.878681) (xy 30.68603 -409.903206) (xy 30.60157 -409.920077)
			(xy 30.515921 -409.929153) (xy 30.4298 -409.930359) (xy 30.34393 -409.923685) (xy 30.25903 -409.909185)
			(xy 30.175812 -409.886983) (xy 30.094974 -409.857263) (xy 30.017191 -409.820275) (xy 29.979874 -409.798774)
			(xy 29.960952 -409.78802) (xy 29.920317 -409.772437) (xy 29.877622 -409.764002) (xy 29.834115 -409.762961)
			(xy 29.791065 -409.769345) (xy 29.749732 -409.782966) (xy 29.711321 -409.803427) (xy 29.676957 -409.83013)
			(xy 29.647641 -409.862296) (xy 29.624232 -409.898984) (xy 29.607412 -409.939122) (xy 29.597673 -409.981539)
			(xy 29.59608 -410.003244) (xy 29.59608 -410.516832) (xy 29.597725 -410.538526) (xy 29.607484 -410.580921)
			(xy 29.624315 -410.621036) (xy 29.647727 -410.657702) (xy 29.677038 -410.689849) (xy 29.711393 -410.716539)
			(xy 29.749788 -410.736992) (xy 29.791104 -410.750614) (xy 29.834135 -410.757005) (xy 29.877627 -410.755979)
			(xy 29.920309 -410.747568) (xy 29.960937 -410.732015) (xy 29.979874 -410.721302) (xy 30.017157 -410.699744)
			(xy 30.094938 -410.662752) (xy 30.175775 -410.633029) (xy 30.258993 -410.610823) (xy 30.343892 -410.59632)
			(xy 30.429761 -410.589642) (xy 30.515882 -410.590844) (xy 30.601532 -410.599917) (xy 30.685993 -410.616785)
			(xy 30.768557 -410.641306) (xy 30.848534 -410.673275) (xy 30.925251 -410.712423) (xy 30.998067 -410.758424)
			(xy 31.066372 -410.81089) (xy 31.129592 -410.869383) (xy 31.187198 -410.933412) (xy 31.238707 -411.002441)
			(xy 31.283687 -411.075892) (xy 31.321763 -411.153148) (xy 31.352613 -411.233562) (xy 31.375981 -411.31646)
			(xy 31.391669 -411.401148) (xy 31.399548 -411.486916) (xy 31.399549 -411.573045) (xy 31.399508 -411.573488)
			(xy 34.599874 -411.573488) (xy 34.599874 -411.486588) (xy 34.607892 -411.400059) (xy 34.62386 -411.314639)
			(xy 34.647641 -411.231057) (xy 34.679033 -411.150025) (xy 34.717767 -411.072236) (xy 34.763514 -410.998352)
			(xy 34.815883 -410.929005) (xy 34.874427 -410.864785) (xy 34.938647 -410.806241) (xy 35.007994 -410.753872)
			(xy 35.081878 -410.708125) (xy 35.159667 -410.669391) (xy 35.240699 -410.637999) (xy 35.324281 -410.614218)
			(xy 35.409701 -410.59825) (xy 35.49623 -410.590232) (xy 35.58313 -410.590232) (xy 35.669659 -410.59825)
			(xy 35.755079 -410.614218) (xy 35.838661 -410.637999) (xy 35.919693 -410.669391) (xy 35.997482 -410.708125)
			(xy 36.071366 -410.753872) (xy 36.140713 -410.806241) (xy 36.204933 -410.864785) (xy 36.263477 -410.929005)
			(xy 36.315846 -410.998352) (xy 36.361593 -411.072236) (xy 36.400327 -411.150025) (xy 36.431719 -411.231057)
			(xy 36.4555 -411.314639) (xy 36.471468 -411.400059) (xy 36.479486 -411.486588) (xy 36.479988 -411.530038)
			(xy 36.479486 -411.573488) (xy 36.471468 -411.660017) (xy 36.4555 -411.745437) (xy 36.431719 -411.829019)
			(xy 36.400327 -411.910051) (xy 36.383933 -411.942975) (xy 65.293443 -411.942975) (xy 65.297334 -411.888631)
			(xy 65.308919 -411.835394) (xy 65.327962 -411.784347) (xy 65.354076 -411.736531) (xy 65.386729 -411.692917)
			(xy 65.425257 -411.654395) (xy 65.468876 -411.621747) (xy 65.516696 -411.59564) (xy 65.567745 -411.576604)
			(xy 65.620984 -411.565026) (xy 65.675328 -411.561143) (xy 65.729672 -411.565034) (xy 65.782909 -411.576619)
			(xy 65.833955 -411.595663) (xy 65.881772 -411.621778) (xy 65.903856 -411.637734) (xy 65.922868 -411.65133)
			(xy 65.964751 -411.672062) (xy 66.009719 -411.684788) (xy 66.056256 -411.689078) (xy 66.102793 -411.684788)
			(xy 66.147761 -411.672062) (xy 66.189644 -411.65133) (xy 66.208656 -411.637734) (xy 66.230706 -411.621714)
			(xy 66.278537 -411.59558) (xy 66.3296 -411.576521) (xy 66.382857 -411.564923) (xy 66.437222 -411.561023)
			(xy 66.491588 -411.564901) (xy 66.544849 -411.576477) (xy 66.595921 -411.595515) (xy 66.643762 -411.621629)
			(xy 66.6874 -411.654286) (xy 66.725946 -411.692821) (xy 66.758615 -411.73645) (xy 66.784742 -411.784285)
			(xy 66.803794 -411.835351) (xy 66.815384 -411.888609) (xy 66.819277 -411.942975) (xy 68.285036 -411.942975)
			(xy 68.288927 -411.888629) (xy 68.300512 -411.835391) (xy 68.319556 -411.784343) (xy 68.345671 -411.736525)
			(xy 68.378326 -411.69291) (xy 68.416856 -411.654387) (xy 68.460475 -411.621739) (xy 68.508298 -411.595631)
			(xy 68.559348 -411.576595) (xy 68.612589 -411.565018) (xy 68.666935 -411.561136) (xy 68.72128 -411.565028)
			(xy 68.774519 -411.576615) (xy 68.825566 -411.59566) (xy 68.873384 -411.621777) (xy 68.895468 -411.637734)
			(xy 68.91448 -411.65133) (xy 68.956363 -411.672062) (xy 69.001331 -411.684788) (xy 69.047868 -411.689078)
			(xy 69.094405 -411.684788) (xy 69.139373 -411.672062) (xy 69.181256 -411.65133) (xy 69.200268 -411.637734)
			(xy 69.222318 -411.621715) (xy 69.270148 -411.595583) (xy 69.32121 -411.576526) (xy 69.374465 -411.564929)
			(xy 69.428829 -411.561031) (xy 69.483193 -411.564909) (xy 69.536453 -411.576485) (xy 69.587522 -411.595524)
			(xy 69.635362 -411.621637) (xy 69.678999 -411.654294) (xy 69.717543 -411.692828) (xy 69.75021 -411.736456)
			(xy 69.776336 -411.78429) (xy 69.795387 -411.835355) (xy 69.806977 -411.888611) (xy 69.810869 -411.942975)
			(xy 69.806984 -411.997339) (xy 69.795402 -412.050597) (xy 69.776357 -412.101664) (xy 69.750238 -412.149501)
			(xy 69.717576 -412.193134) (xy 69.679037 -412.231673) (xy 69.635405 -412.264335) (xy 69.587568 -412.290455)
			(xy 69.536501 -412.3095) (xy 69.483243 -412.321084) (xy 69.428879 -412.324969) (xy 69.374515 -412.321078)
			(xy 69.321259 -412.309489) (xy 69.270194 -412.290438) (xy 69.22236 -412.264313) (xy 69.200268 -412.24835)
			(xy 69.181256 -412.234754) (xy 69.139373 -412.214022) (xy 69.094405 -412.201296) (xy 69.047868 -412.197006)
			(xy 69.001331 -412.201296) (xy 68.956363 -412.214022) (xy 68.91448 -412.234754) (xy 68.895468 -412.24835)
			(xy 68.873341 -412.264251) (xy 68.82552 -412.290361) (xy 68.77447 -412.309399) (xy 68.721231 -412.320979)
			(xy 68.666885 -412.324864) (xy 68.612539 -412.320975) (xy 68.5593 -412.309391) (xy 68.508252 -412.290348)
			(xy 68.460433 -412.264234) (xy 68.416817 -412.23158) (xy 68.378293 -412.193052) (xy 68.345644 -412.149433)
			(xy 68.319535 -412.101611) (xy 68.300498 -412.050561) (xy 68.28892 -411.997321) (xy 68.285036 -411.942975)
			(xy 66.819277 -411.942975) (xy 66.815391 -411.997341) (xy 66.803808 -412.0506) (xy 66.784763 -412.101669)
			(xy 66.758642 -412.149507) (xy 66.725979 -412.193141) (xy 66.687439 -412.231681) (xy 66.643805 -412.264344)
			(xy 66.595967 -412.290464) (xy 66.544898 -412.309509) (xy 66.491638 -412.321092) (xy 66.437272 -412.324977)
			(xy 66.382907 -412.321084) (xy 66.329649 -412.309493) (xy 66.278583 -412.29044) (xy 66.230748 -412.264314)
			(xy 66.208656 -412.24835) (xy 66.189644 -412.234754) (xy 66.147761 -412.214022) (xy 66.102793 -412.201296)
			(xy 66.056256 -412.197006) (xy 66.009719 -412.201296) (xy 65.964751 -412.214022) (xy 65.922868 -412.234754)
			(xy 65.903856 -412.24835) (xy 65.881729 -412.26425) (xy 65.833909 -412.290358) (xy 65.782861 -412.309395)
			(xy 65.729622 -412.320973) (xy 65.675278 -412.324857) (xy 65.620934 -412.320967) (xy 65.567697 -412.309382)
			(xy 65.51665 -412.290339) (xy 65.468833 -412.264226) (xy 65.425219 -412.231572) (xy 65.386696 -412.193045)
			(xy 65.354049 -412.149427) (xy 65.327941 -412.101607) (xy 65.308904 -412.050558) (xy 65.297327 -411.997319)
			(xy 65.293443 -411.942975) (xy 36.383933 -411.942975) (xy 36.361593 -411.98784) (xy 36.315846 -412.061724)
			(xy 36.263477 -412.131071) (xy 36.204933 -412.195291) (xy 36.140713 -412.253835) (xy 36.071366 -412.306204)
			(xy 35.997482 -412.351951) (xy 35.919693 -412.390685) (xy 35.838661 -412.422077) (xy 35.755079 -412.445858)
			(xy 35.669659 -412.461826) (xy 35.58313 -412.469844) (xy 35.49623 -412.469844) (xy 35.409701 -412.461826)
			(xy 35.324281 -412.445858) (xy 35.240699 -412.422077) (xy 35.159667 -412.390685) (xy 35.081878 -412.351951)
			(xy 35.007994 -412.306204) (xy 34.938647 -412.253835) (xy 34.874427 -412.195291) (xy 34.815883 -412.131071)
			(xy 34.763514 -412.061724) (xy 34.717767 -411.98784) (xy 34.679033 -411.910051) (xy 34.647641 -411.829019)
			(xy 34.62386 -411.745437) (xy 34.607892 -411.660017) (xy 34.599874 -411.573488) (xy 31.399508 -411.573488)
			(xy 31.391675 -411.658813) (xy 31.37599 -411.743502) (xy 31.352625 -411.826401) (xy 31.321778 -411.906817)
			(xy 31.283706 -411.984074) (xy 31.238729 -412.057527) (xy 31.187222 -412.126558) (xy 31.129619 -412.190589)
			(xy 31.066401 -412.249085) (xy 30.998099 -412.301554) (xy 30.925285 -412.347558) (xy 30.848569 -412.386709)
			(xy 30.768594 -412.418681) (xy 30.68603 -412.443206) (xy 30.60157 -412.460077) (xy 30.515921 -412.469153)
			(xy 30.4298 -412.470359) (xy 30.34393 -412.463685) (xy 30.25903 -412.449185) (xy 30.175812 -412.426983)
			(xy 30.094974 -412.397263) (xy 30.017191 -412.360275) (xy 29.979874 -412.338774) (xy 29.960952 -412.32802)
			(xy 29.920317 -412.312437) (xy 29.877622 -412.304002) (xy 29.834115 -412.302961) (xy 29.791065 -412.309345)
			(xy 29.749732 -412.322966) (xy 29.711321 -412.343427) (xy 29.676957 -412.37013) (xy 29.647641 -412.402296)
			(xy 29.624232 -412.438984) (xy 29.607412 -412.479122) (xy 29.597673 -412.521539) (xy 29.59608 -412.543244)
			(xy 29.59608 -413.056832) (xy 29.597725 -413.078526) (xy 29.607484 -413.120921) (xy 29.624315 -413.161036)
			(xy 29.647727 -413.197702) (xy 29.677038 -413.229849) (xy 29.711393 -413.256539) (xy 29.749788 -413.276992)
			(xy 29.791104 -413.290614) (xy 29.834135 -413.297005) (xy 29.877627 -413.295979) (xy 29.920309 -413.287568)
			(xy 29.960937 -413.272015) (xy 29.979874 -413.261302) (xy 30.017157 -413.239744) (xy 30.094938 -413.202752)
			(xy 30.175775 -413.173029) (xy 30.258993 -413.150823) (xy 30.343892 -413.13632) (xy 30.429761 -413.129642)
			(xy 30.515882 -413.130844) (xy 30.601532 -413.139917) (xy 30.685993 -413.156785) (xy 30.768557 -413.181306)
			(xy 30.848534 -413.213275) (xy 30.925251 -413.252423) (xy 30.998067 -413.298424) (xy 31.066372 -413.35089)
			(xy 31.129592 -413.409383) (xy 31.187198 -413.473412) (xy 31.238707 -413.542441) (xy 31.283687 -413.615892)
			(xy 31.321763 -413.693148) (xy 31.352613 -413.773562) (xy 31.375981 -413.85646) (xy 31.391669 -413.941148)
			(xy 31.399548 -414.026916) (xy 31.399549 -414.113045) (xy 31.399508 -414.113488) (xy 34.599874 -414.113488)
			(xy 34.599874 -414.026588) (xy 34.607892 -413.940059) (xy 34.62386 -413.854639) (xy 34.647641 -413.771057)
			(xy 34.679033 -413.690025) (xy 34.717767 -413.612236) (xy 34.763514 -413.538352) (xy 34.815883 -413.469005)
			(xy 34.874427 -413.404785) (xy 34.938647 -413.346241) (xy 35.007994 -413.293872) (xy 35.081878 -413.248125)
			(xy 35.159667 -413.209391) (xy 35.240699 -413.177999) (xy 35.324281 -413.154218) (xy 35.409701 -413.13825)
			(xy 35.49623 -413.130232) (xy 35.58313 -413.130232) (xy 35.669659 -413.13825) (xy 35.755079 -413.154218)
			(xy 35.838661 -413.177999) (xy 35.919693 -413.209391) (xy 35.997482 -413.248125) (xy 36.071366 -413.293872)
			(xy 36.140713 -413.346241) (xy 36.204933 -413.404785) (xy 36.263477 -413.469005) (xy 36.315846 -413.538352)
			(xy 36.361593 -413.612236) (xy 36.400327 -413.690025) (xy 36.431719 -413.771057) (xy 36.4555 -413.854639)
			(xy 36.471468 -413.940059) (xy 36.479486 -414.026588) (xy 36.479988 -414.070038) (xy 36.479486 -414.113488)
			(xy 36.471468 -414.200017) (xy 36.4555 -414.285437) (xy 36.431719 -414.369019) (xy 36.400327 -414.450051)
			(xy 36.361593 -414.52784) (xy 36.315846 -414.601724) (xy 36.306629 -414.613929) (xy 65.293371 -414.613929)
			(xy 65.297255 -414.559574) (xy 65.308834 -414.506325) (xy 65.327874 -414.455267) (xy 65.353986 -414.407437)
			(xy 65.38664 -414.363811) (xy 65.425169 -414.325275) (xy 65.468791 -414.292616) (xy 65.516617 -414.266497)
			(xy 65.567673 -414.24745) (xy 65.62092 -414.235863) (xy 65.675274 -414.231971) (xy 65.729629 -414.235855)
			(xy 65.782877 -414.247435) (xy 65.833936 -414.266475) (xy 65.881765 -414.292588) (xy 65.903856 -414.308544)
			(xy 65.922868 -414.32214) (xy 65.964751 -414.342872) (xy 66.009719 -414.355598) (xy 66.056256 -414.359888)
			(xy 66.102793 -414.355598) (xy 66.147761 -414.342872) (xy 66.189644 -414.32214) (xy 66.208656 -414.308544)
			(xy 66.23079 -414.292645) (xy 66.278616 -414.266524) (xy 66.329673 -414.247475) (xy 66.382921 -414.235887)
			(xy 66.437276 -414.231996) (xy 66.491631 -414.23588) (xy 66.544881 -414.247461) (xy 66.59594 -414.266503)
			(xy 66.643769 -414.292619) (xy 66.687394 -414.325276) (xy 66.725927 -414.363809) (xy 66.758584 -414.407435)
			(xy 66.784698 -414.455264) (xy 66.80374 -414.506323) (xy 66.815321 -414.559573) (xy 66.819204 -414.613929)
			(xy 68.284964 -414.613929) (xy 68.288848 -414.559573) (xy 68.300428 -414.506322) (xy 68.319468 -414.455262)
			(xy 68.345582 -414.407431) (xy 68.378236 -414.363804) (xy 68.416768 -414.325268) (xy 68.460391 -414.292607)
			(xy 68.508218 -414.266488) (xy 68.559276 -414.247441) (xy 68.612525 -414.235855) (xy 68.666881 -414.231964)
			(xy 68.721237 -414.235849) (xy 68.774487 -414.24743) (xy 68.825547 -414.266472) (xy 68.873377 -414.292587)
			(xy 68.895468 -414.308544) (xy 68.91448 -414.32214) (xy 68.956363 -414.342872) (xy 69.001331 -414.355598)
			(xy 69.047868 -414.359888) (xy 69.094405 -414.355598) (xy 69.139373 -414.342872) (xy 69.181256 -414.32214)
			(xy 69.200268 -414.308544) (xy 69.222402 -414.292646) (xy 69.270227 -414.266526) (xy 69.321282 -414.24748)
			(xy 69.374529 -414.235893) (xy 69.428883 -414.232003) (xy 69.483237 -414.235888) (xy 69.536484 -414.24747)
			(xy 69.587541 -414.266512) (xy 69.635369 -414.292627) (xy 69.678992 -414.325284) (xy 69.717524 -414.363816)
			(xy 69.750179 -414.407441) (xy 69.776293 -414.455269) (xy 69.795334 -414.506327) (xy 69.806914 -414.559575)
			(xy 69.810797 -414.613929) (xy 69.806905 -414.668282) (xy 69.795317 -414.721529) (xy 69.776269 -414.772584)
			(xy 69.750148 -414.820408) (xy 69.717486 -414.864027) (xy 69.678949 -414.902554) (xy 69.63532 -414.935204)
			(xy 69.587489 -414.961312) (xy 69.536429 -414.980347) (xy 69.48318 -414.99192) (xy 69.428825 -414.995797)
			(xy 69.374472 -414.991899) (xy 69.321227 -414.980304) (xy 69.270174 -414.96125) (xy 69.222353 -414.935123)
			(xy 69.200268 -414.91916) (xy 69.181256 -414.905564) (xy 69.139373 -414.884832) (xy 69.094405 -414.872106)
			(xy 69.047868 -414.867816) (xy 69.001331 -414.872106) (xy 68.956363 -414.884832) (xy 68.91448 -414.905564)
			(xy 68.895468 -414.91916) (xy 68.873426 -414.935182) (xy 68.825599 -414.961304) (xy 68.774543 -414.980353)
			(xy 68.721294 -414.991943) (xy 68.666939 -414.995836) (xy 68.612582 -414.991954) (xy 68.559332 -414.980375)
			(xy 68.508271 -414.961336) (xy 68.460439 -414.935224) (xy 68.416811 -414.90257) (xy 68.378274 -414.86404)
			(xy 68.345613 -414.820417) (xy 68.319492 -414.77259) (xy 68.300444 -414.721533) (xy 68.288856 -414.668285)
			(xy 68.284964 -414.613929) (xy 66.819204 -414.613929) (xy 66.815312 -414.668284) (xy 66.803724 -414.721532)
			(xy 66.784675 -414.772588) (xy 66.758552 -414.820414) (xy 66.725889 -414.864034) (xy 66.687351 -414.902562)
			(xy 66.64372 -414.935212) (xy 66.595888 -414.961321) (xy 66.544826 -414.980355) (xy 66.491574 -414.991928)
			(xy 66.437218 -414.995804) (xy 66.382864 -414.991905) (xy 66.329617 -414.980309) (xy 66.278564 -414.961252)
			(xy 66.230742 -414.935124) (xy 66.208656 -414.91916) (xy 66.189644 -414.905564) (xy 66.147761 -414.884832)
			(xy 66.102793 -414.872106) (xy 66.056256 -414.867816) (xy 66.009719 -414.872106) (xy 65.964751 -414.884832)
			(xy 65.922868 -414.905564) (xy 65.903856 -414.91916) (xy 65.881814 -414.935181) (xy 65.833989 -414.961301)
			(xy 65.782933 -414.980349) (xy 65.729686 -414.991937) (xy 65.675332 -414.995829) (xy 65.620977 -414.991946)
			(xy 65.567728 -414.980367) (xy 65.516669 -414.961327) (xy 65.46884 -414.935215) (xy 65.425213 -414.902562)
			(xy 65.386677 -414.864033) (xy 65.354017 -414.820411) (xy 65.327898 -414.772586) (xy 65.30885 -414.72153)
			(xy 65.297263 -414.668283) (xy 65.293371 -414.613929) (xy 36.306629 -414.613929) (xy 36.263477 -414.671071)
			(xy 36.204933 -414.735291) (xy 36.140713 -414.793835) (xy 36.071366 -414.846204) (xy 35.997482 -414.891951)
			(xy 35.919693 -414.930685) (xy 35.838661 -414.962077) (xy 35.755079 -414.985858) (xy 35.669659 -415.001826)
			(xy 35.58313 -415.009844) (xy 35.49623 -415.009844) (xy 35.409701 -415.001826) (xy 35.324281 -414.985858)
			(xy 35.240699 -414.962077) (xy 35.159667 -414.930685) (xy 35.081878 -414.891951) (xy 35.007994 -414.846204)
			(xy 34.938647 -414.793835) (xy 34.874427 -414.735291) (xy 34.815883 -414.671071) (xy 34.763514 -414.601724)
			(xy 34.717767 -414.52784) (xy 34.679033 -414.450051) (xy 34.647641 -414.369019) (xy 34.62386 -414.285437)
			(xy 34.607892 -414.200017) (xy 34.599874 -414.113488) (xy 31.399508 -414.113488) (xy 31.391675 -414.198813)
			(xy 31.37599 -414.283502) (xy 31.352625 -414.366401) (xy 31.321778 -414.446817) (xy 31.283706 -414.524074)
			(xy 31.238729 -414.597527) (xy 31.187222 -414.666558) (xy 31.129619 -414.730589) (xy 31.066401 -414.789085)
			(xy 30.998099 -414.841554) (xy 30.925285 -414.887558) (xy 30.848569 -414.926709) (xy 30.768594 -414.958681)
			(xy 30.68603 -414.983206) (xy 30.60157 -415.000077) (xy 30.515921 -415.009153) (xy 30.4298 -415.010359)
			(xy 30.34393 -415.003685) (xy 30.25903 -414.989185) (xy 30.175812 -414.966983) (xy 30.094974 -414.937263)
			(xy 30.017191 -414.900275) (xy 29.979874 -414.878774) (xy 29.960952 -414.86802) (xy 29.920317 -414.852437)
			(xy 29.877622 -414.844002) (xy 29.834115 -414.842961) (xy 29.791065 -414.849345) (xy 29.749732 -414.862966)
			(xy 29.711321 -414.883427) (xy 29.676957 -414.91013) (xy 29.647641 -414.942296) (xy 29.624232 -414.978984)
			(xy 29.607412 -415.019122) (xy 29.597673 -415.061539) (xy 29.59608 -415.083244) (xy 29.59608 -415.596832)
			(xy 29.597725 -415.618526) (xy 29.607484 -415.660921) (xy 29.624315 -415.701036) (xy 29.647727 -415.737702)
			(xy 29.677038 -415.769849) (xy 29.711393 -415.796539) (xy 29.749788 -415.816992) (xy 29.791104 -415.830614)
			(xy 29.834135 -415.837005) (xy 29.877627 -415.835979) (xy 29.920309 -415.827568) (xy 29.960937 -415.812015)
			(xy 29.979874 -415.801302) (xy 30.017157 -415.779744) (xy 30.094938 -415.742752) (xy 30.175775 -415.713029)
			(xy 30.258993 -415.690823) (xy 30.343892 -415.67632) (xy 30.429761 -415.669642) (xy 30.515882 -415.670844)
			(xy 30.601532 -415.679917) (xy 30.685993 -415.696785) (xy 30.768557 -415.721306) (xy 30.848534 -415.753275)
			(xy 30.925251 -415.792423) (xy 30.998067 -415.838424) (xy 31.066372 -415.89089) (xy 31.129592 -415.949383)
			(xy 31.187198 -416.013412) (xy 31.238707 -416.082441) (xy 31.283687 -416.155892) (xy 31.321763 -416.233148)
			(xy 31.352613 -416.313562) (xy 31.375981 -416.39646) (xy 31.391669 -416.481148) (xy 31.399548 -416.566916)
			(xy 31.399549 -416.653045) (xy 31.399508 -416.653488) (xy 34.599874 -416.653488) (xy 34.599874 -416.566588)
			(xy 34.607892 -416.480059) (xy 34.62386 -416.394639) (xy 34.647641 -416.311057) (xy 34.679033 -416.230025)
			(xy 34.717767 -416.152236) (xy 34.763514 -416.078352) (xy 34.815883 -416.009005) (xy 34.874427 -415.944785)
			(xy 34.938647 -415.886241) (xy 35.007994 -415.833872) (xy 35.081878 -415.788125) (xy 35.159667 -415.749391)
			(xy 35.240699 -415.717999) (xy 35.324281 -415.694218) (xy 35.409701 -415.67825) (xy 35.49623 -415.670232)
			(xy 35.58313 -415.670232) (xy 35.669659 -415.67825) (xy 35.755079 -415.694218) (xy 35.838661 -415.717999)
			(xy 35.919693 -415.749391) (xy 35.997482 -415.788125) (xy 36.071366 -415.833872) (xy 36.140713 -415.886241)
			(xy 36.204933 -415.944785) (xy 36.263477 -416.009005) (xy 36.315846 -416.078352) (xy 36.361593 -416.152236)
			(xy 36.400327 -416.230025) (xy 36.431719 -416.311057) (xy 36.4555 -416.394639) (xy 36.471468 -416.480059)
			(xy 36.479486 -416.566588) (xy 36.479988 -416.610038) (xy 36.479486 -416.653488) (xy 36.471468 -416.740017)
			(xy 36.4555 -416.825437) (xy 36.431719 -416.909019) (xy 36.400327 -416.990051) (xy 36.361593 -417.06784)
			(xy 36.315846 -417.141724) (xy 36.263477 -417.211071) (xy 36.204933 -417.275291) (xy 36.197478 -417.282087)
			(xy 65.293427 -417.282087) (xy 65.297316 -417.227741) (xy 65.3089 -417.174501) (xy 65.327942 -417.123452)
			(xy 65.354056 -417.075632) (xy 65.38671 -417.032016) (xy 65.425238 -416.99349) (xy 65.468857 -416.96084)
			(xy 65.516678 -416.93473) (xy 65.567729 -416.915692) (xy 65.62097 -416.904112) (xy 65.675316 -416.900227)
			(xy 65.729662 -416.904117) (xy 65.782902 -416.915701) (xy 65.833951 -416.934744) (xy 65.88177 -416.960858)
			(xy 65.903856 -416.976814) (xy 65.922868 -416.99041) (xy 65.964751 -417.011142) (xy 66.009719 -417.023868)
			(xy 66.056256 -417.028158) (xy 66.102793 -417.023868) (xy 66.147761 -417.011142) (xy 66.189644 -416.99041)
			(xy 66.208656 -416.976814) (xy 66.230725 -416.960821) (xy 66.278554 -416.93469) (xy 66.329616 -416.915633)
			(xy 66.382871 -416.904037) (xy 66.437234 -416.90014) (xy 66.491598 -416.904019) (xy 66.544856 -416.915596)
			(xy 66.595925 -416.934635) (xy 66.643764 -416.960749) (xy 66.687399 -416.993406) (xy 66.725942 -417.031941)
			(xy 66.758608 -417.075569) (xy 66.784732 -417.123403) (xy 66.803782 -417.174467) (xy 66.81537 -417.227724)
			(xy 66.819261 -417.282087) (xy 68.28502 -417.282087) (xy 68.288909 -417.227739) (xy 68.300493 -417.174498)
			(xy 68.319537 -417.123447) (xy 68.345651 -417.075626) (xy 68.378306 -417.032009) (xy 68.416836 -416.993482)
			(xy 68.460457 -416.960832) (xy 68.50828 -416.934722) (xy 68.559332 -416.915683) (xy 68.612575 -416.904104)
			(xy 68.666923 -416.90022) (xy 68.721271 -416.904111) (xy 68.774512 -416.915696) (xy 68.825562 -416.934741)
			(xy 68.873382 -416.960857) (xy 68.895468 -416.976814) (xy 68.91448 -416.99041) (xy 68.956363 -417.011142)
			(xy 69.001331 -417.023868) (xy 69.047868 -417.028158) (xy 69.094405 -417.023868) (xy 69.139373 -417.011142)
			(xy 69.181256 -416.99041) (xy 69.200268 -416.976814) (xy 69.222336 -416.960822) (xy 69.270165 -416.934693)
			(xy 69.321226 -416.915638) (xy 69.374479 -416.904043) (xy 69.428841 -416.900147) (xy 69.483203 -416.904027)
			(xy 69.53646 -416.915604) (xy 69.587527 -416.934644) (xy 69.635364 -416.960757) (xy 69.678997 -416.993414)
			(xy 69.717539 -417.031948) (xy 69.750203 -417.075575) (xy 69.776326 -417.123407) (xy 69.795375 -417.174471)
			(xy 69.806963 -417.227725) (xy 69.810853 -417.282087) (xy 69.806967 -417.336449) (xy 69.795383 -417.389704)
			(xy 69.776337 -417.440769) (xy 69.750218 -417.488603) (xy 69.717556 -417.532232) (xy 69.679017 -417.570769)
			(xy 69.635386 -417.603428) (xy 69.587551 -417.629545) (xy 69.536485 -417.648588) (xy 69.483229 -417.66017)
			(xy 69.428867 -417.664053) (xy 69.374506 -417.66016) (xy 69.321252 -417.64857) (xy 69.270189 -417.629518)
			(xy 69.222359 -417.603393) (xy 69.200268 -417.58743) (xy 69.181256 -417.573834) (xy 69.139373 -417.553102)
			(xy 69.094405 -417.540376) (xy 69.047868 -417.536086) (xy 69.001331 -417.540376) (xy 68.956363 -417.553102)
			(xy 68.91448 -417.573834) (xy 68.895468 -417.58743) (xy 68.87336 -417.603358) (xy 68.825538 -417.62947)
			(xy 68.774486 -417.648511) (xy 68.721245 -417.660093) (xy 68.666897 -417.66398) (xy 68.612549 -417.660092)
			(xy 68.559307 -417.648509) (xy 68.508256 -417.629468) (xy 68.460434 -417.603354) (xy 68.416816 -417.5707)
			(xy 68.378289 -417.532171) (xy 68.345637 -417.488552) (xy 68.319526 -417.440729) (xy 68.300486 -417.389677)
			(xy 68.288906 -417.336435) (xy 68.28502 -417.282087) (xy 66.819261 -417.282087) (xy 66.815374 -417.33645)
			(xy 66.803789 -417.389707) (xy 66.784743 -417.440773) (xy 66.758622 -417.488609) (xy 66.725959 -417.532239)
			(xy 66.687419 -417.570777) (xy 66.643786 -417.603437) (xy 66.595949 -417.629554) (xy 66.544882 -417.648597)
			(xy 66.491624 -417.660178) (xy 66.43726 -417.664061) (xy 66.382897 -417.660166) (xy 66.329642 -417.648574)
			(xy 66.278578 -417.629521) (xy 66.230747 -417.603394) (xy 66.208656 -417.58743) (xy 66.189644 -417.573834)
			(xy 66.147761 -417.553102) (xy 66.102793 -417.540376) (xy 66.056256 -417.536086) (xy 66.009719 -417.540376)
			(xy 65.964751 -417.553102) (xy 65.922868 -417.573834) (xy 65.903856 -417.58743) (xy 65.881748 -417.603357)
			(xy 65.833927 -417.629467) (xy 65.782877 -417.648507) (xy 65.729636 -417.660087) (xy 65.67529 -417.663973)
			(xy 65.620944 -417.660084) (xy 65.567704 -417.648501) (xy 65.516654 -417.629459) (xy 65.468835 -417.603346)
			(xy 65.425218 -417.570692) (xy 65.386692 -417.532164) (xy 65.354042 -417.488546) (xy 65.327931 -417.440724)
			(xy 65.308892 -417.389674) (xy 65.297313 -417.336433) (xy 65.293427 -417.282087) (xy 36.197478 -417.282087)
			(xy 36.140713 -417.333835) (xy 36.071366 -417.386204) (xy 35.997482 -417.431951) (xy 35.919693 -417.470685)
			(xy 35.838661 -417.502077) (xy 35.755079 -417.525858) (xy 35.669659 -417.541826) (xy 35.58313 -417.549844)
			(xy 35.49623 -417.549844) (xy 35.409701 -417.541826) (xy 35.324281 -417.525858) (xy 35.240699 -417.502077)
			(xy 35.159667 -417.470685) (xy 35.081878 -417.431951) (xy 35.007994 -417.386204) (xy 34.938647 -417.333835)
			(xy 34.874427 -417.275291) (xy 34.815883 -417.211071) (xy 34.763514 -417.141724) (xy 34.717767 -417.06784)
			(xy 34.679033 -416.990051) (xy 34.647641 -416.909019) (xy 34.62386 -416.825437) (xy 34.607892 -416.740017)
			(xy 34.599874 -416.653488) (xy 31.399508 -416.653488) (xy 31.391675 -416.738813) (xy 31.37599 -416.823502)
			(xy 31.352625 -416.906401) (xy 31.321778 -416.986817) (xy 31.283706 -417.064074) (xy 31.238729 -417.137527)
			(xy 31.187222 -417.206558) (xy 31.129619 -417.270589) (xy 31.066401 -417.329085) (xy 30.998099 -417.381554)
			(xy 30.925285 -417.427558) (xy 30.848569 -417.466709) (xy 30.768594 -417.498681) (xy 30.68603 -417.523206)
			(xy 30.60157 -417.540077) (xy 30.515921 -417.549153) (xy 30.4298 -417.550359) (xy 30.34393 -417.543685)
			(xy 30.25903 -417.529185) (xy 30.175812 -417.506983) (xy 30.094974 -417.477263) (xy 30.017191 -417.440275)
			(xy 29.979874 -417.418774) (xy 29.960952 -417.40802) (xy 29.920317 -417.392437) (xy 29.877622 -417.384002)
			(xy 29.834115 -417.382961) (xy 29.791065 -417.389345) (xy 29.749732 -417.402966) (xy 29.711321 -417.423427)
			(xy 29.676957 -417.45013) (xy 29.647641 -417.482296) (xy 29.624232 -417.518984) (xy 29.607412 -417.559122)
			(xy 29.597673 -417.601539) (xy 29.59608 -417.623244) (xy 29.59608 -418.136832) (xy 29.597725 -418.158526)
			(xy 29.607484 -418.200921) (xy 29.624315 -418.241036) (xy 29.647727 -418.277702) (xy 29.677038 -418.309849)
			(xy 29.711393 -418.336539) (xy 29.749788 -418.356992) (xy 29.791104 -418.370614) (xy 29.834135 -418.377005)
			(xy 29.877627 -418.375979) (xy 29.920309 -418.367568) (xy 29.960937 -418.352015) (xy 29.979874 -418.341302)
			(xy 30.017157 -418.319744) (xy 30.094938 -418.282752) (xy 30.175775 -418.253029) (xy 30.258993 -418.230823)
			(xy 30.343892 -418.21632) (xy 30.429761 -418.209642) (xy 30.515882 -418.210844) (xy 30.601532 -418.219917)
			(xy 30.685993 -418.236785) (xy 30.768557 -418.261306) (xy 30.848534 -418.293275) (xy 30.925251 -418.332423)
			(xy 30.998067 -418.378424) (xy 31.066372 -418.43089) (xy 31.129592 -418.489383) (xy 31.187198 -418.553412)
			(xy 31.238707 -418.622441) (xy 31.283687 -418.695892) (xy 31.321763 -418.773148) (xy 31.352613 -418.853562)
			(xy 31.375981 -418.93646) (xy 31.391669 -419.021148) (xy 31.399548 -419.106916) (xy 31.399549 -419.193045)
			(xy 31.399508 -419.193488) (xy 34.599874 -419.193488) (xy 34.599874 -419.106588) (xy 34.607892 -419.020059)
			(xy 34.62386 -418.934639) (xy 34.647641 -418.851057) (xy 34.679033 -418.770025) (xy 34.717767 -418.692236)
			(xy 34.763514 -418.618352) (xy 34.815883 -418.549005) (xy 34.874427 -418.484785) (xy 34.938647 -418.426241)
			(xy 35.007994 -418.373872) (xy 35.081878 -418.328125) (xy 35.159667 -418.289391) (xy 35.240699 -418.257999)
			(xy 35.324281 -418.234218) (xy 35.409701 -418.21825) (xy 35.49623 -418.210232) (xy 35.58313 -418.210232)
			(xy 35.669659 -418.21825) (xy 35.755079 -418.234218) (xy 35.838661 -418.257999) (xy 35.919693 -418.289391)
			(xy 35.997482 -418.328125) (xy 36.071366 -418.373872) (xy 36.140713 -418.426241) (xy 36.204933 -418.484785)
			(xy 36.263477 -418.549005) (xy 36.315846 -418.618352) (xy 36.352477 -418.677513) (xy 47.978812 -418.677513)
			(xy 47.978812 -418.596403) (xy 47.986762 -418.515684) (xy 48.002585 -418.436133) (xy 48.02613 -418.358517)
			(xy 48.057169 -418.283581) (xy 48.095404 -418.212049) (xy 48.140466 -418.144609) (xy 48.191921 -418.08191)
			(xy 48.249274 -418.024557) (xy 48.311973 -417.973102) (xy 48.379413 -417.92804) (xy 48.450945 -417.889805)
			(xy 48.525881 -417.858766) (xy 48.603497 -417.835221) (xy 48.683048 -417.819398) (xy 48.763767 -417.811448)
			(xy 48.844877 -417.811448) (xy 48.925596 -417.819398) (xy 49.005147 -417.835221) (xy 49.082763 -417.858766)
			(xy 49.157699 -417.889805) (xy 49.229231 -417.92804) (xy 49.296671 -417.973102) (xy 49.35937 -418.024557)
			(xy 49.416723 -418.08191) (xy 49.468178 -418.144609) (xy 49.51324 -418.212049) (xy 49.551475 -418.283581)
			(xy 49.582514 -418.358517) (xy 49.606059 -418.436133) (xy 49.621882 -418.515684) (xy 49.629832 -418.596403)
			(xy 49.63033 -418.636958) (xy 49.629832 -418.677513) (xy 51.478932 -418.677513) (xy 51.478932 -418.596403)
			(xy 51.486882 -418.515684) (xy 51.502705 -418.436133) (xy 51.52625 -418.358517) (xy 51.557289 -418.283581)
			(xy 51.595524 -418.212049) (xy 51.640586 -418.144609) (xy 51.692041 -418.08191) (xy 51.749394 -418.024557)
			(xy 51.812093 -417.973102) (xy 51.879533 -417.92804) (xy 51.951065 -417.889805) (xy 52.026001 -417.858766)
			(xy 52.103617 -417.835221) (xy 52.183168 -417.819398) (xy 52.263887 -417.811448) (xy 52.344997 -417.811448)
			(xy 52.425716 -417.819398) (xy 52.505267 -417.835221) (xy 52.582883 -417.858766) (xy 52.657819 -417.889805)
			(xy 52.729351 -417.92804) (xy 52.796791 -417.973102) (xy 52.85949 -418.024557) (xy 52.916843 -418.08191)
			(xy 52.968298 -418.144609) (xy 53.01336 -418.212049) (xy 53.051595 -418.283581) (xy 53.082634 -418.358517)
			(xy 53.106179 -418.436133) (xy 53.122002 -418.515684) (xy 53.129952 -418.596403) (xy 53.13045 -418.636958)
			(xy 53.129952 -418.677513) (xy 53.122002 -418.758232) (xy 53.106179 -418.837783) (xy 53.082634 -418.915399)
			(xy 53.051595 -418.990335) (xy 53.01336 -419.061867) (xy 52.968298 -419.129307) (xy 52.916843 -419.192006)
			(xy 52.85949 -419.249359) (xy 52.796791 -419.300814) (xy 52.729351 -419.345876) (xy 52.657819 -419.384111)
			(xy 52.582883 -419.41515) (xy 52.505267 -419.438695) (xy 52.425716 -419.454518) (xy 52.344997 -419.462468)
			(xy 52.263887 -419.462468) (xy 52.183168 -419.454518) (xy 52.103617 -419.438695) (xy 52.026001 -419.41515)
			(xy 51.951065 -419.384111) (xy 51.879533 -419.345876) (xy 51.812093 -419.300814) (xy 51.749394 -419.249359)
			(xy 51.692041 -419.192006) (xy 51.640586 -419.129307) (xy 51.595524 -419.061867) (xy 51.557289 -418.990335)
			(xy 51.52625 -418.915399) (xy 51.502705 -418.837783) (xy 51.486882 -418.758232) (xy 51.478932 -418.677513)
			(xy 49.629832 -418.677513) (xy 49.621882 -418.758232) (xy 49.606059 -418.837783) (xy 49.582514 -418.915399)
			(xy 49.551475 -418.990335) (xy 49.51324 -419.061867) (xy 49.468178 -419.129307) (xy 49.416723 -419.192006)
			(xy 49.35937 -419.249359) (xy 49.296671 -419.300814) (xy 49.229231 -419.345876) (xy 49.157699 -419.384111)
			(xy 49.082763 -419.41515) (xy 49.005147 -419.438695) (xy 48.925596 -419.454518) (xy 48.844877 -419.462468)
			(xy 48.763767 -419.462468) (xy 48.683048 -419.454518) (xy 48.603497 -419.438695) (xy 48.525881 -419.41515)
			(xy 48.450945 -419.384111) (xy 48.379413 -419.345876) (xy 48.311973 -419.300814) (xy 48.249274 -419.249359)
			(xy 48.191921 -419.192006) (xy 48.140466 -419.129307) (xy 48.095404 -419.061867) (xy 48.057169 -418.990335)
			(xy 48.02613 -418.915399) (xy 48.002585 -418.837783) (xy 47.986762 -418.758232) (xy 47.978812 -418.677513)
			(xy 36.352477 -418.677513) (xy 36.361593 -418.692236) (xy 36.400327 -418.770025) (xy 36.431719 -418.851057)
			(xy 36.4555 -418.934639) (xy 36.471468 -419.020059) (xy 36.479486 -419.106588) (xy 36.479988 -419.150038)
			(xy 36.479486 -419.193488) (xy 36.471468 -419.280017) (xy 36.4555 -419.365437) (xy 36.431719 -419.449019)
			(xy 36.400327 -419.530051) (xy 36.361593 -419.60784) (xy 36.333205 -419.653688) (xy 65.293426 -419.653688)
			(xy 65.297315 -419.599341) (xy 65.308898 -419.546102) (xy 65.32794 -419.495052) (xy 65.354054 -419.447232)
			(xy 65.386708 -419.403616) (xy 65.425236 -419.36509) (xy 65.468855 -419.33244) (xy 65.516677 -419.306329)
			(xy 65.567728 -419.28729) (xy 65.620968 -419.275711) (xy 65.675315 -419.271826) (xy 65.729661 -419.275715)
			(xy 65.782901 -419.287299) (xy 65.833951 -419.306342) (xy 65.88177 -419.332456) (xy 65.903856 -419.348412)
			(xy 65.922868 -419.362008) (xy 65.964751 -419.38274) (xy 66.009719 -419.395466) (xy 66.056256 -419.399756)
			(xy 66.102793 -419.395466) (xy 66.147761 -419.38274) (xy 66.189644 -419.362008) (xy 66.208656 -419.348412)
			(xy 66.230726 -419.332421) (xy 66.278556 -419.306291) (xy 66.329618 -419.287234) (xy 66.382872 -419.275639)
			(xy 66.437235 -419.271741) (xy 66.491599 -419.27562) (xy 66.544857 -419.287198) (xy 66.595925 -419.306237)
			(xy 66.643764 -419.332351) (xy 66.687399 -419.365008) (xy 66.725942 -419.403543) (xy 66.758607 -419.447171)
			(xy 66.784731 -419.495004) (xy 66.803781 -419.546069) (xy 66.815369 -419.599325) (xy 66.819259 -419.653688)
			(xy 68.285019 -419.653688) (xy 68.288908 -419.59934) (xy 68.300491 -419.546098) (xy 68.319535 -419.495047)
			(xy 68.345649 -419.447226) (xy 68.378304 -419.403608) (xy 68.416834 -419.365082) (xy 68.460455 -419.332431)
			(xy 68.508278 -419.306321) (xy 68.559331 -419.287282) (xy 68.612573 -419.275703) (xy 68.666922 -419.271819)
			(xy 68.72127 -419.275709) (xy 68.774511 -419.287294) (xy 68.825562 -419.306339) (xy 68.873382 -419.332455)
			(xy 68.895468 -419.348412) (xy 68.91448 -419.362008) (xy 68.956363 -419.38274) (xy 69.001331 -419.395466)
			(xy 69.047868 -419.399756) (xy 69.094405 -419.395466) (xy 69.139373 -419.38274) (xy 69.181256 -419.362008)
			(xy 69.200268 -419.348412) (xy 69.222338 -419.332422) (xy 69.270167 -419.306294) (xy 69.321228 -419.287239)
			(xy 69.374481 -419.275645) (xy 69.428842 -419.271748) (xy 69.483204 -419.275628) (xy 69.53646 -419.287206)
			(xy 69.587527 -419.306246) (xy 69.635364 -419.332359) (xy 69.678997 -419.365016) (xy 69.717538 -419.40355)
			(xy 69.750203 -419.447177) (xy 69.776325 -419.495009) (xy 69.795374 -419.546072) (xy 69.806962 -419.599327)
			(xy 69.810852 -419.653688) (xy 69.806965 -419.70805) (xy 69.795381 -419.761305) (xy 69.776335 -419.812369)
			(xy 69.750216 -419.860203) (xy 69.717554 -419.903832) (xy 69.679015 -419.942369) (xy 69.635384 -419.975028)
			(xy 69.587549 -420.001144) (xy 69.536483 -420.020187) (xy 69.483228 -420.031768) (xy 69.428866 -420.035652)
			(xy 69.374505 -420.031759) (xy 69.321251 -420.020168) (xy 69.270189 -420.001116) (xy 69.222358 -419.974991)
			(xy 69.200268 -419.959028) (xy 69.181256 -419.945432) (xy 69.139373 -419.9247) (xy 69.094405 -419.911974)
			(xy 69.047868 -419.907684) (xy 69.001331 -419.911974) (xy 68.956363 -419.9247) (xy 68.91448 -419.945432)
			(xy 68.895468 -419.959028) (xy 68.873362 -419.974958) (xy 68.82554 -420.001071) (xy 68.774488 -420.020113)
			(xy 68.721246 -420.031695) (xy 68.666898 -420.035581) (xy 68.61255 -420.031694) (xy 68.559308 -420.020111)
			(xy 68.508256 -420.001069) (xy 68.460435 -419.974956) (xy 68.416816 -419.942302) (xy 68.378288 -419.903773)
			(xy 68.345636 -419.860154) (xy 68.319525 -419.812331) (xy 68.300485 -419.761279) (xy 68.288904 -419.708036)
			(xy 68.285019 -419.653688) (xy 66.819259 -419.653688) (xy 66.815372 -419.708051) (xy 66.803788 -419.761308)
			(xy 66.784741 -419.812374) (xy 66.75862 -419.860209) (xy 66.725957 -419.903839) (xy 66.687417 -419.942376)
			(xy 66.643784 -419.975036) (xy 66.595947 -420.001153) (xy 66.54488 -420.020196) (xy 66.491623 -420.031776)
			(xy 66.437259 -420.035659) (xy 66.382896 -420.031765) (xy 66.329641 -420.020173) (xy 66.278578 -420.001119)
			(xy 66.230747 -419.974992) (xy 66.208656 -419.959028) (xy 66.189644 -419.945432) (xy 66.147761 -419.9247)
			(xy 66.102793 -419.911974) (xy 66.056256 -419.907684) (xy 66.009719 -419.911974) (xy 65.964751 -419.9247)
			(xy 65.922868 -419.945432) (xy 65.903856 -419.959028) (xy 65.88175 -419.974957) (xy 65.833929 -420.001068)
			(xy 65.782878 -420.020108) (xy 65.729638 -420.031688) (xy 65.675291 -420.035574) (xy 65.620944 -420.031686)
			(xy 65.567704 -420.020103) (xy 65.516655 -420.001061) (xy 65.468835 -419.974948) (xy 65.425218 -419.942294)
			(xy 65.386692 -419.903766) (xy 65.354041 -419.860148) (xy 65.32793 -419.812326) (xy 65.308891 -419.761275)
			(xy 65.297311 -419.708035) (xy 65.293426 -419.653688) (xy 36.333205 -419.653688) (xy 36.315846 -419.681724)
			(xy 36.263477 -419.751071) (xy 36.204933 -419.815291) (xy 36.140713 -419.873835) (xy 36.071366 -419.926204)
			(xy 35.997482 -419.971951) (xy 35.919693 -420.010685) (xy 35.838661 -420.042077) (xy 35.775246 -420.06012)
			(xy 86.877404 -420.06012) (xy 86.881424 -419.869469) (xy 86.893478 -419.679156) (xy 86.913544 -419.489521)
			(xy 86.941587 -419.3009) (xy 86.977556 -419.11363) (xy 87.021388 -418.928042) (xy 87.073005 -418.744467)
			(xy 87.132315 -418.563231) (xy 87.199213 -418.384656) (xy 87.273579 -418.209061) (xy 87.355281 -418.036756)
			(xy 87.444175 -417.868049) (xy 87.540101 -417.703239) (xy 87.64289 -417.54262) (xy 87.752359 -417.386477)
			(xy 87.868313 -417.235088) (xy 87.990547 -417.088721) (xy 88.118841 -416.947637) (xy 88.252969 -416.812088)
			(xy 88.392693 -416.682313) (xy 88.537763 -416.558543) (xy 88.687921 -416.441) (xy 88.842902 -416.329891)
			(xy 89.002429 -416.225414) (xy 89.166218 -416.127755) (xy 89.333978 -416.037088) (xy 89.505412 -415.953574)
			(xy 89.680214 -415.877361) (xy 89.858073 -415.808585) (xy 90.038674 -415.747367) (xy 90.221694 -415.693818)
			(xy 90.40681 -415.648032) (xy 90.593691 -415.61009) (xy 90.782006 -415.580061) (xy 90.971419 -415.557996)
			(xy 91.161593 -415.543937) (xy 91.352192 -415.537907) (xy 91.542875 -415.539917) (xy 91.733304 -415.549964)
			(xy 91.92314 -415.56803) (xy 92.112046 -415.594083) (xy 92.299685 -415.628076) (xy 92.485725 -415.669949)
			(xy 92.669834 -415.719628) (xy 92.851685 -415.777024) (xy 93.030955 -415.842035) (xy 93.207325 -415.914546)
			(xy 93.380481 -415.994427) (xy 93.550116 -416.081537) (xy 93.715928 -416.175721) (xy 93.877622 -416.276812)
			(xy 94.03491 -416.384628) (xy 94.187513 -416.49898) (xy 94.335161 -416.619663) (xy 94.477589 -416.746464)
			(xy 94.614545 -416.879155) (xy 94.745786 -417.017503) (xy 94.871078 -417.16126) (xy 94.990198 -417.310171)
			(xy 95.102934 -417.463972) (xy 95.209087 -417.622388) (xy 95.308467 -417.785139) (xy 95.400897 -417.951934)
			(xy 95.486214 -418.122478) (xy 95.564266 -418.296466) (xy 95.634913 -418.473591) (xy 95.698031 -418.653536)
			(xy 95.753507 -418.835982) (xy 95.801242 -419.020605) (xy 95.841152 -419.207075) (xy 95.873165 -419.395063)
			(xy 95.897225 -419.584233) (xy 95.913288 -419.774249) (xy 95.921327 -419.964773) (xy 95.92183 -420.06012)
			(xy 95.921327 -420.155467) (xy 95.913288 -420.345991) (xy 95.897225 -420.536007) (xy 95.873165 -420.725177)
			(xy 95.841152 -420.913165) (xy 95.801242 -421.099635) (xy 95.753507 -421.284258) (xy 95.698031 -421.466704)
			(xy 95.634913 -421.646649) (xy 95.564266 -421.823774) (xy 95.486214 -421.997762) (xy 95.400897 -422.168306)
			(xy 95.308467 -422.335101) (xy 95.209087 -422.497852) (xy 95.102934 -422.656268) (xy 94.990198 -422.810069)
			(xy 94.871078 -422.95898) (xy 94.745786 -423.102737) (xy 94.614545 -423.241085) (xy 94.477589 -423.373776)
			(xy 94.335161 -423.500577) (xy 94.187513 -423.62126) (xy 94.03491 -423.735612) (xy 93.877622 -423.843428)
			(xy 93.715928 -423.944519) (xy 93.550116 -424.038703) (xy 93.380481 -424.125813) (xy 93.207325 -424.205694)
			(xy 93.030955 -424.278205) (xy 92.851685 -424.343216) (xy 92.669834 -424.400612) (xy 92.485725 -424.450291)
			(xy 92.299685 -424.492164) (xy 92.112046 -424.526157) (xy 91.92314 -424.55221) (xy 91.733304 -424.570276)
			(xy 91.542875 -424.580323) (xy 91.352192 -424.582333) (xy 91.161593 -424.576303) (xy 90.971419 -424.562244)
			(xy 90.782006 -424.540179) (xy 90.593691 -424.51015) (xy 90.40681 -424.472208) (xy 90.221694 -424.426422)
			(xy 90.038674 -424.372873) (xy 89.858073 -424.311655) (xy 89.680214 -424.242879) (xy 89.505412 -424.166666)
			(xy 89.333978 -424.083152) (xy 89.166218 -423.992485) (xy 89.002429 -423.894826) (xy 88.842902 -423.790349)
			(xy 88.687921 -423.67924) (xy 88.537763 -423.561697) (xy 88.392693 -423.437927) (xy 88.252969 -423.308152)
			(xy 88.118841 -423.172603) (xy 87.990547 -423.031519) (xy 87.868313 -422.885152) (xy 87.752359 -422.733763)
			(xy 87.64289 -422.57762) (xy 87.540101 -422.417001) (xy 87.444175 -422.252191) (xy 87.355281 -422.083484)
			(xy 87.273579 -421.911179) (xy 87.199213 -421.735584) (xy 87.132315 -421.557009) (xy 87.073005 -421.375773)
			(xy 87.021388 -421.192198) (xy 86.977556 -421.00661) (xy 86.941587 -420.81934) (xy 86.913544 -420.630719)
			(xy 86.893478 -420.441084) (xy 86.881424 -420.250771) (xy 86.877404 -420.06012) (xy 35.775246 -420.06012)
			(xy 35.755079 -420.065858) (xy 35.669659 -420.081826) (xy 35.58313 -420.089844) (xy 35.49623 -420.089844)
			(xy 35.409701 -420.081826) (xy 35.324281 -420.065858) (xy 35.240699 -420.042077) (xy 35.159667 -420.010685)
			(xy 35.081878 -419.971951) (xy 35.007994 -419.926204) (xy 34.938647 -419.873835) (xy 34.874427 -419.815291)
			(xy 34.815883 -419.751071) (xy 34.763514 -419.681724) (xy 34.717767 -419.60784) (xy 34.679033 -419.530051)
			(xy 34.647641 -419.449019) (xy 34.62386 -419.365437) (xy 34.607892 -419.280017) (xy 34.599874 -419.193488)
			(xy 31.399508 -419.193488) (xy 31.391675 -419.278813) (xy 31.37599 -419.363502) (xy 31.352625 -419.446401)
			(xy 31.321778 -419.526817) (xy 31.283706 -419.604074) (xy 31.238729 -419.677527) (xy 31.187222 -419.746558)
			(xy 31.129619 -419.810589) (xy 31.066401 -419.869085) (xy 30.998099 -419.921554) (xy 30.925285 -419.967558)
			(xy 30.848569 -420.006709) (xy 30.768594 -420.038681) (xy 30.68603 -420.063206) (xy 30.60157 -420.080077)
			(xy 30.515921 -420.089153) (xy 30.4298 -420.090359) (xy 30.34393 -420.083685) (xy 30.25903 -420.069185)
			(xy 30.175812 -420.046983) (xy 30.094974 -420.017263) (xy 30.017191 -419.980275) (xy 29.979874 -419.958774)
			(xy 29.960952 -419.94802) (xy 29.920317 -419.932437) (xy 29.877622 -419.924002) (xy 29.834115 -419.922961)
			(xy 29.791065 -419.929345) (xy 29.749732 -419.942966) (xy 29.711321 -419.963427) (xy 29.676957 -419.99013)
			(xy 29.647641 -420.022296) (xy 29.624232 -420.058984) (xy 29.607412 -420.099122) (xy 29.597673 -420.141539)
			(xy 29.59608 -420.163244) (xy 29.59608 -420.676832) (xy 29.597725 -420.698526) (xy 29.607484 -420.740921)
			(xy 29.624315 -420.781036) (xy 29.647727 -420.817702) (xy 29.677038 -420.849849) (xy 29.711393 -420.876539)
			(xy 29.749788 -420.896992) (xy 29.791104 -420.910614) (xy 29.834135 -420.917005) (xy 29.877627 -420.915979)
			(xy 29.920309 -420.907568) (xy 29.960937 -420.892015) (xy 29.979874 -420.881302) (xy 30.017157 -420.859744)
			(xy 30.094938 -420.822752) (xy 30.175775 -420.793029) (xy 30.258993 -420.770823) (xy 30.343892 -420.75632)
			(xy 30.429761 -420.749642) (xy 30.515882 -420.750844) (xy 30.601532 -420.759917) (xy 30.685993 -420.776785)
			(xy 30.768557 -420.801306) (xy 30.848534 -420.833275) (xy 30.925251 -420.872423) (xy 30.998067 -420.918424)
			(xy 31.066372 -420.97089) (xy 31.129592 -421.029383) (xy 31.187198 -421.093412) (xy 31.238707 -421.162441)
			(xy 31.283687 -421.235892) (xy 31.321763 -421.313148) (xy 31.352613 -421.393562) (xy 31.375981 -421.47646)
			(xy 31.391669 -421.561148) (xy 31.399548 -421.646916) (xy 31.399549 -421.733045) (xy 31.399508 -421.733488)
			(xy 34.599874 -421.733488) (xy 34.599874 -421.646588) (xy 34.607892 -421.560059) (xy 34.62386 -421.474639)
			(xy 34.647641 -421.391057) (xy 34.679033 -421.310025) (xy 34.717767 -421.232236) (xy 34.763514 -421.158352)
			(xy 34.815883 -421.089005) (xy 34.874427 -421.024785) (xy 34.938647 -420.966241) (xy 35.007994 -420.913872)
			(xy 35.081878 -420.868125) (xy 35.159667 -420.829391) (xy 35.240699 -420.797999) (xy 35.324281 -420.774218)
			(xy 35.409701 -420.75825) (xy 35.49623 -420.750232) (xy 35.58313 -420.750232) (xy 35.669659 -420.75825)
			(xy 35.755079 -420.774218) (xy 35.838661 -420.797999) (xy 35.919693 -420.829391) (xy 35.997482 -420.868125)
			(xy 36.071366 -420.913872) (xy 36.107296 -420.941005) (xy 39.875096 -420.941005) (xy 39.878983 -420.886653)
			(xy 39.890565 -420.833408) (xy 39.909607 -420.782353) (xy 39.935721 -420.734528) (xy 39.968376 -420.690906)
			(xy 40.006907 -420.652376) (xy 40.050528 -420.619721) (xy 40.098354 -420.593607) (xy 40.149408 -420.574565)
			(xy 40.202654 -420.562983) (xy 40.257005 -420.559096) (xy 40.311356 -420.562984) (xy 40.364601 -420.574568)
			(xy 40.415656 -420.593611) (xy 40.46348 -420.619727) (xy 40.485568 -420.635684) (xy 40.50458 -420.64928)
			(xy 40.546463 -420.670012) (xy 40.591431 -420.682738) (xy 40.637968 -420.687028) (xy 40.684505 -420.682738)
			(xy 40.729473 -420.670012) (xy 40.771356 -420.64928) (xy 40.790368 -420.635684) (xy 40.812464 -420.619732)
			(xy 40.860292 -420.593607) (xy 40.91135 -420.574556) (xy 40.964601 -420.562965) (xy 41.018959 -420.559071)
			(xy 41.073317 -420.562953) (xy 41.12657 -420.574532) (xy 41.177633 -420.593573) (xy 41.225466 -420.619687)
			(xy 41.269095 -420.652344) (xy 41.307632 -420.690877) (xy 41.340293 -420.734503) (xy 41.366412 -420.782334)
			(xy 41.385457 -420.833395) (xy 41.397042 -420.886646) (xy 41.400929 -420.941005) (xy 41.397041 -420.995363)
			(xy 41.385455 -421.048615) (xy 41.366408 -421.099675) (xy 41.340288 -421.147505) (xy 41.307626 -421.19113)
			(xy 41.269088 -421.229663) (xy 41.225458 -421.262318) (xy 41.177624 -421.288431) (xy 41.126561 -421.30747)
			(xy 41.073308 -421.319048) (xy 41.018949 -421.322929) (xy 40.964591 -421.319034) (xy 40.911341 -421.307442)
			(xy 40.860283 -421.288389) (xy 40.812456 -421.262263) (xy 40.790368 -421.2463) (xy 40.771356 -421.232704)
			(xy 40.729473 -421.211972) (xy 40.684505 -421.199246) (xy 40.637968 -421.194956) (xy 40.591431 -421.199246)
			(xy 40.546463 -421.211972) (xy 40.50458 -421.232704) (xy 40.485568 -421.2463) (xy 40.463488 -421.262268)
			(xy 40.415664 -421.288385) (xy 40.36461 -421.307429) (xy 40.311366 -421.319014) (xy 40.257015 -421.322904)
			(xy 40.202663 -421.319018) (xy 40.149418 -421.307438) (xy 40.098362 -421.288397) (xy 40.050537 -421.262284)
			(xy 40.006914 -421.22963) (xy 39.968382 -421.191101) (xy 39.935727 -421.14748) (xy 39.909611 -421.099655)
			(xy 39.890568 -421.048601) (xy 39.878984 -420.995356) (xy 39.875096 -420.941005) (xy 36.107296 -420.941005)
			(xy 36.140713 -420.966241) (xy 36.204933 -421.024785) (xy 36.263477 -421.089005) (xy 36.315846 -421.158352)
			(xy 36.361593 -421.232236) (xy 36.400327 -421.310025) (xy 36.431719 -421.391057) (xy 36.4555 -421.474639)
			(xy 36.471468 -421.560059) (xy 36.476705 -421.616581) (xy 65.293435 -421.616581) (xy 65.297325 -421.562236)
			(xy 65.308909 -421.508997) (xy 65.327952 -421.45795) (xy 65.354066 -421.410131) (xy 65.38672 -421.366516)
			(xy 65.425248 -421.327992) (xy 65.468866 -421.295344) (xy 65.516687 -421.269235) (xy 65.567737 -421.250198)
			(xy 65.620977 -421.238619) (xy 65.675322 -421.234735) (xy 65.729667 -421.238625) (xy 65.782906 -421.25021)
			(xy 65.833953 -421.269253) (xy 65.881771 -421.295368) (xy 65.903856 -421.311324) (xy 65.922868 -421.32492)
			(xy 65.964751 -421.345652) (xy 66.009719 -421.358378) (xy 66.056256 -421.362668) (xy 66.102793 -421.358378)
			(xy 66.147761 -421.345652) (xy 66.189644 -421.32492) (xy 66.208656 -421.311324) (xy 66.230715 -421.295317)
			(xy 66.278546 -421.269185) (xy 66.329608 -421.250127) (xy 66.382864 -421.23853) (xy 66.437228 -421.234631)
			(xy 66.491593 -421.23851) (xy 66.544853 -421.250086) (xy 66.595923 -421.269125) (xy 66.643763 -421.295239)
			(xy 66.6874 -421.327896) (xy 66.725944 -421.366431) (xy 66.758612 -421.41006) (xy 66.784737 -421.457894)
			(xy 66.803788 -421.508959) (xy 66.815377 -421.562216) (xy 66.819269 -421.616581) (xy 68.285028 -421.616581)
			(xy 68.288918 -421.562234) (xy 68.300503 -421.508994) (xy 68.319546 -421.457945) (xy 68.345661 -421.410125)
			(xy 68.378316 -421.366509) (xy 68.416846 -421.327985) (xy 68.460466 -421.295335) (xy 68.508289 -421.269226)
			(xy 68.55934 -421.250189) (xy 68.612582 -421.238611) (xy 68.666929 -421.234728) (xy 68.721276 -421.238619)
			(xy 68.774515 -421.250205) (xy 68.825564 -421.26925) (xy 68.873383 -421.295367) (xy 68.895468 -421.311324)
			(xy 68.91448 -421.32492) (xy 68.956363 -421.345652) (xy 69.001331 -421.358378) (xy 69.047868 -421.362668)
			(xy 69.094405 -421.358378) (xy 69.139373 -421.345652) (xy 69.181256 -421.32492) (xy 69.200268 -421.311324)
			(xy 69.222327 -421.295318) (xy 69.270157 -421.269188) (xy 69.321218 -421.250132) (xy 69.374472 -421.238536)
			(xy 69.428835 -421.234639) (xy 69.483198 -421.238518) (xy 69.536456 -421.250095) (xy 69.587524 -421.269134)
			(xy 69.635363 -421.295247) (xy 69.678998 -421.327904) (xy 69.717541 -421.366438) (xy 69.750207 -421.410066)
			(xy 69.776331 -421.457899) (xy 69.795381 -421.508963) (xy 69.80697 -421.562218) (xy 69.810861 -421.616581)
			(xy 69.806976 -421.670944) (xy 69.795392 -421.724201) (xy 69.776347 -421.775266) (xy 69.750228 -421.823102)
			(xy 69.717566 -421.866733) (xy 69.679027 -421.905271) (xy 69.635395 -421.937932) (xy 69.587559 -421.96405)
			(xy 69.536493 -421.983094) (xy 69.483236 -421.994677) (xy 69.428873 -421.998561) (xy 69.37451 -421.994669)
			(xy 69.321255 -421.983079) (xy 69.270191 -421.964028) (xy 69.222359 -421.937903) (xy 69.200268 -421.92194)
			(xy 69.181256 -421.908344) (xy 69.139373 -421.887612) (xy 69.094405 -421.874886) (xy 69.047868 -421.870596)
			(xy 69.001331 -421.874886) (xy 68.956363 -421.887612) (xy 68.91448 -421.908344) (xy 68.895468 -421.92194)
			(xy 68.873351 -421.937854) (xy 68.825529 -421.963966) (xy 68.774478 -421.983005) (xy 68.721238 -421.994586)
			(xy 68.666891 -421.998472) (xy 68.612544 -421.994583) (xy 68.559304 -421.983) (xy 68.508254 -421.963958)
			(xy 68.460434 -421.937844) (xy 68.416817 -421.90519) (xy 68.378291 -421.866662) (xy 68.345641 -421.823042)
			(xy 68.31953 -421.77522) (xy 68.300492 -421.724169) (xy 68.288913 -421.670928) (xy 68.285028 -421.616581)
			(xy 66.819269 -421.616581) (xy 66.815383 -421.670946) (xy 66.803799 -421.724204) (xy 66.784753 -421.775271)
			(xy 66.758632 -421.823108) (xy 66.725969 -421.86674) (xy 66.687429 -421.905279) (xy 66.643796 -421.93794)
			(xy 66.595958 -421.964059) (xy 66.54489 -421.983103) (xy 66.491631 -421.994685) (xy 66.437266 -421.998569)
			(xy 66.382902 -421.994675) (xy 66.329645 -421.983084) (xy 66.278581 -421.964031) (xy 66.230748 -421.937904)
			(xy 66.208656 -421.92194) (xy 66.189644 -421.908344) (xy 66.147761 -421.887612) (xy 66.102793 -421.874886)
			(xy 66.056256 -421.870596) (xy 66.009719 -421.874886) (xy 65.964751 -421.887612) (xy 65.922868 -421.908344)
			(xy 65.903856 -421.92194) (xy 65.881739 -421.937853) (xy 65.833918 -421.963963) (xy 65.782869 -421.983001)
			(xy 65.729629 -421.99458) (xy 65.675284 -421.998465) (xy 65.620939 -421.994575) (xy 65.5677 -421.982992)
			(xy 65.516652 -421.963949) (xy 65.468834 -421.937836) (xy 65.425219 -421.905182) (xy 65.386694 -421.866655)
			(xy 65.354045 -421.823036) (xy 65.327936 -421.775216) (xy 65.308898 -421.724166) (xy 65.29732 -421.670926)
			(xy 65.293435 -421.616581) (xy 36.476705 -421.616581) (xy 36.479486 -421.646588) (xy 36.479988 -421.690038)
			(xy 36.479486 -421.733488) (xy 36.471468 -421.820017) (xy 36.4555 -421.905437) (xy 36.431719 -421.989019)
			(xy 36.400327 -422.070051) (xy 36.361593 -422.14784) (xy 36.315846 -422.221724) (xy 36.263477 -422.291071)
			(xy 36.204933 -422.355291) (xy 36.140713 -422.413835) (xy 36.071366 -422.466204) (xy 35.997482 -422.511951)
			(xy 35.919693 -422.550685) (xy 35.838661 -422.582077) (xy 35.755079 -422.605858) (xy 35.669659 -422.621826)
			(xy 35.58313 -422.629844) (xy 35.49623 -422.629844) (xy 35.409701 -422.621826) (xy 35.324281 -422.605858)
			(xy 35.240699 -422.582077) (xy 35.159667 -422.550685) (xy 35.081878 -422.511951) (xy 35.007994 -422.466204)
			(xy 34.938647 -422.413835) (xy 34.874427 -422.355291) (xy 34.815883 -422.291071) (xy 34.763514 -422.221724)
			(xy 34.717767 -422.14784) (xy 34.679033 -422.070051) (xy 34.647641 -421.989019) (xy 34.62386 -421.905437)
			(xy 34.607892 -421.820017) (xy 34.599874 -421.733488) (xy 31.399508 -421.733488) (xy 31.391675 -421.818813)
			(xy 31.37599 -421.903502) (xy 31.352625 -421.986401) (xy 31.321778 -422.066817) (xy 31.283706 -422.144074)
			(xy 31.238729 -422.217527) (xy 31.187222 -422.286558) (xy 31.129619 -422.350589) (xy 31.066401 -422.409085)
			(xy 30.998099 -422.461554) (xy 30.925285 -422.507558) (xy 30.848569 -422.546709) (xy 30.768594 -422.578681)
			(xy 30.68603 -422.603206) (xy 30.60157 -422.620077) (xy 30.515921 -422.629153) (xy 30.4298 -422.630359)
			(xy 30.34393 -422.623685) (xy 30.25903 -422.609185) (xy 30.175812 -422.586983) (xy 30.094974 -422.557263)
			(xy 30.017191 -422.520275) (xy 29.979874 -422.498774) (xy 29.960952 -422.48802) (xy 29.920317 -422.472437)
			(xy 29.877622 -422.464002) (xy 29.834115 -422.462961) (xy 29.791065 -422.469345) (xy 29.749732 -422.482966)
			(xy 29.711321 -422.503427) (xy 29.676957 -422.53013) (xy 29.647641 -422.562296) (xy 29.624232 -422.598984)
			(xy 29.607412 -422.639122) (xy 29.597673 -422.681539) (xy 29.59608 -422.703244) (xy 29.59608 -423.216832)
			(xy 29.597725 -423.238526) (xy 29.607484 -423.280921) (xy 29.624315 -423.321036) (xy 29.647727 -423.357702)
			(xy 29.677038 -423.389849) (xy 29.711393 -423.416539) (xy 29.749788 -423.436992) (xy 29.791104 -423.450614)
			(xy 29.834135 -423.457005) (xy 29.877627 -423.455979) (xy 29.920309 -423.447568) (xy 29.960937 -423.432015)
			(xy 29.979874 -423.421302) (xy 30.017157 -423.399744) (xy 30.094938 -423.362752) (xy 30.175775 -423.333029)
			(xy 30.258993 -423.310823) (xy 30.343892 -423.29632) (xy 30.429761 -423.289642) (xy 30.515882 -423.290844)
			(xy 30.601532 -423.299917) (xy 30.685993 -423.316785) (xy 30.768557 -423.341306) (xy 30.848534 -423.373275)
			(xy 30.925251 -423.412423) (xy 30.998067 -423.458424) (xy 31.066372 -423.51089) (xy 31.129592 -423.569383)
			(xy 31.187198 -423.633412) (xy 31.238707 -423.702441) (xy 31.283687 -423.775892) (xy 31.321763 -423.853148)
			(xy 31.352613 -423.933562) (xy 31.375981 -424.01646) (xy 31.391669 -424.101148) (xy 31.399548 -424.186916)
			(xy 31.399549 -424.273045) (xy 31.399508 -424.273488) (xy 34.599874 -424.273488) (xy 34.599874 -424.186588)
			(xy 34.607892 -424.100059) (xy 34.62386 -424.014639) (xy 34.647641 -423.931057) (xy 34.679033 -423.850025)
			(xy 34.717767 -423.772236) (xy 34.763514 -423.698352) (xy 34.815883 -423.629005) (xy 34.874427 -423.564785)
			(xy 34.938647 -423.506241) (xy 35.007994 -423.453872) (xy 35.081878 -423.408125) (xy 35.159667 -423.369391)
			(xy 35.240699 -423.337999) (xy 35.324281 -423.314218) (xy 35.409701 -423.29825) (xy 35.49623 -423.290232)
			(xy 35.58313 -423.290232) (xy 35.669659 -423.29825) (xy 35.755079 -423.314218) (xy 35.838661 -423.337999)
			(xy 35.919693 -423.369391) (xy 35.997482 -423.408125) (xy 36.071366 -423.453872) (xy 36.140713 -423.506241)
			(xy 36.204933 -423.564785) (xy 36.247792 -423.611799) (xy 39.875104 -423.611799) (xy 39.878992 -423.557448)
			(xy 39.890575 -423.504205) (xy 39.909617 -423.453151) (xy 39.935731 -423.405328) (xy 39.968386 -423.361707)
			(xy 40.006916 -423.323178) (xy 40.050538 -423.290525) (xy 40.098362 -423.264412) (xy 40.149416 -423.245371)
			(xy 40.202661 -423.23379) (xy 40.257011 -423.229904) (xy 40.311361 -423.233793) (xy 40.364605 -423.245377)
			(xy 40.415658 -423.264421) (xy 40.463481 -423.290537) (xy 40.485568 -423.306494) (xy 40.50458 -423.32009)
			(xy 40.546463 -423.340822) (xy 40.591431 -423.353548) (xy 40.637968 -423.357838) (xy 40.684505 -423.353548)
			(xy 40.729473 -423.340822) (xy 40.771356 -423.32009) (xy 40.790368 -423.306494) (xy 40.812455 -423.290529)
			(xy 40.860283 -423.264403) (xy 40.911342 -423.24535) (xy 40.964594 -423.233758) (xy 41.018953 -423.229863)
			(xy 41.073313 -423.233744) (xy 41.126567 -423.245323) (xy 41.177631 -423.264363) (xy 41.225465 -423.290477)
			(xy 41.269096 -423.323134) (xy 41.307634 -423.361667) (xy 41.340296 -423.405294) (xy 41.366417 -423.453125)
			(xy 41.385463 -423.504187) (xy 41.397049 -423.557439) (xy 41.400937 -423.611799) (xy 41.397049 -423.666158)
			(xy 41.385464 -423.719411) (xy 41.370296 -423.760077) (xy 65.29344 -423.760077) (xy 65.29733 -423.705733)
			(xy 65.308915 -423.652495) (xy 65.327958 -423.601448) (xy 65.354072 -423.553631) (xy 65.386725 -423.510017)
			(xy 65.425254 -423.471494) (xy 65.468872 -423.438846) (xy 65.516692 -423.412738) (xy 65.567742 -423.393701)
			(xy 65.620981 -423.382123) (xy 65.675326 -423.37824) (xy 65.72967 -423.382131) (xy 65.782908 -423.393716)
			(xy 65.833954 -423.412759) (xy 65.881772 -423.438874) (xy 65.903856 -423.45483) (xy 65.922868 -423.468426)
			(xy 65.964751 -423.489158) (xy 66.009719 -423.501884) (xy 66.056256 -423.506174) (xy 66.102793 -423.501884)
			(xy 66.147761 -423.489158) (xy 66.189644 -423.468426) (xy 66.208656 -423.45483) (xy 66.23071 -423.438815)
			(xy 66.27854 -423.412682) (xy 66.329604 -423.393623) (xy 66.38286 -423.382026) (xy 66.437224 -423.378127)
			(xy 66.49159 -423.382005) (xy 66.544851 -423.393581) (xy 66.595922 -423.412619) (xy 66.643763 -423.438733)
			(xy 66.6874 -423.47139) (xy 66.725945 -423.509925) (xy 66.758614 -423.553554) (xy 66.78474 -423.601389)
			(xy 66.803792 -423.652455) (xy 66.815381 -423.705712) (xy 66.819273 -423.760077) (xy 68.285033 -423.760077)
			(xy 68.288923 -423.705731) (xy 68.300508 -423.652492) (xy 68.319552 -423.601444) (xy 68.345667 -423.553625)
			(xy 68.378322 -423.51001) (xy 68.416852 -423.471486) (xy 68.460472 -423.438837) (xy 68.508294 -423.412729)
			(xy 68.559345 -423.393693) (xy 68.612586 -423.382115) (xy 68.666933 -423.378233) (xy 68.721279 -423.382125)
			(xy 68.774517 -423.393711) (xy 68.825565 -423.412756) (xy 68.873383 -423.438873) (xy 68.895468 -423.45483)
			(xy 68.91448 -423.468426) (xy 68.956363 -423.489158) (xy 69.001331 -423.501884) (xy 69.047868 -423.506174)
			(xy 69.094405 -423.501884) (xy 69.139373 -423.489158) (xy 69.181256 -423.468426) (xy 69.200268 -423.45483)
			(xy 69.222321 -423.438816) (xy 69.270151 -423.412685) (xy 69.321213 -423.393628) (xy 69.374468 -423.382032)
			(xy 69.428831 -423.378134) (xy 69.483195 -423.382013) (xy 69.536454 -423.393589) (xy 69.587523 -423.412628)
			(xy 69.635363 -423.438741) (xy 69.678998 -423.471398) (xy 69.717542 -423.509932) (xy 69.750209 -423.55356)
			(xy 69.776334 -423.601393) (xy 69.795385 -423.652458) (xy 69.806974 -423.705714) (xy 69.810866 -423.760077)
			(xy 69.806981 -423.814441) (xy 69.795398 -423.867698) (xy 69.776353 -423.918765) (xy 69.750234 -423.966601)
			(xy 69.717572 -424.010233) (xy 69.679033 -424.048772) (xy 69.635401 -424.081434) (xy 69.587565 -424.107553)
			(xy 69.536498 -424.126598) (xy 69.48324 -424.138181) (xy 69.428877 -424.142066) (xy 69.374513 -424.138174)
			(xy 69.321257 -424.126585) (xy 69.270193 -424.107534) (xy 69.22236 -424.081409) (xy 69.200268 -424.065446)
			(xy 69.181256 -424.05185) (xy 69.139373 -424.031118) (xy 69.094405 -424.018392) (xy 69.047868 -424.014102)
			(xy 69.001331 -424.018392) (xy 68.956363 -424.031118) (xy 68.91448 -424.05185) (xy 68.895468 -424.065446)
			(xy 68.873345 -424.081352) (xy 68.825524 -424.107463) (xy 68.774474 -424.126502) (xy 68.721233 -424.138082)
			(xy 68.666887 -424.141967) (xy 68.612541 -424.138078) (xy 68.559302 -424.126494) (xy 68.508253 -424.107452)
			(xy 68.460433 -424.081338) (xy 68.416817 -424.048684) (xy 68.378292 -424.010156) (xy 68.345643 -423.966537)
			(xy 68.319533 -423.918715) (xy 68.300495 -423.867664) (xy 68.288917 -423.814424) (xy 68.285033 -423.760077)
			(xy 66.819273 -423.760077) (xy 66.815388 -423.814443) (xy 66.803804 -423.867702) (xy 66.784759 -423.91877)
			(xy 66.758638 -423.966607) (xy 66.725975 -424.01024) (xy 66.687435 -424.04878) (xy 66.643801 -424.081442)
			(xy 66.595963 -424.107562) (xy 66.544895 -424.126607) (xy 66.491635 -424.138189) (xy 66.43727 -424.142073)
			(xy 66.382905 -424.13818) (xy 66.329647 -424.126589) (xy 66.278582 -424.107537) (xy 66.230748 -424.08141)
			(xy 66.208656 -424.065446) (xy 66.189644 -424.05185) (xy 66.147761 -424.031118) (xy 66.102793 -424.018392)
			(xy 66.056256 -424.014102) (xy 66.009719 -424.018392) (xy 65.964751 -424.031118) (xy 65.922868 -424.05185)
			(xy 65.903856 -424.065446) (xy 65.881733 -424.081351) (xy 65.833913 -424.10746) (xy 65.782864 -424.126497)
			(xy 65.729625 -424.138076) (xy 65.67528 -424.14196) (xy 65.620936 -424.13807) (xy 65.567698 -424.126486)
			(xy 65.516651 -424.107443) (xy 65.468833 -424.08133) (xy 65.425219 -424.048676) (xy 65.386696 -424.010149)
			(xy 65.354047 -423.966531) (xy 65.327939 -423.91871) (xy 65.308902 -423.867661) (xy 65.297324 -423.814422)
			(xy 65.29344 -423.760077) (xy 41.370296 -423.760077) (xy 41.366418 -423.770473) (xy 41.340298 -423.818304)
			(xy 41.307636 -423.861931) (xy 41.269098 -423.900465) (xy 41.225467 -423.933121) (xy 41.177633 -423.959236)
			(xy 41.126569 -423.978276) (xy 41.073315 -423.989856) (xy 41.018955 -423.993737) (xy 40.964596 -423.989843)
			(xy 40.911345 -423.978251) (xy 40.860285 -423.959198) (xy 40.812457 -423.933073) (xy 40.790368 -423.91711)
			(xy 40.771356 -423.903514) (xy 40.729473 -423.882782) (xy 40.684505 -423.870056) (xy 40.637968 -423.865766)
			(xy 40.591431 -423.870056) (xy 40.546463 -423.882782) (xy 40.50458 -423.903514) (xy 40.485568 -423.91711)
			(xy 40.463479 -423.933065) (xy 40.415656 -423.95918) (xy 40.364602 -423.978223) (xy 40.311359 -423.989807)
			(xy 40.257009 -423.993696) (xy 40.202658 -423.98981) (xy 40.149414 -423.978228) (xy 40.09836 -423.959187)
			(xy 40.050536 -423.933074) (xy 40.006915 -423.90042) (xy 39.968385 -423.861891) (xy 39.93573 -423.81827)
			(xy 39.909616 -423.770447) (xy 39.890574 -423.719393) (xy 39.878991 -423.666149) (xy 39.875104 -423.611799)
			(xy 36.247792 -423.611799) (xy 36.263477 -423.629005) (xy 36.315846 -423.698352) (xy 36.361593 -423.772236)
			(xy 36.400327 -423.850025) (xy 36.431719 -423.931057) (xy 36.4555 -424.014639) (xy 36.471468 -424.100059)
			(xy 36.479486 -424.186588) (xy 36.479988 -424.230038) (xy 36.479486 -424.273488) (xy 36.471468 -424.360017)
			(xy 36.4555 -424.445437) (xy 36.431719 -424.529019) (xy 36.400327 -424.610051) (xy 36.361593 -424.68784)
			(xy 36.315846 -424.761724) (xy 36.263477 -424.831071) (xy 36.204933 -424.895291) (xy 36.140713 -424.953835)
			(xy 36.071366 -425.006204) (xy 35.997482 -425.051951) (xy 35.919693 -425.090685) (xy 35.838661 -425.122077)
			(xy 35.755079 -425.145858) (xy 35.669659 -425.161826) (xy 35.58313 -425.169844) (xy 35.49623 -425.169844)
			(xy 35.409701 -425.161826) (xy 35.324281 -425.145858) (xy 35.240699 -425.122077) (xy 35.159667 -425.090685)
			(xy 35.081878 -425.051951) (xy 35.007994 -425.006204) (xy 34.938647 -424.953835) (xy 34.874427 -424.895291)
			(xy 34.815883 -424.831071) (xy 34.763514 -424.761724) (xy 34.717767 -424.68784) (xy 34.679033 -424.610051)
			(xy 34.647641 -424.529019) (xy 34.62386 -424.445437) (xy 34.607892 -424.360017) (xy 34.599874 -424.273488)
			(xy 31.399508 -424.273488) (xy 31.391675 -424.358813) (xy 31.37599 -424.443502) (xy 31.352625 -424.526401)
			(xy 31.321778 -424.606817) (xy 31.283706 -424.684074) (xy 31.238729 -424.757527) (xy 31.187222 -424.826558)
			(xy 31.129619 -424.890589) (xy 31.066401 -424.949085) (xy 30.998099 -425.001554) (xy 30.925285 -425.047558)
			(xy 30.848569 -425.086709) (xy 30.768594 -425.118681) (xy 30.68603 -425.143206) (xy 30.60157 -425.160077)
			(xy 30.515921 -425.169153) (xy 30.4298 -425.170359) (xy 30.34393 -425.163685) (xy 30.25903 -425.149185)
			(xy 30.175812 -425.126983) (xy 30.094974 -425.097263) (xy 30.017191 -425.060275) (xy 29.979874 -425.038774)
			(xy 29.960952 -425.02802) (xy 29.920317 -425.012437) (xy 29.877622 -425.004002) (xy 29.834115 -425.002961)
			(xy 29.791065 -425.009345) (xy 29.749732 -425.022966) (xy 29.711321 -425.043427) (xy 29.676957 -425.07013)
			(xy 29.647641 -425.102296) (xy 29.624232 -425.138984) (xy 29.607412 -425.179122) (xy 29.597673 -425.221539)
			(xy 29.59608 -425.243244) (xy 29.59608 -425.756832) (xy 29.597725 -425.778526) (xy 29.607484 -425.820921)
			(xy 29.624315 -425.861036) (xy 29.647727 -425.897702) (xy 29.677038 -425.929849) (xy 29.711393 -425.956539)
			(xy 29.749788 -425.976992) (xy 29.791104 -425.990614) (xy 29.834135 -425.997005) (xy 29.877627 -425.995979)
			(xy 29.920309 -425.987568) (xy 29.960937 -425.972015) (xy 29.979874 -425.961302) (xy 30.017157 -425.939744)
			(xy 30.094938 -425.902752) (xy 30.175775 -425.873029) (xy 30.258993 -425.850823) (xy 30.343892 -425.83632)
			(xy 30.429761 -425.829642) (xy 30.515882 -425.830844) (xy 30.601532 -425.839917) (xy 30.685993 -425.856785)
			(xy 30.768557 -425.881306) (xy 30.848534 -425.913275) (xy 30.925251 -425.952423) (xy 30.998067 -425.998424)
			(xy 31.066372 -426.05089) (xy 31.129592 -426.109383) (xy 31.187198 -426.173412) (xy 31.238707 -426.242441)
			(xy 31.283687 -426.315892) (xy 31.321763 -426.393148) (xy 31.352613 -426.473562) (xy 31.375981 -426.55646)
			(xy 31.391669 -426.641148) (xy 31.399548 -426.726916) (xy 31.399549 -426.813045) (xy 31.399508 -426.813488)
			(xy 34.599874 -426.813488) (xy 34.599874 -426.726588) (xy 34.607892 -426.640059) (xy 34.62386 -426.554639)
			(xy 34.647641 -426.471057) (xy 34.679033 -426.390025) (xy 34.717767 -426.312236) (xy 34.763514 -426.238352)
			(xy 34.815883 -426.169005) (xy 34.874427 -426.104785) (xy 34.938647 -426.046241) (xy 35.007994 -425.993872)
			(xy 35.081878 -425.948125) (xy 35.159667 -425.909391) (xy 35.240699 -425.877999) (xy 35.324281 -425.854218)
			(xy 35.409701 -425.83825) (xy 35.49623 -425.830232) (xy 35.58313 -425.830232) (xy 35.669659 -425.83825)
			(xy 35.755079 -425.854218) (xy 35.756376 -425.854587) (xy 63.554518 -425.854587) (xy 63.558407 -425.800238)
			(xy 63.569991 -425.746997) (xy 63.589035 -425.695945) (xy 63.61515 -425.648124) (xy 63.647805 -425.604506)
			(xy 63.686335 -425.56598) (xy 63.729957 -425.533329) (xy 63.77778 -425.507219) (xy 63.828834 -425.48818)
			(xy 63.882076 -425.476601) (xy 63.936425 -425.472718) (xy 63.990774 -425.476609) (xy 64.044015 -425.488195)
			(xy 64.095066 -425.50724) (xy 64.142886 -425.533356) (xy 64.164972 -425.549314) (xy 64.183984 -425.56291)
			(xy 64.225867 -425.583642) (xy 64.270835 -425.596368) (xy 64.317372 -425.600658) (xy 64.363909 -425.596368)
			(xy 64.408877 -425.583642) (xy 64.45076 -425.56291) (xy 64.469772 -425.549314) (xy 64.49184 -425.533322)
			(xy 64.539669 -425.507194) (xy 64.590729 -425.488139) (xy 64.643982 -425.476546) (xy 64.698343 -425.472649)
			(xy 64.752705 -425.476529) (xy 64.805961 -425.488107) (xy 64.857027 -425.507146) (xy 64.904864 -425.53326)
			(xy 64.948497 -425.565916) (xy 64.987038 -425.60445) (xy 65.019702 -425.648077) (xy 65.045824 -425.695909)
			(xy 65.064873 -425.746972) (xy 65.076461 -425.800226) (xy 65.080351 -425.854587) (xy 66.358909 -425.854587)
			(xy 66.362799 -425.800236) (xy 66.374383 -425.746993) (xy 66.393428 -425.69594) (xy 66.419544 -425.648117)
			(xy 66.452201 -425.604498) (xy 66.490733 -425.565971) (xy 66.534356 -425.533319) (xy 66.582182 -425.507209)
			(xy 66.633237 -425.48817) (xy 66.686482 -425.476592) (xy 66.740833 -425.472709) (xy 66.795183 -425.476602)
			(xy 66.848426 -425.488189) (xy 66.899478 -425.507236) (xy 66.9473 -425.533355) (xy 66.969386 -425.549314)
			(xy 66.988398 -425.56291) (xy 67.030281 -425.583642) (xy 67.075249 -425.596368) (xy 67.121786 -425.600658)
			(xy 67.168323 -425.596368) (xy 67.213291 -425.583642) (xy 67.255174 -425.56291) (xy 67.274186 -425.549314)
			(xy 67.296254 -425.533323) (xy 67.344082 -425.507197) (xy 67.395141 -425.488145) (xy 67.448392 -425.476553)
			(xy 67.502751 -425.472657) (xy 67.557111 -425.476539) (xy 67.610365 -425.488117) (xy 67.661429 -425.507156)
			(xy 67.709263 -425.53327) (xy 67.752894 -425.565926) (xy 67.791434 -425.604458) (xy 67.824096 -425.648084)
			(xy 67.850218 -425.695914) (xy 67.869266 -425.746975) (xy 67.880853 -425.800228) (xy 67.884743 -425.854587)
			(xy 67.880856 -425.908946) (xy 67.869273 -425.962199) (xy 67.850229 -426.013262) (xy 67.824111 -426.061094)
			(xy 67.791451 -426.104722) (xy 67.752914 -426.143257) (xy 67.709286 -426.175916) (xy 67.661453 -426.202033)
			(xy 67.61039 -426.221076) (xy 67.557137 -426.232658) (xy 67.502777 -426.236543) (xy 67.448418 -426.232651)
			(xy 67.395166 -426.221063) (xy 67.344106 -426.202014) (xy 67.296276 -426.175891) (xy 67.274186 -426.15993)
			(xy 67.255174 -426.146334) (xy 67.213291 -426.125602) (xy 67.168323 -426.112876) (xy 67.121786 -426.108586)
			(xy 67.075249 -426.112876) (xy 67.030281 -426.125602) (xy 66.988398 -426.146334) (xy 66.969386 -426.15993)
			(xy 66.947278 -426.175859) (xy 66.899454 -426.201975) (xy 66.848401 -426.221018) (xy 66.795157 -426.232602)
			(xy 66.740807 -426.236491) (xy 66.686456 -426.232604) (xy 66.633212 -426.221022) (xy 66.582158 -426.20198)
			(xy 66.534334 -426.175867) (xy 66.490713 -426.143212) (xy 66.452184 -426.104682) (xy 66.41953 -426.061061)
			(xy 66.393417 -426.013236) (xy 66.374376 -425.962182) (xy 66.362795 -425.908937) (xy 66.358909 -425.854587)
			(xy 65.080351 -425.854587) (xy 65.076465 -425.908948) (xy 65.064881 -425.962203) (xy 65.045835 -426.013267)
			(xy 65.019716 -426.061101) (xy 64.987055 -426.10473) (xy 64.948517 -426.143266) (xy 64.904886 -426.175926)
			(xy 64.857051 -426.202043) (xy 64.805986 -426.221086) (xy 64.752731 -426.232667) (xy 64.698369 -426.236551)
			(xy 64.644008 -426.232658) (xy 64.590755 -426.221068) (xy 64.539693 -426.202017) (xy 64.491862 -426.175892)
			(xy 64.469772 -426.15993) (xy 64.45076 -426.146334) (xy 64.408877 -426.125602) (xy 64.363909 -426.112876)
			(xy 64.317372 -426.108586) (xy 64.270835 -426.112876) (xy 64.225867 -426.125602) (xy 64.183984 -426.146334)
			(xy 64.164972 -426.15993) (xy 64.142864 -426.175858) (xy 64.095042 -426.201971) (xy 64.04399 -426.221013)
			(xy 63.990748 -426.232595) (xy 63.936399 -426.236482) (xy 63.88205 -426.232595) (xy 63.828808 -426.221012)
			(xy 63.777756 -426.20197) (xy 63.729934 -426.175857) (xy 63.686315 -426.143203) (xy 63.647788 -426.104674)
			(xy 63.615136 -426.061054) (xy 63.589024 -426.013231) (xy 63.569984 -425.962178) (xy 63.558403 -425.908936)
			(xy 63.554518 -425.854587) (xy 35.756376 -425.854587) (xy 35.838661 -425.877999) (xy 35.919693 -425.909391)
			(xy 35.997482 -425.948125) (xy 36.071366 -425.993872) (xy 36.140713 -426.046241) (xy 36.204933 -426.104785)
			(xy 36.263477 -426.169005) (xy 36.315846 -426.238352) (xy 36.341706 -426.280117) (xy 39.87508 -426.280117)
			(xy 39.878965 -426.225763) (xy 39.890546 -426.172515) (xy 39.909588 -426.121458) (xy 39.935702 -426.07363)
			(xy 39.968356 -426.030005) (xy 40.006887 -425.991472) (xy 40.05051 -425.958814) (xy 40.098336 -425.932698)
			(xy 40.149392 -425.913653) (xy 40.202639 -425.902069) (xy 40.256993 -425.89818) (xy 40.311347 -425.902067)
			(xy 40.364594 -425.913649) (xy 40.415651 -425.932692) (xy 40.463479 -425.958807) (xy 40.485568 -425.974764)
			(xy 40.50458 -425.98836) (xy 40.546463 -426.009092) (xy 40.591431 -426.021818) (xy 40.637968 -426.026108)
			(xy 40.684505 -426.021818) (xy 40.729473 -426.009092) (xy 40.771356 -425.98836) (xy 40.790368 -425.974764)
			(xy 40.812483 -425.958839) (xy 40.860309 -425.932717) (xy 40.911366 -425.913668) (xy 40.964615 -425.902079)
			(xy 41.018971 -425.898187) (xy 41.073327 -425.90207) (xy 41.126577 -425.913651) (xy 41.177637 -425.932692)
			(xy 41.225467 -425.958807) (xy 41.269094 -425.991464) (xy 41.307628 -426.029997) (xy 41.340286 -426.073622)
			(xy 41.366402 -426.121451) (xy 41.385445 -426.172511) (xy 41.397028 -426.225761) (xy 41.400913 -426.280117)
			(xy 41.397023 -426.334473) (xy 41.385436 -426.387722) (xy 41.366388 -426.438779) (xy 41.340268 -426.486606)
			(xy 41.307606 -426.530229) (xy 41.269068 -426.568758) (xy 41.225439 -426.601411) (xy 41.177607 -426.627521)
			(xy 41.126545 -426.646559) (xy 41.073294 -426.658134) (xy 41.018937 -426.662013) (xy 40.964582 -426.658116)
			(xy 40.911334 -426.646523) (xy 40.860279 -426.627469) (xy 40.812455 -426.601343) (xy 40.790368 -426.58538)
			(xy 40.771356 -426.571784) (xy 40.729473 -426.551052) (xy 40.684505 -426.538326) (xy 40.637968 -426.534036)
			(xy 40.591431 -426.538326) (xy 40.546463 -426.551052) (xy 40.50458 -426.571784) (xy 40.485568 -426.58538)
			(xy 40.463507 -426.601375) (xy 40.415682 -426.627494) (xy 40.364627 -426.646541) (xy 40.31138 -426.658128)
			(xy 40.257027 -426.66202) (xy 40.202673 -426.658136) (xy 40.149425 -426.646556) (xy 40.098367 -426.627516)
			(xy 40.050538 -426.601404) (xy 40.006913 -426.56875) (xy 39.968378 -426.53022) (xy 39.93572 -426.486599)
			(xy 39.909602 -426.438773) (xy 39.890556 -426.387717) (xy 39.87897 -426.33447) (xy 39.87508 -426.280117)
			(xy 36.341706 -426.280117) (xy 36.361593 -426.312236) (xy 36.400327 -426.390025) (xy 36.431719 -426.471057)
			(xy 36.4555 -426.554639) (xy 36.471468 -426.640059) (xy 36.479486 -426.726588) (xy 36.479988 -426.770038)
			(xy 36.479486 -426.813488) (xy 36.471468 -426.900017) (xy 36.4555 -426.985437) (xy 36.431719 -427.069019)
			(xy 36.400327 -427.150051) (xy 36.361593 -427.22784) (xy 36.315846 -427.301724) (xy 36.263477 -427.371071)
			(xy 36.204933 -427.435291) (xy 36.140713 -427.493835) (xy 36.071366 -427.546204) (xy 35.997482 -427.591951)
			(xy 35.919693 -427.630685) (xy 35.838661 -427.662077) (xy 35.755079 -427.685858) (xy 35.669659 -427.701826)
			(xy 35.58313 -427.709844) (xy 35.49623 -427.709844) (xy 35.409701 -427.701826) (xy 35.324281 -427.685858)
			(xy 35.240699 -427.662077) (xy 35.159667 -427.630685) (xy 35.081878 -427.591951) (xy 35.007994 -427.546204)
			(xy 34.938647 -427.493835) (xy 34.874427 -427.435291) (xy 34.815883 -427.371071) (xy 34.763514 -427.301724)
			(xy 34.717767 -427.22784) (xy 34.679033 -427.150051) (xy 34.647641 -427.069019) (xy 34.62386 -426.985437)
			(xy 34.607892 -426.900017) (xy 34.599874 -426.813488) (xy 31.399508 -426.813488) (xy 31.391675 -426.898813)
			(xy 31.37599 -426.983502) (xy 31.352625 -427.066401) (xy 31.321778 -427.146817) (xy 31.283706 -427.224074)
			(xy 31.238729 -427.297527) (xy 31.187222 -427.366558) (xy 31.129619 -427.430589) (xy 31.066401 -427.489085)
			(xy 30.998099 -427.541554) (xy 30.925285 -427.587558) (xy 30.848569 -427.626709) (xy 30.768594 -427.658681)
			(xy 30.68603 -427.683206) (xy 30.60157 -427.700077) (xy 30.515921 -427.709153) (xy 30.4298 -427.710359)
			(xy 30.34393 -427.703685) (xy 30.25903 -427.689185) (xy 30.175812 -427.666983) (xy 30.094974 -427.637263)
			(xy 30.017191 -427.600275) (xy 29.979874 -427.578774) (xy 29.960952 -427.56802) (xy 29.920317 -427.552437)
			(xy 29.877622 -427.544002) (xy 29.834115 -427.542961) (xy 29.791065 -427.549345) (xy 29.749732 -427.562966)
			(xy 29.711321 -427.583427) (xy 29.676957 -427.61013) (xy 29.647641 -427.642296) (xy 29.624232 -427.678984)
			(xy 29.607412 -427.719122) (xy 29.597673 -427.761539) (xy 29.59608 -427.783244) (xy 29.59608 -428.296832)
			(xy 29.597725 -428.318526) (xy 29.607484 -428.360921) (xy 29.624315 -428.401036) (xy 29.647727 -428.437702)
			(xy 29.677038 -428.469849) (xy 29.711393 -428.496539) (xy 29.749788 -428.516992) (xy 29.791104 -428.530614)
			(xy 29.834135 -428.537005) (xy 29.877627 -428.535979) (xy 29.920309 -428.527568) (xy 29.960937 -428.512015)
			(xy 29.979874 -428.501302) (xy 30.017157 -428.479744) (xy 30.094938 -428.442752) (xy 30.175775 -428.413029)
			(xy 30.258993 -428.390823) (xy 30.343892 -428.37632) (xy 30.429761 -428.369642) (xy 30.515882 -428.370844)
			(xy 30.601532 -428.379917) (xy 30.685993 -428.396785) (xy 30.768557 -428.421306) (xy 30.848534 -428.453275)
			(xy 30.925251 -428.492423) (xy 30.998067 -428.538424) (xy 31.066372 -428.59089) (xy 31.129592 -428.649383)
			(xy 31.187198 -428.713412) (xy 31.238707 -428.782441) (xy 31.283687 -428.855892) (xy 31.321763 -428.933148)
			(xy 31.352613 -429.013562) (xy 31.375981 -429.09646) (xy 31.391669 -429.181148) (xy 31.399548 -429.266916)
			(xy 31.399549 -429.353045) (xy 31.399508 -429.353488) (xy 34.599874 -429.353488) (xy 34.599874 -429.266588)
			(xy 34.607892 -429.180059) (xy 34.62386 -429.094639) (xy 34.647641 -429.011057) (xy 34.679033 -428.930025)
			(xy 34.717767 -428.852236) (xy 34.763514 -428.778352) (xy 34.815883 -428.709005) (xy 34.874427 -428.644785)
			(xy 34.938647 -428.586241) (xy 35.007994 -428.533872) (xy 35.081878 -428.488125) (xy 35.159667 -428.449391)
			(xy 35.240699 -428.417999) (xy 35.324281 -428.394218) (xy 35.409701 -428.37825) (xy 35.49623 -428.370232)
			(xy 35.58313 -428.370232) (xy 35.669659 -428.37825) (xy 35.755079 -428.394218) (xy 35.838661 -428.417999)
			(xy 35.919693 -428.449391) (xy 35.997482 -428.488125) (xy 36.071366 -428.533872) (xy 36.140713 -428.586241)
			(xy 36.204933 -428.644785) (xy 36.211253 -428.651718) (xy 39.875079 -428.651718) (xy 39.878964 -428.597364)
			(xy 39.890545 -428.544116) (xy 39.909586 -428.493058) (xy 39.9357 -428.44523) (xy 39.968354 -428.401605)
			(xy 40.006885 -428.363071) (xy 40.050508 -428.330414) (xy 40.098334 -428.304297) (xy 40.149391 -428.285252)
			(xy 40.202638 -428.273667) (xy 40.256992 -428.269779) (xy 40.311346 -428.273665) (xy 40.364594 -428.285247)
			(xy 40.415651 -428.30429) (xy 40.463478 -428.330405) (xy 40.485568 -428.346362) (xy 40.50458 -428.359958)
			(xy 40.546463 -428.38069) (xy 40.591431 -428.393416) (xy 40.637968 -428.397706) (xy 40.684505 -428.393416)
			(xy 40.729473 -428.38069) (xy 40.771356 -428.359958) (xy 40.790368 -428.346362) (xy 40.812485 -428.33044)
			(xy 40.860311 -428.304318) (xy 40.911368 -428.285269) (xy 40.964616 -428.27368) (xy 41.018972 -428.269788)
			(xy 41.073328 -428.273672) (xy 41.126578 -428.285253) (xy 41.177638 -428.304294) (xy 41.225467 -428.330409)
			(xy 41.269094 -428.363066) (xy 41.307628 -428.401599) (xy 41.340285 -428.445224) (xy 41.366401 -428.493053)
			(xy 41.378458 -428.525381) (xy 63.554526 -428.525381) (xy 63.558416 -428.471034) (xy 63.57 -428.417793)
			(xy 63.589044 -428.366743) (xy 63.61516 -428.318923) (xy 63.647815 -428.275307) (xy 63.686345 -428.236782)
			(xy 63.729966 -428.204132) (xy 63.777789 -428.178023) (xy 63.828842 -428.158986) (xy 63.882084 -428.147409)
			(xy 63.936431 -428.143526) (xy 63.990778 -428.147417) (xy 64.044019 -428.159004) (xy 64.095068 -428.178049)
			(xy 64.142887 -428.204166) (xy 64.164972 -428.220124) (xy 64.183984 -428.23372) (xy 64.225867 -428.254452)
			(xy 64.270835 -428.267178) (xy 64.317372 -428.271468) (xy 64.363909 -428.267178) (xy 64.408877 -428.254452)
			(xy 64.45076 -428.23372) (xy 64.469772 -428.220124) (xy 64.491831 -428.204119) (xy 64.53966 -428.177989)
			(xy 64.590721 -428.158933) (xy 64.643975 -428.147338) (xy 64.698337 -428.143441) (xy 64.7527 -428.14732)
			(xy 64.805957 -428.158898) (xy 64.857025 -428.177937) (xy 64.904863 -428.20405) (xy 64.948497 -428.236706)
			(xy 64.98704 -428.27524) (xy 65.019705 -428.318868) (xy 65.045829 -428.3667) (xy 65.064879 -428.417764)
			(xy 65.076468 -428.471019) (xy 65.080359 -428.525381) (xy 66.358917 -428.525381) (xy 66.362807 -428.471032)
			(xy 66.374393 -428.417789) (xy 66.393438 -428.366738) (xy 66.419554 -428.318916) (xy 66.452211 -428.275299)
			(xy 66.490743 -428.236773) (xy 66.534366 -428.204123) (xy 66.582191 -428.178013) (xy 66.633245 -428.158976)
			(xy 66.68649 -428.147399) (xy 66.740839 -428.143517) (xy 66.795188 -428.14741) (xy 66.84843 -428.158999)
			(xy 66.89948 -428.178046) (xy 66.9473 -428.204165) (xy 66.969386 -428.220124) (xy 66.988398 -428.23372)
			(xy 67.030281 -428.254452) (xy 67.075249 -428.267178) (xy 67.121786 -428.271468) (xy 67.168323 -428.267178)
			(xy 67.213291 -428.254452) (xy 67.255174 -428.23372) (xy 67.274186 -428.220124) (xy 67.296244 -428.20412)
			(xy 67.344073 -428.177993) (xy 67.395133 -428.158939) (xy 67.448385 -428.147346) (xy 67.502745 -428.143449)
			(xy 67.557106 -428.14733) (xy 67.610361 -428.158907) (xy 67.661427 -428.177947) (xy 67.709263 -428.20406)
			(xy 67.752895 -428.236716) (xy 67.791436 -428.275249) (xy 67.8241 -428.318875) (xy 67.850222 -428.366706)
			(xy 67.869272 -428.417767) (xy 67.88086 -428.471021) (xy 67.884751 -428.525381) (xy 67.880865 -428.579741)
			(xy 67.869282 -428.632996) (xy 67.850238 -428.684059) (xy 67.824121 -428.731893) (xy 67.791461 -428.775522)
			(xy 67.752924 -428.814059) (xy 67.709295 -428.846719) (xy 67.661462 -428.872837) (xy 67.610398 -428.891882)
			(xy 67.557144 -428.903465) (xy 67.502783 -428.907351) (xy 67.448423 -428.90346) (xy 67.39517 -428.891872)
			(xy 67.344108 -428.872823) (xy 67.296277 -428.846701) (xy 67.274186 -428.83074) (xy 67.255174 -428.817144)
			(xy 67.213291 -428.796412) (xy 67.168323 -428.783686) (xy 67.121786 -428.779396) (xy 67.075249 -428.783686)
			(xy 67.030281 -428.796412) (xy 66.988398 -428.817144) (xy 66.969386 -428.83074) (xy 66.947268 -428.846656)
			(xy 66.899446 -428.87277) (xy 66.848393 -428.891812) (xy 66.79515 -428.903395) (xy 66.740801 -428.907283)
			(xy 66.686452 -428.903395) (xy 66.633209 -428.891813) (xy 66.582156 -428.872771) (xy 66.534333 -428.846657)
			(xy 66.490714 -428.814002) (xy 66.452186 -428.775472) (xy 66.419534 -428.731851) (xy 66.393422 -428.684027)
			(xy 66.374382 -428.632974) (xy 66.362802 -428.57973) (xy 66.358917 -428.525381) (xy 65.080359 -428.525381)
			(xy 65.076473 -428.579743) (xy 65.06489 -428.633) (xy 65.045845 -428.684065) (xy 65.019726 -428.7319)
			(xy 64.987065 -428.77553) (xy 64.948526 -428.814068) (xy 64.904895 -428.846729) (xy 64.85706 -428.872847)
			(xy 64.805994 -428.891892) (xy 64.752738 -428.903474) (xy 64.698375 -428.907359) (xy 64.644013 -428.903467)
			(xy 64.590758 -428.891878) (xy 64.539695 -428.872827) (xy 64.491863 -428.846702) (xy 64.469772 -428.83074)
			(xy 64.45076 -428.817144) (xy 64.408877 -428.796412) (xy 64.363909 -428.783686) (xy 64.317372 -428.779396)
			(xy 64.270835 -428.783686) (xy 64.225867 -428.796412) (xy 64.183984 -428.817144) (xy 64.164972 -428.83074)
			(xy 64.142854 -428.846654) (xy 64.095033 -428.872766) (xy 64.043982 -428.891807) (xy 63.99074 -428.903388)
			(xy 63.936393 -428.907274) (xy 63.882046 -428.903386) (xy 63.828805 -428.891803) (xy 63.777754 -428.872761)
			(xy 63.729934 -428.846647) (xy 63.686316 -428.813993) (xy 63.64779 -428.775464) (xy 63.615139 -428.731844)
			(xy 63.589028 -428.684022) (xy 63.56999 -428.63297) (xy 63.55841 -428.579728) (xy 63.554526 -428.525381)
			(xy 41.378458 -428.525381) (xy 41.385444 -428.544112) (xy 41.397026 -428.597362) (xy 41.400912 -428.651718)
			(xy 41.397021 -428.706074) (xy 41.385434 -428.759322) (xy 41.366386 -428.81038) (xy 41.340266 -428.858206)
			(xy 41.307604 -428.901828) (xy 41.269066 -428.940358) (xy 41.225437 -428.97301) (xy 41.177605 -428.999121)
			(xy 41.126543 -429.018157) (xy 41.073292 -429.029733) (xy 41.018936 -429.033612) (xy 40.964581 -429.029715)
			(xy 40.911333 -429.018121) (xy 40.860278 -428.999067) (xy 40.812455 -428.972941) (xy 40.790368 -428.956978)
			(xy 40.771356 -428.943382) (xy 40.729473 -428.92265) (xy 40.684505 -428.909924) (xy 40.637968 -428.905634)
			(xy 40.591431 -428.909924) (xy 40.546463 -428.92265) (xy 40.50458 -428.943382) (xy 40.485568 -428.956978)
			(xy 40.463509 -428.972976) (xy 40.415684 -428.999095) (xy 40.364628 -429.018143) (xy 40.311382 -429.02973)
			(xy 40.257028 -429.033621) (xy 40.202674 -429.029738) (xy 40.149425 -429.018158) (xy 40.098367 -428.999118)
			(xy 40.050538 -428.973006) (xy 40.006912 -428.940352) (xy 39.968378 -428.901822) (xy 39.935719 -428.8582)
			(xy 39.909601 -428.810375) (xy 39.890555 -428.759319) (xy 39.878969 -428.706072) (xy 39.875079 -428.651718)
			(xy 36.211253 -428.651718) (xy 36.263477 -428.709005) (xy 36.315846 -428.778352) (xy 36.361593 -428.852236)
			(xy 36.400327 -428.930025) (xy 36.431719 -429.011057) (xy 36.4555 -429.094639) (xy 36.471468 -429.180059)
			(xy 36.479486 -429.266588) (xy 36.479988 -429.310038) (xy 36.479486 -429.353488) (xy 36.471468 -429.440017)
			(xy 36.4555 -429.525437) (xy 36.431719 -429.609019) (xy 36.400327 -429.690051) (xy 36.361593 -429.76784)
			(xy 36.315846 -429.841724) (xy 36.263477 -429.911071) (xy 36.204933 -429.975291) (xy 36.140713 -430.033835)
			(xy 36.071366 -430.086204) (xy 35.997482 -430.131951) (xy 35.961712 -430.149762) (xy 72.868035 -430.149762)
			(xy 72.872042 -429.947012) (xy 72.884055 -429.744578) (xy 72.904056 -429.542777) (xy 72.932015 -429.341923)
			(xy 72.967886 -429.142331) (xy 73.011615 -428.944312) (xy 73.063133 -428.748175) (xy 73.122359 -428.554227)
			(xy 73.189201 -428.362769) (xy 73.263555 -428.174102) (xy 73.345304 -427.98852) (xy 73.434322 -427.806312)
			(xy 73.530468 -427.627763) (xy 73.633593 -427.453152) (xy 73.743536 -427.282752) (xy 73.860125 -427.116828)
			(xy 73.983178 -426.955639) (xy 74.112503 -426.799438) (xy 74.247898 -426.648468) (xy 74.389151 -426.502964)
			(xy 74.536043 -426.363155) (xy 74.688343 -426.229258) (xy 74.845814 -426.101483) (xy 75.008211 -425.980028)
			(xy 75.175278 -425.865084) (xy 75.346757 -425.75683) (xy 75.522378 -425.655435) (xy 75.701868 -425.561057)
			(xy 75.884946 -425.473845) (xy 76.071327 -425.393933) (xy 76.26072 -425.321446) (xy 76.452828 -425.256499)
			(xy 76.647352 -425.199191) (xy 76.843988 -425.149614) (xy 77.04243 -425.107843) (xy 77.242367 -425.073945)
			(xy 77.443486 -425.047973) (xy 77.645475 -425.029966) (xy 77.848018 -425.019953) (xy 78.050798 -425.017949)
			(xy 78.253499 -425.023959) (xy 78.455804 -425.037971) (xy 78.657398 -425.059966) (xy 78.857965 -425.089907)
			(xy 79.057193 -425.127748) (xy 79.254771 -425.173431) (xy 79.450389 -425.226884) (xy 79.643743 -425.288023)
			(xy 79.834531 -425.356754) (xy 80.022454 -425.432968) (xy 80.20722 -425.516547) (xy 80.388539 -425.60736)
			(xy 80.56613 -425.705265) (xy 80.739713 -425.81011) (xy 80.909019 -425.921731) (xy 81.073784 -426.039953)
			(xy 81.233749 -426.164593) (xy 81.388665 -426.295454) (xy 81.53829 -426.432334) (xy 81.68239 -426.575018)
			(xy 81.820742 -426.723284) (xy 81.953127 -426.8769) (xy 82.079341 -427.035625) (xy 82.199185 -427.199214)
			(xy 82.312473 -427.367409) (xy 82.419028 -427.539948) (xy 82.518683 -427.716563) (xy 82.611283 -427.896976)
			(xy 82.696683 -428.080907) (xy 82.77475 -428.268068) (xy 82.845362 -428.458168) (xy 82.908408 -428.650908)
			(xy 82.963791 -428.845989) (xy 83.011423 -429.043106) (xy 83.051231 -429.24195) (xy 83.083153 -429.442212)
			(xy 83.107137 -429.643578) (xy 83.123148 -429.845735) (xy 83.131159 -430.048367) (xy 83.13166 -430.149762)
			(xy 83.131159 -430.251157) (xy 83.123148 -430.453789) (xy 83.107137 -430.655946) (xy 83.083153 -430.857312)
			(xy 83.051231 -431.057574) (xy 83.011423 -431.256418) (xy 82.963791 -431.453535) (xy 82.908408 -431.648616)
			(xy 82.845362 -431.841356) (xy 82.77475 -432.031456) (xy 82.696683 -432.218617) (xy 82.611283 -432.402548)
			(xy 82.518683 -432.582961) (xy 82.419028 -432.759576) (xy 82.312473 -432.932115) (xy 82.199185 -433.10031)
			(xy 82.079341 -433.263899) (xy 81.953127 -433.422624) (xy 81.820742 -433.57624) (xy 81.68239 -433.724506)
			(xy 81.53829 -433.86719) (xy 81.388665 -434.00407) (xy 81.233749 -434.134931) (xy 81.073784 -434.259571)
			(xy 80.909019 -434.377793) (xy 80.739713 -434.489414) (xy 80.56613 -434.594259) (xy 80.388539 -434.692164)
			(xy 80.20722 -434.782977) (xy 80.022454 -434.866556) (xy 79.834531 -434.94277) (xy 79.643743 -435.011501)
			(xy 79.450389 -435.07264) (xy 79.254771 -435.126093) (xy 79.057193 -435.171776) (xy 78.857965 -435.209617)
			(xy 78.657398 -435.239558) (xy 78.455804 -435.261553) (xy 78.253499 -435.275565) (xy 78.050798 -435.281575)
			(xy 77.848018 -435.279571) (xy 77.645475 -435.269558) (xy 77.443486 -435.251551) (xy 77.242367 -435.225579)
			(xy 77.04243 -435.191681) (xy 76.843988 -435.14991) (xy 76.647352 -435.100333) (xy 76.452828 -435.043025)
			(xy 76.26072 -434.978078) (xy 76.071327 -434.905591) (xy 75.884946 -434.825679) (xy 75.701868 -434.738467)
			(xy 75.522378 -434.644089) (xy 75.346757 -434.542694) (xy 75.175278 -434.43444) (xy 75.008211 -434.319496)
			(xy 74.845814 -434.198041) (xy 74.688343 -434.070266) (xy 74.536043 -433.936369) (xy 74.389151 -433.79656)
			(xy 74.247898 -433.651056) (xy 74.112503 -433.500086) (xy 73.983178 -433.343885) (xy 73.860125 -433.182696)
			(xy 73.743536 -433.016772) (xy 73.633593 -432.846372) (xy 73.530468 -432.671761) (xy 73.434322 -432.493212)
			(xy 73.345304 -432.311004) (xy 73.263555 -432.125422) (xy 73.189201 -431.936755) (xy 73.122359 -431.745297)
			(xy 73.063133 -431.551349) (xy 73.011615 -431.355212) (xy 72.967886 -431.157193) (xy 72.932015 -430.957601)
			(xy 72.904056 -430.756747) (xy 72.884055 -430.554946) (xy 72.872042 -430.352512) (xy 72.868035 -430.149762)
			(xy 35.961712 -430.149762) (xy 35.919693 -430.170685) (xy 35.838661 -430.202077) (xy 35.755079 -430.225858)
			(xy 35.669659 -430.241826) (xy 35.58313 -430.249844) (xy 35.49623 -430.249844) (xy 35.409701 -430.241826)
			(xy 35.324281 -430.225858) (xy 35.240699 -430.202077) (xy 35.159667 -430.170685) (xy 35.081878 -430.131951)
			(xy 35.007994 -430.086204) (xy 34.938647 -430.033835) (xy 34.874427 -429.975291) (xy 34.815883 -429.911071)
			(xy 34.763514 -429.841724) (xy 34.717767 -429.76784) (xy 34.679033 -429.690051) (xy 34.647641 -429.609019)
			(xy 34.62386 -429.525437) (xy 34.607892 -429.440017) (xy 34.599874 -429.353488) (xy 31.399508 -429.353488)
			(xy 31.391675 -429.438813) (xy 31.37599 -429.523502) (xy 31.352625 -429.606401) (xy 31.321778 -429.686817)
			(xy 31.283706 -429.764074) (xy 31.238729 -429.837527) (xy 31.187222 -429.906558) (xy 31.129619 -429.970589)
			(xy 31.066401 -430.029085) (xy 30.998099 -430.081554) (xy 30.925285 -430.127558) (xy 30.848569 -430.166709)
			(xy 30.768594 -430.198681) (xy 30.68603 -430.223206) (xy 30.60157 -430.240077) (xy 30.515921 -430.249153)
			(xy 30.4298 -430.250359) (xy 30.34393 -430.243685) (xy 30.25903 -430.229185) (xy 30.175812 -430.206983)
			(xy 30.094974 -430.177263) (xy 30.017191 -430.140275) (xy 29.979874 -430.118774) (xy 29.960952 -430.10802)
			(xy 29.920317 -430.092437) (xy 29.877622 -430.084002) (xy 29.834115 -430.082961) (xy 29.791065 -430.089345)
			(xy 29.749732 -430.102966) (xy 29.711321 -430.123427) (xy 29.676957 -430.15013) (xy 29.647641 -430.182296)
			(xy 29.624232 -430.218984) (xy 29.607412 -430.259122) (xy 29.597673 -430.301539) (xy 29.59608 -430.323244)
			(xy 29.59608 -430.614611) (xy 39.875088 -430.614611) (xy 39.878974 -430.560258) (xy 39.890556 -430.507012)
			(xy 39.909597 -430.455956) (xy 39.935711 -430.408129) (xy 39.968366 -430.364506) (xy 40.006897 -430.325974)
			(xy 40.050519 -430.293318) (xy 40.098345 -430.267202) (xy 40.1494 -430.248159) (xy 40.202646 -430.236576)
			(xy 40.256999 -430.232688) (xy 40.311352 -430.236576) (xy 40.364598 -430.248159) (xy 40.415653 -430.267202)
			(xy 40.463479 -430.293317) (xy 40.485568 -430.309274) (xy 40.50458 -430.32287) (xy 40.546463 -430.343602)
			(xy 40.591431 -430.356328) (xy 40.637968 -430.360618) (xy 40.684505 -430.356328) (xy 40.729473 -430.343602)
			(xy 40.771356 -430.32287) (xy 40.790368 -430.309274) (xy 40.812474 -430.293336) (xy 40.8603 -430.267212)
			(xy 40.911358 -430.248162) (xy 40.964608 -430.236572) (xy 41.018965 -430.232679) (xy 41.073322 -430.236562)
			(xy 41.126574 -430.248142) (xy 41.177635 -430.267183) (xy 41.225467 -430.293297) (xy 41.269094 -430.325954)
			(xy 41.30763 -430.364487) (xy 41.340289 -430.408113) (xy 41.366407 -430.455943) (xy 41.385451 -430.507003)
			(xy 41.397035 -430.560253) (xy 41.400921 -430.614611) (xy 41.397032 -430.668968) (xy 41.385445 -430.722218)
			(xy 41.366398 -430.773277) (xy 41.340278 -430.821105) (xy 41.307616 -430.864729) (xy 41.269078 -430.90326)
			(xy 41.225448 -430.935914) (xy 41.177615 -430.962026) (xy 41.126553 -430.981064) (xy 41.073301 -430.992641)
			(xy 41.018943 -430.996521) (xy 40.964586 -430.992625) (xy 40.911338 -430.981032) (xy 40.860281 -430.961979)
			(xy 40.812456 -430.935853) (xy 40.790368 -430.91989) (xy 40.771356 -430.906294) (xy 40.729473 -430.885562)
			(xy 40.684505 -430.872836) (xy 40.637968 -430.868546) (xy 40.591431 -430.872836) (xy 40.546463 -430.885562)
			(xy 40.50458 -430.906294) (xy 40.485568 -430.91989) (xy 40.463497 -430.935872) (xy 40.415673 -430.961989)
			(xy 40.364618 -430.981035) (xy 40.311373 -430.992621) (xy 40.257021 -430.996512) (xy 40.202668 -430.992627)
			(xy 40.149421 -430.981047) (xy 40.098364 -430.962007) (xy 40.050537 -430.935894) (xy 40.006913 -430.90324)
			(xy 39.96838 -430.864711) (xy 39.935723 -430.821089) (xy 39.909606 -430.773264) (xy 39.890562 -430.722209)
			(xy 39.878977 -430.668963) (xy 39.875088 -430.614611) (xy 29.59608 -430.614611) (xy 29.59608 -430.836832)
			(xy 29.597725 -430.858526) (xy 29.607484 -430.900921) (xy 29.624315 -430.941036) (xy 29.647727 -430.977702)
			(xy 29.677038 -431.009849) (xy 29.711393 -431.036539) (xy 29.749788 -431.056992) (xy 29.791104 -431.070614)
			(xy 29.834135 -431.077005) (xy 29.877627 -431.075979) (xy 29.920309 -431.067568) (xy 29.960937 -431.052015)
			(xy 29.979874 -431.041302) (xy 30.017157 -431.019744) (xy 30.094938 -430.982752) (xy 30.175775 -430.953029)
			(xy 30.258993 -430.930823) (xy 30.343892 -430.91632) (xy 30.429761 -430.909642) (xy 30.515882 -430.910844)
			(xy 30.601532 -430.919917) (xy 30.685993 -430.936785) (xy 30.768557 -430.961306) (xy 30.848534 -430.993275)
			(xy 30.925251 -431.032423) (xy 30.998067 -431.078424) (xy 31.066372 -431.13089) (xy 31.129592 -431.189383)
			(xy 31.187198 -431.253412) (xy 31.238707 -431.322441) (xy 31.283687 -431.395892) (xy 31.321763 -431.473148)
			(xy 31.352613 -431.553562) (xy 31.375981 -431.63646) (xy 31.391669 -431.721148) (xy 31.399548 -431.806916)
			(xy 31.399549 -431.893045) (xy 31.399508 -431.893488) (xy 34.599874 -431.893488) (xy 34.599874 -431.806588)
			(xy 34.607892 -431.720059) (xy 34.62386 -431.634639) (xy 34.647641 -431.551057) (xy 34.679033 -431.470025)
			(xy 34.717767 -431.392236) (xy 34.763514 -431.318352) (xy 34.815883 -431.249005) (xy 34.874427 -431.184785)
			(xy 34.938647 -431.126241) (xy 35.007994 -431.073872) (xy 35.081878 -431.028125) (xy 35.159667 -430.989391)
			(xy 35.240699 -430.957999) (xy 35.324281 -430.934218) (xy 35.409701 -430.91825) (xy 35.49623 -430.910232)
			(xy 35.58313 -430.910232) (xy 35.669659 -430.91825) (xy 35.755079 -430.934218) (xy 35.838661 -430.957999)
			(xy 35.919693 -430.989391) (xy 35.997482 -431.028125) (xy 36.071366 -431.073872) (xy 36.140713 -431.126241)
			(xy 36.204933 -431.184785) (xy 36.213059 -431.193699) (xy 63.554502 -431.193699) (xy 63.558389 -431.139348)
			(xy 63.569972 -431.086104) (xy 63.589015 -431.03505) (xy 63.61513 -430.987226) (xy 63.647785 -430.943605)
			(xy 63.686316 -430.905076) (xy 63.729938 -430.872422) (xy 63.777763 -430.846309) (xy 63.828818 -430.827268)
			(xy 63.882062 -430.815687) (xy 63.936413 -430.811802) (xy 63.990764 -430.815691) (xy 64.044008 -430.827276)
			(xy 64.095061 -430.84632) (xy 64.142885 -430.872436) (xy 64.164972 -430.888394) (xy 64.183984 -430.90199)
			(xy 64.225867 -430.922722) (xy 64.270835 -430.935448) (xy 64.317372 -430.939738) (xy 64.363909 -430.935448)
			(xy 64.408877 -430.922722) (xy 64.45076 -430.90199) (xy 64.469772 -430.888394) (xy 64.491859 -430.872429)
			(xy 64.539687 -430.846304) (xy 64.590745 -430.827251) (xy 64.643996 -430.81566) (xy 64.698355 -430.811765)
			(xy 64.752714 -430.815647) (xy 64.805968 -430.827226) (xy 64.857031 -430.846266) (xy 64.904865 -430.87238)
			(xy 64.948495 -430.905036) (xy 64.987033 -430.94357) (xy 65.019695 -430.987196) (xy 65.045815 -431.035027)
			(xy 65.064861 -431.086088) (xy 65.076447 -431.13934) (xy 65.080335 -431.193699) (xy 66.358893 -431.193699)
			(xy 66.362781 -431.139346) (xy 66.374365 -431.0861) (xy 66.393408 -431.035044) (xy 66.419524 -430.987219)
			(xy 66.452181 -430.943597) (xy 66.490714 -430.905066) (xy 66.534338 -430.872412) (xy 66.582165 -430.846299)
			(xy 66.633221 -430.827258) (xy 66.686468 -430.815678) (xy 66.740821 -430.811793) (xy 66.795174 -430.815684)
			(xy 66.848419 -430.82727) (xy 66.899474 -430.846317) (xy 66.947298 -430.872435) (xy 66.969386 -430.888394)
			(xy 66.988398 -430.90199) (xy 67.030281 -430.922722) (xy 67.075249 -430.935448) (xy 67.121786 -430.939738)
			(xy 67.168323 -430.935448) (xy 67.213291 -430.922722) (xy 67.255174 -430.90199) (xy 67.274186 -430.888394)
			(xy 67.296273 -430.87243) (xy 67.344099 -430.846307) (xy 67.395157 -430.827257) (xy 67.448406 -430.815667)
			(xy 67.502763 -430.811773) (xy 67.55712 -430.815656) (xy 67.610372 -430.827236) (xy 67.661433 -430.846276)
			(xy 67.709265 -430.87239) (xy 67.752893 -430.905046) (xy 67.791429 -430.943578) (xy 67.824089 -430.987203)
			(xy 67.850208 -431.035032) (xy 67.869254 -431.086091) (xy 67.880838 -431.139342) (xy 67.884727 -431.193699)
			(xy 67.880839 -431.248056) (xy 67.869254 -431.301306) (xy 67.850209 -431.352366) (xy 67.824091 -431.400195)
			(xy 67.791431 -431.44382) (xy 67.752895 -431.482353) (xy 67.709267 -431.515009) (xy 67.661435 -431.541123)
			(xy 67.610374 -431.560164) (xy 67.557123 -431.571744) (xy 67.502765 -431.575627) (xy 67.448408 -431.571734)
			(xy 67.395159 -431.560144) (xy 67.344101 -431.541094) (xy 67.296275 -431.514971) (xy 67.274186 -431.49901)
			(xy 67.255174 -431.485414) (xy 67.213291 -431.464682) (xy 67.168323 -431.451956) (xy 67.121786 -431.447666)
			(xy 67.075249 -431.451956) (xy 67.030281 -431.464682) (xy 66.988398 -431.485414) (xy 66.969386 -431.49901)
			(xy 66.947296 -431.514966) (xy 66.899472 -431.541084) (xy 66.848417 -431.56013) (xy 66.795171 -431.571716)
			(xy 66.740819 -431.575607) (xy 66.686466 -431.571722) (xy 66.633219 -431.560141) (xy 66.582162 -431.5411)
			(xy 66.534335 -431.514986) (xy 66.490712 -431.482332) (xy 66.452179 -431.443802) (xy 66.419523 -431.400179)
			(xy 66.393407 -431.352354) (xy 66.374364 -431.301298) (xy 66.362781 -431.248052) (xy 66.358893 -431.193699)
			(xy 65.080335 -431.193699) (xy 65.076447 -431.248058) (xy 65.064862 -431.30131) (xy 65.045816 -431.352371)
			(xy 65.019696 -431.400202) (xy 64.987035 -431.443828) (xy 64.948497 -431.482362) (xy 64.904867 -431.515019)
			(xy 64.857033 -431.541133) (xy 64.80597 -431.560174) (xy 64.752717 -431.571753) (xy 64.698357 -431.575635)
			(xy 64.643999 -431.571741) (xy 64.590748 -431.56015) (xy 64.539689 -431.541097) (xy 64.491861 -431.514972)
			(xy 64.469772 -431.49901) (xy 64.45076 -431.485414) (xy 64.408877 -431.464682) (xy 64.363909 -431.451956)
			(xy 64.317372 -431.447666) (xy 64.270835 -431.451956) (xy 64.225867 -431.464682) (xy 64.183984 -431.485414)
			(xy 64.164972 -431.49901) (xy 64.142883 -431.514965) (xy 64.095059 -431.541081) (xy 64.044006 -431.560125)
			(xy 63.990762 -431.571709) (xy 63.936411 -431.575598) (xy 63.88206 -431.571712) (xy 63.828815 -431.560131)
			(xy 63.777761 -431.54109) (xy 63.729936 -431.514977) (xy 63.686314 -431.482323) (xy 63.647783 -431.443793)
			(xy 63.615129 -431.400172) (xy 63.589014 -431.352348) (xy 63.569972 -431.301294) (xy 63.558389 -431.24805)
			(xy 63.554502 -431.193699) (xy 36.213059 -431.193699) (xy 36.263477 -431.249005) (xy 36.315846 -431.318352)
			(xy 36.361593 -431.392236) (xy 36.400327 -431.470025) (xy 36.431719 -431.551057) (xy 36.4555 -431.634639)
			(xy 36.471468 -431.720059) (xy 36.479486 -431.806588) (xy 36.479988 -431.850038) (xy 36.479486 -431.893488)
			(xy 36.471468 -431.980017) (xy 36.4555 -432.065437) (xy 36.431719 -432.149019) (xy 36.400327 -432.230051)
			(xy 36.361593 -432.30784) (xy 36.315846 -432.381724) (xy 36.263477 -432.451071) (xy 36.204933 -432.515291)
			(xy 36.140713 -432.573835) (xy 36.071366 -432.626204) (xy 35.997482 -432.671951) (xy 35.919693 -432.710685)
			(xy 35.838661 -432.742077) (xy 35.782321 -432.758107) (xy 39.875093 -432.758107) (xy 39.878979 -432.703755)
			(xy 39.890561 -432.65051) (xy 39.909603 -432.599454) (xy 39.935717 -432.551629) (xy 39.968372 -432.508006)
			(xy 40.006903 -432.469475) (xy 40.050525 -432.43682) (xy 40.09835 -432.410705) (xy 40.149405 -432.391663)
			(xy 40.202651 -432.38008) (xy 40.257003 -432.376193) (xy 40.311355 -432.380081) (xy 40.3646 -432.391664)
			(xy 40.415655 -432.410707) (xy 40.46348 -432.436823) (xy 40.485568 -432.45278) (xy 40.50458 -432.466376)
			(xy 40.546463 -432.487108) (xy 40.591431 -432.499834) (xy 40.637968 -432.504124) (xy 40.684505 -432.499834)
			(xy 40.729473 -432.487108) (xy 40.771356 -432.466376) (xy 40.790368 -432.45278) (xy 40.812468 -432.436834)
			(xy 40.860295 -432.410709) (xy 40.911353 -432.391658) (xy 40.964603 -432.380068) (xy 41.018961 -432.376174)
			(xy 41.073319 -432.380056) (xy 41.126572 -432.391636) (xy 41.177634 -432.410677) (xy 41.225466 -432.436791)
			(xy 41.269095 -432.469448) (xy 41.307631 -432.507981) (xy 41.340291 -432.551607) (xy 41.36641 -432.599437)
			(xy 41.385455 -432.650498) (xy 41.397039 -432.703749) (xy 41.400926 -432.758107) (xy 41.397037 -432.812465)
			(xy 41.385451 -432.865716) (xy 41.366404 -432.916776) (xy 41.340284 -432.964605) (xy 41.307622 -433.00823)
			(xy 41.269084 -433.046762) (xy 41.225454 -433.079416) (xy 41.177621 -433.105529) (xy 41.126558 -433.124568)
			(xy 41.073305 -433.136146) (xy 41.018947 -433.140026) (xy 40.964589 -433.13613) (xy 40.91134 -433.124538)
			(xy 40.860282 -433.105485) (xy 40.812456 -433.079359) (xy 40.790368 -433.063396) (xy 40.771356 -433.0498)
			(xy 40.729473 -433.029068) (xy 40.684505 -433.016342) (xy 40.637968 -433.012052) (xy 40.591431 -433.016342)
			(xy 40.546463 -433.029068) (xy 40.50458 -433.0498) (xy 40.485568 -433.063396) (xy 40.463492 -433.079369)
			(xy 40.415668 -433.105487) (xy 40.364614 -433.124532) (xy 40.311369 -433.136117) (xy 40.257017 -433.140007)
			(xy 40.202665 -433.136122) (xy 40.149419 -433.124541) (xy 40.098363 -433.105501) (xy 40.050537 -433.079388)
			(xy 40.006914 -433.046734) (xy 39.968382 -433.008205) (xy 39.935725 -432.964584) (xy 39.909609 -432.916759)
			(xy 39.890565 -432.865704) (xy 39.878981 -432.812459) (xy 39.875093 -432.758107) (xy 35.782321 -432.758107)
			(xy 35.755079 -432.765858) (xy 35.669659 -432.781826) (xy 35.58313 -432.789844) (xy 35.49623 -432.789844)
			(xy 35.409701 -432.781826) (xy 35.324281 -432.765858) (xy 35.240699 -432.742077) (xy 35.159667 -432.710685)
			(xy 35.081878 -432.671951) (xy 35.007994 -432.626204) (xy 34.938647 -432.573835) (xy 34.874427 -432.515291)
			(xy 34.815883 -432.451071) (xy 34.763514 -432.381724) (xy 34.717767 -432.30784) (xy 34.679033 -432.230051)
			(xy 34.647641 -432.149019) (xy 34.62386 -432.065437) (xy 34.607892 -431.980017) (xy 34.599874 -431.893488)
			(xy 31.399508 -431.893488) (xy 31.391675 -431.978813) (xy 31.37599 -432.063502) (xy 31.352625 -432.146401)
			(xy 31.321778 -432.226817) (xy 31.283706 -432.304074) (xy 31.238729 -432.377527) (xy 31.187222 -432.446558)
			(xy 31.129619 -432.510589) (xy 31.066401 -432.569085) (xy 30.998099 -432.621554) (xy 30.925285 -432.667558)
			(xy 30.848569 -432.706709) (xy 30.768594 -432.738681) (xy 30.68603 -432.763206) (xy 30.60157 -432.780077)
			(xy 30.515921 -432.789153) (xy 30.4298 -432.790359) (xy 30.34393 -432.783685) (xy 30.25903 -432.769185)
			(xy 30.175812 -432.746983) (xy 30.094974 -432.717263) (xy 30.017191 -432.680275) (xy 29.979874 -432.658774)
			(xy 29.960952 -432.64802) (xy 29.920317 -432.632437) (xy 29.877622 -432.624002) (xy 29.834115 -432.622961)
			(xy 29.791065 -432.629345) (xy 29.749732 -432.642966) (xy 29.711321 -432.663427) (xy 29.676957 -432.69013)
			(xy 29.647641 -432.722296) (xy 29.624232 -432.758984) (xy 29.607412 -432.799122) (xy 29.597673 -432.841539)
			(xy 29.59608 -432.863244) (xy 29.59608 -433.376832) (xy 29.597725 -433.398526) (xy 29.607484 -433.440921)
			(xy 29.624315 -433.481036) (xy 29.647727 -433.517702) (xy 29.677038 -433.549849) (xy 29.711393 -433.576539)
			(xy 29.749788 -433.596992) (xy 29.791104 -433.610614) (xy 29.834135 -433.617005) (xy 29.877627 -433.615979)
			(xy 29.920309 -433.607568) (xy 29.960937 -433.592015) (xy 29.979874 -433.581302) (xy 30.017157 -433.559744)
			(xy 30.094938 -433.522752) (xy 30.175775 -433.493029) (xy 30.258993 -433.470823) (xy 30.343892 -433.45632)
			(xy 30.429761 -433.449642) (xy 30.515882 -433.450844) (xy 30.601532 -433.459917) (xy 30.685993 -433.476785)
			(xy 30.768557 -433.501306) (xy 30.848534 -433.533275) (xy 30.925251 -433.572423) (xy 30.998067 -433.618424)
			(xy 31.066372 -433.67089) (xy 31.129592 -433.729383) (xy 31.187198 -433.793412) (xy 31.238707 -433.862441)
			(xy 31.283687 -433.935892) (xy 31.321763 -434.013148) (xy 31.352613 -434.093562) (xy 31.375981 -434.17646)
			(xy 31.391669 -434.261148) (xy 31.399548 -434.346916) (xy 31.399549 -434.433045) (xy 31.399508 -434.433488)
			(xy 34.599874 -434.433488) (xy 34.599874 -434.346588) (xy 34.607892 -434.260059) (xy 34.62386 -434.174639)
			(xy 34.647641 -434.091057) (xy 34.679033 -434.010025) (xy 34.717767 -433.932236) (xy 34.763514 -433.858352)
			(xy 34.815883 -433.789005) (xy 34.874427 -433.724785) (xy 34.938647 -433.666241) (xy 35.007994 -433.613872)
			(xy 35.081878 -433.568125) (xy 35.159667 -433.529391) (xy 35.240699 -433.497999) (xy 35.324281 -433.474218)
			(xy 35.409701 -433.45825) (xy 35.49623 -433.450232) (xy 35.58313 -433.450232) (xy 35.669659 -433.45825)
			(xy 35.755079 -433.474218) (xy 35.838661 -433.497999) (xy 35.919693 -433.529391) (xy 35.991809 -433.5653)
			(xy 63.5545 -433.5653) (xy 63.558388 -433.510949) (xy 63.569971 -433.457704) (xy 63.589013 -433.40665)
			(xy 63.615128 -433.358826) (xy 63.647783 -433.315205) (xy 63.686314 -433.276675) (xy 63.729936 -433.244021)
			(xy 63.777761 -433.217908) (xy 63.828816 -433.198867) (xy 63.882061 -433.187286) (xy 63.936412 -433.1834)
			(xy 63.990763 -433.187289) (xy 64.044007 -433.198874) (xy 64.095061 -433.217918) (xy 64.142884 -433.244034)
			(xy 64.164972 -433.259992) (xy 64.183984 -433.273588) (xy 64.225867 -433.29432) (xy 64.270835 -433.307046)
			(xy 64.317372 -433.311336) (xy 64.363909 -433.307046) (xy 64.408877 -433.29432) (xy 64.45076 -433.273588)
			(xy 64.469772 -433.259992) (xy 64.491861 -433.24403) (xy 64.539688 -433.217904) (xy 64.590747 -433.198852)
			(xy 64.643998 -433.187261) (xy 64.698356 -433.183367) (xy 64.752715 -433.187249) (xy 64.805969 -433.198828)
			(xy 64.857032 -433.217868) (xy 64.904865 -433.243982) (xy 64.948495 -433.276638) (xy 64.987033 -433.315172)
			(xy 65.019694 -433.358798) (xy 65.045814 -433.406628) (xy 65.06486 -433.457689) (xy 65.076445 -433.510941)
			(xy 65.080333 -433.5653) (xy 66.358892 -433.5653) (xy 66.362779 -433.510947) (xy 66.374363 -433.457701)
			(xy 66.393406 -433.406645) (xy 66.419522 -433.358819) (xy 66.452179 -433.315196) (xy 66.490712 -433.276666)
			(xy 66.534336 -433.244012) (xy 66.582163 -433.217898) (xy 66.63322 -433.198857) (xy 66.686467 -433.187277)
			(xy 66.74082 -433.183392) (xy 66.795173 -433.187282) (xy 66.848419 -433.198869) (xy 66.899474 -433.217915)
			(xy 66.947298 -433.244033) (xy 66.969386 -433.259992) (xy 66.988398 -433.273588) (xy 67.030281 -433.29432)
			(xy 67.075249 -433.307046) (xy 67.121786 -433.311336) (xy 67.168323 -433.307046) (xy 67.213291 -433.29432)
			(xy 67.255174 -433.273588) (xy 67.274186 -433.259992) (xy 67.296274 -433.244031) (xy 67.344101 -433.217908)
			(xy 67.395158 -433.198858) (xy 67.448408 -433.187268) (xy 67.502764 -433.183375) (xy 67.557121 -433.187258)
			(xy 67.610372 -433.198837) (xy 67.661434 -433.217878) (xy 67.709265 -433.243992) (xy 67.752893 -433.276648)
			(xy 67.791429 -433.31518) (xy 67.824089 -433.358805) (xy 67.850207 -433.406634) (xy 67.869252 -433.457693)
			(xy 67.880837 -433.510943) (xy 67.884725 -433.5653) (xy 67.880837 -433.619657) (xy 67.869252 -433.672907)
			(xy 67.850207 -433.723966) (xy 67.824089 -433.771795) (xy 67.791429 -433.81542) (xy 67.752893 -433.853952)
			(xy 67.709265 -433.886608) (xy 67.661434 -433.912722) (xy 67.610372 -433.931763) (xy 67.557121 -433.943342)
			(xy 67.502764 -433.947225) (xy 67.448408 -433.943332) (xy 67.395158 -433.931742) (xy 67.344101 -433.912692)
			(xy 67.296274 -433.886569) (xy 67.274186 -433.870608) (xy 67.255174 -433.857012) (xy 67.213291 -433.83628)
			(xy 67.168323 -433.823554) (xy 67.121786 -433.819264) (xy 67.075249 -433.823554) (xy 67.030281 -433.83628)
			(xy 66.988398 -433.857012) (xy 66.969386 -433.870608) (xy 66.947298 -433.886567) (xy 66.899474 -433.912685)
			(xy 66.848419 -433.931731) (xy 66.795173 -433.943318) (xy 66.74082 -433.947208) (xy 66.686467 -433.943323)
			(xy 66.63322 -433.931743) (xy 66.582163 -433.912702) (xy 66.534336 -433.886588) (xy 66.490712 -433.853934)
			(xy 66.452179 -433.815404) (xy 66.419522 -433.771781) (xy 66.393406 -433.723955) (xy 66.374363 -433.672899)
			(xy 66.362779 -433.619653) (xy 66.358892 -433.5653) (xy 65.080333 -433.5653) (xy 65.076445 -433.619659)
			(xy 65.06486 -433.672911) (xy 65.045814 -433.723972) (xy 65.019694 -433.771802) (xy 64.987033 -433.815428)
			(xy 64.948495 -433.853962) (xy 64.904865 -433.886618) (xy 64.857032 -433.912732) (xy 64.805969 -433.931772)
			(xy 64.752715 -433.943351) (xy 64.698356 -433.947233) (xy 64.643998 -433.943339) (xy 64.590747 -433.931748)
			(xy 64.539688 -433.912696) (xy 64.491861 -433.88657) (xy 64.469772 -433.870608) (xy 64.45076 -433.857012)
			(xy 64.408877 -433.83628) (xy 64.363909 -433.823554) (xy 64.317372 -433.819264) (xy 64.270835 -433.823554)
			(xy 64.225867 -433.83628) (xy 64.183984 -433.857012) (xy 64.164972 -433.870608) (xy 64.142884 -433.886566)
			(xy 64.095061 -433.912682) (xy 64.044007 -433.931726) (xy 63.990763 -433.943311) (xy 63.936412 -433.9472)
			(xy 63.882061 -433.943314) (xy 63.828816 -433.931733) (xy 63.777761 -433.912692) (xy 63.729936 -433.886579)
			(xy 63.686314 -433.853925) (xy 63.647783 -433.815395) (xy 63.615128 -433.771774) (xy 63.589013 -433.72395)
			(xy 63.569971 -433.672896) (xy 63.558388 -433.619651) (xy 63.5545 -433.5653) (xy 35.991809 -433.5653)
			(xy 35.997482 -433.568125) (xy 36.071366 -433.613872) (xy 36.140713 -433.666241) (xy 36.204933 -433.724785)
			(xy 36.263477 -433.789005) (xy 36.315846 -433.858352) (xy 36.361593 -433.932236) (xy 36.400327 -434.010025)
			(xy 36.431719 -434.091057) (xy 36.4555 -434.174639) (xy 36.471468 -434.260059) (xy 36.479486 -434.346588)
			(xy 36.479988 -434.390038) (xy 36.479486 -434.433488) (xy 36.471468 -434.520017) (xy 36.4555 -434.605437)
			(xy 36.431719 -434.689019) (xy 36.400327 -434.770051) (xy 36.361593 -434.84784) (xy 36.315846 -434.921724)
			(xy 36.263477 -434.991071) (xy 36.204933 -435.055291) (xy 36.140713 -435.113835) (xy 36.071366 -435.166204)
			(xy 35.997482 -435.211951) (xy 35.919693 -435.250685) (xy 35.838661 -435.282077) (xy 35.755079 -435.305858)
			(xy 35.669659 -435.321826) (xy 35.58313 -435.329844) (xy 35.49623 -435.329844) (xy 35.409701 -435.321826)
			(xy 35.324281 -435.305858) (xy 35.240699 -435.282077) (xy 35.159667 -435.250685) (xy 35.081878 -435.211951)
			(xy 35.007994 -435.166204) (xy 34.938647 -435.113835) (xy 34.874427 -435.055291) (xy 34.815883 -434.991071)
			(xy 34.763514 -434.921724) (xy 34.717767 -434.84784) (xy 34.679033 -434.770051) (xy 34.647641 -434.689019)
			(xy 34.62386 -434.605437) (xy 34.607892 -434.520017) (xy 34.599874 -434.433488) (xy 31.399508 -434.433488)
			(xy 31.391675 -434.518813) (xy 31.37599 -434.603502) (xy 31.352625 -434.686401) (xy 31.321778 -434.766817)
			(xy 31.283706 -434.844074) (xy 31.238729 -434.917527) (xy 31.187222 -434.986558) (xy 31.129619 -435.050589)
			(xy 31.066401 -435.109085) (xy 30.998099 -435.161554) (xy 30.925285 -435.207558) (xy 30.848569 -435.246709)
			(xy 30.768594 -435.278681) (xy 30.68603 -435.303206) (xy 30.60157 -435.320077) (xy 30.515921 -435.329153)
			(xy 30.4298 -435.330359) (xy 30.34393 -435.323685) (xy 30.25903 -435.309185) (xy 30.175812 -435.286983)
			(xy 30.094974 -435.257263) (xy 30.017191 -435.220275) (xy 29.979874 -435.198774) (xy 29.960952 -435.18802)
			(xy 29.920317 -435.172437) (xy 29.877622 -435.164002) (xy 29.834115 -435.162961) (xy 29.791065 -435.169345)
			(xy 29.749732 -435.182966) (xy 29.711321 -435.203427) (xy 29.676957 -435.23013) (xy 29.647641 -435.262296)
			(xy 29.624232 -435.298984) (xy 29.607412 -435.339122) (xy 29.597673 -435.381539) (xy 29.59608 -435.403244)
			(xy 29.59608 -435.528193) (xy 63.55451 -435.528193) (xy 63.558398 -435.473843) (xy 63.569982 -435.4206)
			(xy 63.589025 -435.369548) (xy 63.61514 -435.321725) (xy 63.647795 -435.278106) (xy 63.686326 -435.239578)
			(xy 63.729947 -435.206926) (xy 63.777772 -435.180814) (xy 63.828826 -435.161774) (xy 63.882069 -435.150194)
			(xy 63.936419 -435.14631) (xy 63.990769 -435.1502) (xy 64.044012 -435.161785) (xy 64.095063 -435.18083)
			(xy 64.142885 -435.206946) (xy 64.164972 -435.222904) (xy 64.183984 -435.2365) (xy 64.225867 -435.257232)
			(xy 64.270835 -435.269958) (xy 64.317372 -435.274248) (xy 64.363909 -435.269958) (xy 64.408877 -435.257232)
			(xy 64.45076 -435.2365) (xy 64.469772 -435.222904) (xy 64.49185 -435.206925) (xy 64.539678 -435.180799)
			(xy 64.590737 -435.161745) (xy 64.643989 -435.150153) (xy 64.698349 -435.146257) (xy 64.752709 -435.150138)
			(xy 64.805964 -435.161716) (xy 64.857029 -435.180756) (xy 64.904864 -435.20687) (xy 64.948496 -435.239526)
			(xy 64.987035 -435.27806) (xy 65.019698 -435.321687) (xy 65.04582 -435.369518) (xy 65.064867 -435.42058)
			(xy 65.076454 -435.473833) (xy 65.080343 -435.528193) (xy 66.358901 -435.528193) (xy 66.36279 -435.473841)
			(xy 66.374374 -435.420596) (xy 66.393418 -435.369542) (xy 66.419534 -435.321718) (xy 66.452191 -435.278097)
			(xy 66.490723 -435.239568) (xy 66.534347 -435.206916) (xy 66.582173 -435.180804) (xy 66.633229 -435.161764)
			(xy 66.686475 -435.150185) (xy 66.740827 -435.146301) (xy 66.795179 -435.150193) (xy 66.848423 -435.16178)
			(xy 66.899476 -435.180826) (xy 66.947299 -435.206945) (xy 66.969386 -435.222904) (xy 66.988398 -435.2365)
			(xy 67.030281 -435.257232) (xy 67.075249 -435.269958) (xy 67.121786 -435.274248) (xy 67.168323 -435.269958)
			(xy 67.213291 -435.257232) (xy 67.255174 -435.2365) (xy 67.274186 -435.222904) (xy 67.296263 -435.206927)
			(xy 67.34409 -435.180802) (xy 67.395149 -435.161751) (xy 67.448399 -435.15016) (xy 67.502757 -435.146265)
			(xy 67.557115 -435.150147) (xy 67.610368 -435.161726) (xy 67.661431 -435.180766) (xy 67.709264 -435.20688)
			(xy 67.752894 -435.239536) (xy 67.791431 -435.278068) (xy 67.824093 -435.321694) (xy 67.850213 -435.369523)
			(xy 67.86926 -435.420583) (xy 67.880845 -435.473835) (xy 67.884735 -435.528193) (xy 67.880848 -435.582551)
			(xy 67.869264 -435.635803) (xy 67.850219 -435.686864) (xy 67.824101 -435.734694) (xy 67.791441 -435.778321)
			(xy 67.752905 -435.816855) (xy 67.709276 -435.849512) (xy 67.661444 -435.875628) (xy 67.610382 -435.89467)
			(xy 67.55713 -435.906251) (xy 67.502771 -435.910135) (xy 67.448413 -435.906242) (xy 67.395163 -435.894654)
			(xy 67.344104 -435.875604) (xy 67.296275 -435.849481) (xy 67.274186 -435.83352) (xy 67.255174 -435.819924)
			(xy 67.213291 -435.799192) (xy 67.168323 -435.786466) (xy 67.121786 -435.782176) (xy 67.075249 -435.786466)
			(xy 67.030281 -435.799192) (xy 66.988398 -435.819924) (xy 66.969386 -435.83352) (xy 66.947287 -435.849463)
			(xy 66.899463 -435.875579) (xy 66.848409 -435.894624) (xy 66.795164 -435.906209) (xy 66.740813 -435.910099)
			(xy 66.686461 -435.906213) (xy 66.633216 -435.894632) (xy 66.58216 -435.87559) (xy 66.534335 -435.849476)
			(xy 66.490712 -435.816822) (xy 66.452182 -435.778292) (xy 66.419527 -435.73467) (xy 66.393412 -435.686845)
			(xy 66.37437 -435.63579) (xy 66.362788 -435.582545) (xy 66.358901 -435.528193) (xy 65.080343 -435.528193)
			(xy 65.076456 -435.582553) (xy 65.064871 -435.635807) (xy 65.045826 -435.686869) (xy 65.019706 -435.734701)
			(xy 64.987045 -435.778329) (xy 64.948507 -435.816864) (xy 64.904876 -435.849522) (xy 64.857042 -435.875638)
			(xy 64.805978 -435.89468) (xy 64.752724 -435.90626) (xy 64.698363 -435.910143) (xy 64.644004 -435.906249)
			(xy 64.590751 -435.894659) (xy 64.539691 -435.875607) (xy 64.491862 -435.849482) (xy 64.469772 -435.83352)
			(xy 64.45076 -435.819924) (xy 64.408877 -435.799192) (xy 64.363909 -435.786466) (xy 64.317372 -435.782176)
			(xy 64.270835 -435.786466) (xy 64.225867 -435.799192) (xy 64.183984 -435.819924) (xy 64.164972 -435.83352)
			(xy 64.142873 -435.849461) (xy 64.09505 -435.875576) (xy 64.043998 -435.894619) (xy 63.990755 -435.906202)
			(xy 63.936405 -435.91009) (xy 63.882055 -435.906204) (xy 63.828812 -435.894622) (xy 63.777759 -435.87558)
			(xy 63.729935 -435.849467) (xy 63.686315 -435.816813) (xy 63.647786 -435.778284) (xy 63.615132 -435.734663)
			(xy 63.589019 -435.686839) (xy 63.569978 -435.635786) (xy 63.558396 -435.582543) (xy 63.55451 -435.528193)
			(xy 29.59608 -435.528193) (xy 29.59608 -435.916832) (xy 29.597725 -435.938526) (xy 29.607484 -435.980921)
			(xy 29.624315 -436.021036) (xy 29.647727 -436.057702) (xy 29.677038 -436.089849) (xy 29.711393 -436.116539)
			(xy 29.749788 -436.136992) (xy 29.791104 -436.150614) (xy 29.834135 -436.157005) (xy 29.877627 -436.155979)
			(xy 29.920309 -436.147568) (xy 29.960937 -436.132015) (xy 29.979874 -436.121302) (xy 30.016887 -436.099906)
			(xy 30.094076 -436.063137) (xy 30.174284 -436.033527) (xy 30.256849 -436.01132) (xy 30.341089 -435.996699)
			(xy 30.426308 -435.989786) (xy 30.511803 -435.990637) (xy 30.596868 -435.999245) (xy 30.6808 -436.01554)
			(xy 30.762906 -436.039386) (xy 30.842509 -436.070587) (xy 30.918951 -436.108885) (xy 30.991601 -436.153964)
			(xy 31.059859 -436.205452) (xy 31.123161 -436.262923) (xy 31.180985 -436.325903) (xy 31.232853 -436.393873)
			(xy 31.278337 -436.466269) (xy 31.317061 -436.542496) (xy 31.348706 -436.621924) (xy 31.373011 -436.703896)
			(xy 31.389774 -436.787735) (xy 31.398857 -436.872751) (xy 31.400186 -436.958239) (xy 31.399207 -436.973488)
			(xy 34.599874 -436.973488) (xy 34.599874 -436.886588) (xy 34.607892 -436.800059) (xy 34.62386 -436.714639)
			(xy 34.647641 -436.631057) (xy 34.679033 -436.550025) (xy 34.717767 -436.472236) (xy 34.763514 -436.398352)
			(xy 34.815883 -436.329005) (xy 34.874427 -436.264785) (xy 34.938647 -436.206241) (xy 35.007994 -436.153872)
			(xy 35.081878 -436.108125) (xy 35.159667 -436.069391) (xy 35.240699 -436.037999) (xy 35.324281 -436.014218)
			(xy 35.409701 -435.99825) (xy 35.49623 -435.990232) (xy 35.58313 -435.990232) (xy 35.669659 -435.99825)
			(xy 35.755079 -436.014218) (xy 35.838661 -436.037999) (xy 35.919693 -436.069391) (xy 35.997482 -436.108125)
			(xy 36.071366 -436.153872) (xy 36.140713 -436.206241) (xy 36.204933 -436.264785) (xy 36.263477 -436.329005)
			(xy 36.315846 -436.398352) (xy 36.361593 -436.472236) (xy 36.400327 -436.550025) (xy 36.431719 -436.631057)
			(xy 36.4555 -436.714639) (xy 36.471468 -436.800059) (xy 36.479486 -436.886588) (xy 36.479988 -436.930038)
			(xy 36.479486 -436.973488) (xy 36.471468 -437.060017) (xy 36.4555 -437.145437) (xy 36.431719 -437.229019)
			(xy 36.400327 -437.310051) (xy 36.361593 -437.38784) (xy 36.339437 -437.423624) (xy 63.488165 -437.423624)
			(xy 63.492049 -437.369267) (xy 63.50363 -437.316017) (xy 63.522671 -437.264956) (xy 63.548786 -437.217126)
			(xy 63.581441 -437.173498) (xy 63.619974 -437.134963) (xy 63.663598 -437.102303) (xy 63.711427 -437.076185)
			(xy 63.762486 -437.057139) (xy 63.815735 -437.045554) (xy 63.870092 -437.041665) (xy 63.924448 -437.045551)
			(xy 63.977698 -437.057134) (xy 64.028758 -437.076178) (xy 64.076587 -437.102294) (xy 64.098678 -437.118252)
			(xy 64.11769 -437.131848) (xy 64.159573 -437.15258) (xy 64.204541 -437.165306) (xy 64.251078 -437.169596)
			(xy 64.297615 -437.165306) (xy 64.342583 -437.15258) (xy 64.384466 -437.131848) (xy 64.403478 -437.118252)
			(xy 64.425604 -437.102344) (xy 64.473429 -437.076225) (xy 64.524484 -437.057179) (xy 64.57773 -437.045592)
			(xy 64.632083 -437.041702) (xy 64.686437 -437.045588) (xy 64.739684 -437.057169) (xy 64.790741 -437.076211)
			(xy 64.838568 -437.102326) (xy 64.882191 -437.134982) (xy 64.920723 -437.173514) (xy 64.953378 -437.217138)
			(xy 64.979492 -437.264966) (xy 64.998533 -437.316023) (xy 65.010113 -437.36927) (xy 65.013998 -437.423624)
			(xy 66.292556 -437.423624) (xy 66.296441 -437.369265) (xy 66.308022 -437.316013) (xy 66.327064 -437.264951)
			(xy 66.35318 -437.217119) (xy 66.385837 -437.17349) (xy 66.424372 -437.134954) (xy 66.467998 -437.102293)
			(xy 66.515829 -437.076175) (xy 66.566889 -437.057129) (xy 66.620141 -437.045544) (xy 66.674499 -437.041656)
			(xy 66.728858 -437.045544) (xy 66.78211 -437.057129) (xy 66.833171 -437.076174) (xy 66.881001 -437.102293)
			(xy 66.903092 -437.118252) (xy 66.922104 -437.131848) (xy 66.963987 -437.15258) (xy 67.008955 -437.165306)
			(xy 67.055492 -437.169596) (xy 67.102029 -437.165306) (xy 67.146997 -437.15258) (xy 67.18888 -437.131848)
			(xy 67.207892 -437.118252) (xy 67.230018 -437.102345) (xy 67.277842 -437.076229) (xy 67.328895 -437.057184)
			(xy 67.38214 -437.045599) (xy 67.436491 -437.041711) (xy 67.490843 -437.045597) (xy 67.544088 -437.057179)
			(xy 67.595143 -437.076221) (xy 67.642968 -437.102336) (xy 67.686589 -437.134991) (xy 67.725119 -437.173523)
			(xy 67.757772 -437.217145) (xy 67.783885 -437.264971) (xy 67.802925 -437.316027) (xy 67.814505 -437.369272)
			(xy 67.818389 -437.423624) (xy 67.814498 -437.477975) (xy 67.802912 -437.531219) (xy 67.783865 -437.582272)
			(xy 67.757746 -437.630095) (xy 67.725087 -437.673714) (xy 67.686553 -437.71224) (xy 67.642927 -437.74489)
			(xy 67.595099 -437.770999) (xy 67.544042 -437.790034) (xy 67.490795 -437.80161) (xy 67.436443 -437.805489)
			(xy 67.382093 -437.801594) (xy 67.328849 -437.790002) (xy 67.277798 -437.770952) (xy 67.229977 -437.744829)
			(xy 67.207892 -437.728868) (xy 67.18888 -437.715272) (xy 67.146997 -437.69454) (xy 67.102029 -437.681814)
			(xy 67.055492 -437.677524) (xy 67.008955 -437.681814) (xy 66.963987 -437.69454) (xy 66.922104 -437.715272)
			(xy 66.903092 -437.728868) (xy 66.881042 -437.744881) (xy 66.833214 -437.771006) (xy 66.782156 -437.790058)
			(xy 66.728905 -437.801649) (xy 66.674548 -437.805544) (xy 66.620189 -437.801663) (xy 66.566935 -437.790085)
			(xy 66.515872 -437.771045) (xy 66.468038 -437.744933) (xy 66.424408 -437.712278) (xy 66.385869 -437.673746)
			(xy 66.353206 -437.630122) (xy 66.327084 -437.582293) (xy 66.308036 -437.531233) (xy 66.296448 -437.477982)
			(xy 66.292556 -437.423624) (xy 65.013998 -437.423624) (xy 65.010107 -437.477977) (xy 64.998519 -437.531223)
			(xy 64.979472 -437.582278) (xy 64.953352 -437.630102) (xy 64.920691 -437.673722) (xy 64.882155 -437.712249)
			(xy 64.838528 -437.7449) (xy 64.790697 -437.771009) (xy 64.739638 -437.790044) (xy 64.686389 -437.801619)
			(xy 64.632035 -437.805498) (xy 64.577683 -437.801601) (xy 64.524438 -437.790008) (xy 64.473385 -437.770955)
			(xy 64.425564 -437.74483) (xy 64.403478 -437.728868) (xy 64.384466 -437.715272) (xy 64.342583 -437.69454)
			(xy 64.297615 -437.681814) (xy 64.251078 -437.677524) (xy 64.204541 -437.681814) (xy 64.159573 -437.69454)
			(xy 64.11769 -437.715272) (xy 64.098678 -437.728868) (xy 64.076628 -437.74488) (xy 64.028801 -437.771002)
			(xy 63.977744 -437.790052) (xy 63.924496 -437.801642) (xy 63.87014 -437.805535) (xy 63.815783 -437.801653)
			(xy 63.762532 -437.790075) (xy 63.71147 -437.771035) (xy 63.663639 -437.744923) (xy 63.62001 -437.712269)
			(xy 63.581473 -437.673738) (xy 63.548812 -437.630115) (xy 63.522691 -437.582287) (xy 63.503643 -437.531229)
			(xy 63.492056 -437.47798) (xy 63.488165 -437.423624) (xy 36.339437 -437.423624) (xy 36.315846 -437.461724)
			(xy 36.263477 -437.531071) (xy 36.204933 -437.595291) (xy 36.140713 -437.653835) (xy 36.071366 -437.706204)
			(xy 35.997482 -437.751951) (xy 35.919693 -437.790685) (xy 35.838661 -437.822077) (xy 35.755079 -437.845858)
			(xy 35.669659 -437.861826) (xy 35.58313 -437.869844) (xy 35.49623 -437.869844) (xy 35.409701 -437.861826)
			(xy 35.324281 -437.845858) (xy 35.240699 -437.822077) (xy 35.159667 -437.790685) (xy 35.081878 -437.751951)
			(xy 35.007994 -437.706204) (xy 34.938647 -437.653835) (xy 34.874427 -437.595291) (xy 34.815883 -437.531071)
			(xy 34.763514 -437.461724) (xy 34.717767 -437.38784) (xy 34.679033 -437.310051) (xy 34.647641 -437.229019)
			(xy 34.62386 -437.145437) (xy 34.607892 -437.060017) (xy 34.599874 -436.973488) (xy 31.399207 -436.973488)
			(xy 31.397448 -437.000904) (xy 31.393723 -437.043838) (xy 31.379402 -437.128824) (xy 31.357363 -437.212143)
			(xy 31.32779 -437.293094) (xy 31.290932 -437.370999) (xy 31.247098 -437.445204) (xy 31.196656 -437.515085)
			(xy 31.140029 -437.580055) (xy 31.077694 -437.63957) (xy 31.010173 -437.69313) (xy 30.938033 -437.740284)
			(xy 30.861879 -437.780638) (xy 30.782352 -437.813852) (xy 30.741366 -437.827166) (xy 30.719794 -437.835114)
			(xy 30.679727 -437.857647) (xy 30.644366 -437.88702) (xy 30.614867 -437.922274) (xy 30.59219 -437.96226)
			(xy 30.577076 -438.005673) (xy 30.570018 -438.051097) (xy 30.571247 -438.097049) (xy 30.580721 -438.142031)
			(xy 30.598133 -438.184574) (xy 30.622913 -438.223292) (xy 30.638242 -438.240424) (xy 30.742382 -438.344564)
			(xy 31.095188 -438.69737) (xy 31.107317 -438.708767) (xy 31.1361 -438.725455) (xy 31.168216 -438.734139)
			(xy 31.18485 -438.734708) (xy 44.021248 -438.734708) (xy 45.090249 -439.803709) (xy 47.842668 -439.803709)
			(xy 47.842668 -439.722599) (xy 47.850618 -439.64188) (xy 47.866441 -439.562329) (xy 47.889986 -439.484713)
			(xy 47.921025 -439.409777) (xy 47.95926 -439.338245) (xy 48.004322 -439.270805) (xy 48.055777 -439.208106)
			(xy 48.11313 -439.150753) (xy 48.175829 -439.099298) (xy 48.243269 -439.054236) (xy 48.314801 -439.016001)
			(xy 48.389737 -438.984962) (xy 48.467353 -438.961417) (xy 48.546904 -438.945594) (xy 48.627623 -438.937644)
			(xy 48.708733 -438.937644) (xy 48.789452 -438.945594) (xy 48.869003 -438.961417) (xy 48.946619 -438.984962)
			(xy 49.021555 -439.016001) (xy 49.093087 -439.054236) (xy 49.160527 -439.099298) (xy 49.223226 -439.150753)
			(xy 49.280579 -439.208106) (xy 49.332034 -439.270805) (xy 49.377096 -439.338245) (xy 49.415331 -439.409777)
			(xy 49.44637 -439.484713) (xy 49.469915 -439.562329) (xy 49.485738 -439.64188) (xy 49.493688 -439.722599)
			(xy 49.494186 -439.763154) (xy 49.493688 -439.803709) (xy 51.342788 -439.803709) (xy 51.342788 -439.722599)
			(xy 51.350738 -439.64188) (xy 51.366561 -439.562329) (xy 51.390106 -439.484713) (xy 51.421145 -439.409777)
			(xy 51.45938 -439.338245) (xy 51.504442 -439.270805) (xy 51.555897 -439.208106) (xy 51.61325 -439.150753)
			(xy 51.675949 -439.099298) (xy 51.743389 -439.054236) (xy 51.814921 -439.016001) (xy 51.889857 -438.984962)
			(xy 51.967473 -438.961417) (xy 52.047024 -438.945594) (xy 52.127743 -438.937644) (xy 52.208853 -438.937644)
			(xy 52.289572 -438.945594) (xy 52.369123 -438.961417) (xy 52.446739 -438.984962) (xy 52.521675 -439.016001)
			(xy 52.593207 -439.054236) (xy 52.660647 -439.099298) (xy 52.723346 -439.150753) (xy 52.780699 -439.208106)
			(xy 52.832154 -439.270805) (xy 52.877216 -439.338245) (xy 52.915451 -439.409777) (xy 52.94649 -439.484713)
			(xy 52.970035 -439.562329) (xy 52.985858 -439.64188) (xy 52.993808 -439.722599) (xy 52.994306 -439.763154)
			(xy 52.993808 -439.803709) (xy 52.985858 -439.884428) (xy 52.970035 -439.963979) (xy 52.94649 -440.041595)
			(xy 52.915451 -440.116531) (xy 52.877216 -440.188063) (xy 52.832154 -440.255503) (xy 52.780699 -440.318202)
			(xy 52.723346 -440.375555) (xy 52.660647 -440.42701) (xy 52.593207 -440.472072) (xy 52.521675 -440.510307)
			(xy 52.446739 -440.541346) (xy 52.369123 -440.564891) (xy 52.289572 -440.580714) (xy 52.208853 -440.588664)
			(xy 52.127743 -440.588664) (xy 52.047024 -440.580714) (xy 51.967473 -440.564891) (xy 51.889857 -440.541346)
			(xy 51.814921 -440.510307) (xy 51.743389 -440.472072) (xy 51.675949 -440.42701) (xy 51.61325 -440.375555)
			(xy 51.555897 -440.318202) (xy 51.504442 -440.255503) (xy 51.45938 -440.188063) (xy 51.421145 -440.116531)
			(xy 51.390106 -440.041595) (xy 51.366561 -439.963979) (xy 51.350738 -439.884428) (xy 51.342788 -439.803709)
			(xy 49.493688 -439.803709) (xy 49.485738 -439.884428) (xy 49.469915 -439.963979) (xy 49.44637 -440.041595)
			(xy 49.415331 -440.116531) (xy 49.377096 -440.188063) (xy 49.332034 -440.255503) (xy 49.280579 -440.318202)
			(xy 49.223226 -440.375555) (xy 49.160527 -440.42701) (xy 49.093087 -440.472072) (xy 49.021555 -440.510307)
			(xy 48.946619 -440.541346) (xy 48.869003 -440.564891) (xy 48.789452 -440.580714) (xy 48.708733 -440.588664)
			(xy 48.627623 -440.588664) (xy 48.546904 -440.580714) (xy 48.467353 -440.564891) (xy 48.389737 -440.541346)
			(xy 48.314801 -440.510307) (xy 48.243269 -440.472072) (xy 48.175829 -440.42701) (xy 48.11313 -440.375555)
			(xy 48.055777 -440.318202) (xy 48.004322 -440.255503) (xy 47.95926 -440.188063) (xy 47.921025 -440.116531)
			(xy 47.889986 -440.041595) (xy 47.866441 -439.963979) (xy 47.850618 -439.884428) (xy 47.842668 -439.803709)
			(xy 45.090249 -439.803709) (xy 47.201328 -441.914788) (xy 90.306398 -441.914788) (xy 100.603812 -452.212202)
			(xy 100.603812 -483.19817) (xy 96.744282 -487.057954) (xy 96.735138 -487.08945) (xy 96.72674 -487.116869)
			(xy 96.702864 -487.169004) (xy 96.671455 -487.216979) (xy 96.63322 -487.259714) (xy 96.589019 -487.296244)
			(xy 96.564704 -487.311446) (xy 92.359988 -491.516162) (xy 92.359988 -493.279684) (xy 92.360394 -493.294585)
			(xy 92.367309 -493.323574) (xy 92.380767 -493.350165) (xy 92.40003 -493.372904) (xy 92.411804 -493.382046)
			(xy 92.442809 -493.405503) (xy 92.500038 -493.458133) (xy 92.551187 -493.516689) (xy 92.595647 -493.580473)
			(xy 92.632886 -493.648725) (xy 92.662461 -493.72063) (xy 92.684019 -493.795331) (xy 92.697303 -493.871938)
			(xy 92.702155 -493.949536) (xy 92.698517 -494.027201) (xy 92.686431 -494.104006) (xy 92.666043 -494.179035)
			(xy 92.652342 -494.21542) (xy 92.638893 -494.248531) (xy 92.606274 -494.312123) (xy 92.567442 -494.372123)
			(xy 92.522788 -494.427926) (xy 92.472763 -494.47897) (xy 92.417871 -494.524739) (xy 92.358665 -494.564772)
			(xy 92.295743 -494.598666) (xy 92.229739 -494.626078) (xy 92.19565 -494.636806) (xy 92.180235 -494.641952)
			(xy 92.152495 -494.658864) (xy 92.129928 -494.682236) (xy 92.114001 -494.710552) (xy 92.105746 -494.741974)
			(xy 92.105226 -494.758218) (xy 92.105226 -495.734086) (xy 92.155264 -495.801396) (xy 92.19565 -495.813588)
			(xy 92.233685 -495.825658) (xy 92.307017 -495.857131) (xy 92.376371 -495.896606) (xy 92.440874 -495.943589)
			(xy 92.499719 -495.997491) (xy 92.526358 -496.027202) (xy 92.553402 -496.059148) (xy 92.600621 -496.12826)
			(xy 92.639408 -496.202434) (xy 92.654882 -496.241324) (xy 92.668282 -496.277904) (xy 92.687947 -496.353287)
			(xy 92.69926 -496.430368) (xy 92.702087 -496.508223) (xy 92.696394 -496.585921) (xy 92.682248 -496.662533)
			(xy 92.659819 -496.737141) (xy 92.629375 -496.808853) (xy 92.59128 -496.87681) (xy 92.545991 -496.9402)
			(xy 92.494049 -496.998265) (xy 92.465398 -497.02466) (xy 92.450875 -497.037506) (xy 92.420632 -497.061776)
			(xy 92.404946 -497.073174) (xy 92.38107 -497.090446) (xy 92.324428 -497.195348) (xy 92.324428 -497.21008)
			(xy 93.154506 -497.21008) (xy 93.158522 -497.09381) (xy 93.170549 -496.978095) (xy 93.190531 -496.863485)
			(xy 93.218373 -496.750526) (xy 93.253942 -496.639758) (xy 93.297068 -496.531707) (xy 93.347545 -496.426889)
			(xy 93.405134 -496.325804) (xy 93.46956 -496.228932) (xy 93.540515 -496.136736) (xy 93.617662 -496.049655)
			(xy 93.700633 -495.968104) (xy 93.789033 -495.892472) (xy 93.88244 -495.823118) (xy 93.980409 -495.760375)
			(xy 94.082473 -495.704539) (xy 94.188147 -495.655878) (xy 94.296926 -495.614624) (xy 94.408291 -495.580973)
			(xy 94.521714 -495.555085) (xy 94.636651 -495.537084) (xy 94.752557 -495.527055) (xy 94.868879 -495.525047)
			(xy 94.985062 -495.531069) (xy 95.100553 -495.545092) (xy 95.214801 -495.56705) (xy 95.327262 -495.596837)
			(xy 95.4374 -495.634312) (xy 95.54469 -495.679297) (xy 95.648621 -495.731576) (xy 95.748697 -495.790901)
			(xy 95.844443 -495.856989) (xy 95.9354 -495.929525) (xy 96.021136 -496.008164) (xy 96.101243 -496.09253)
			(xy 96.175339 -496.182222) (xy 96.243069 -496.276812) (xy 96.304113 -496.37585) (xy 96.358178 -496.478863)
			(xy 96.405008 -496.58536) (xy 96.444379 -496.694835) (xy 96.476103 -496.806765) (xy 96.500029 -496.920617)
			(xy 96.516043 -497.035849) (xy 96.52407 -497.151911) (xy 96.524572 -497.21008) (xy 96.52407 -497.268249)
			(xy 96.516043 -497.384311) (xy 96.500029 -497.499543) (xy 96.476103 -497.613395) (xy 96.444379 -497.725325)
			(xy 96.405008 -497.8348) (xy 96.358178 -497.941297) (xy 96.304113 -498.04431) (xy 96.243069 -498.143348)
			(xy 96.175339 -498.237938) (xy 96.101243 -498.32763) (xy 96.021136 -498.411996) (xy 95.9354 -498.490635)
			(xy 95.844443 -498.563171) (xy 95.748697 -498.629259) (xy 95.648621 -498.688584) (xy 95.54469 -498.740863)
			(xy 95.4374 -498.785848) (xy 95.327262 -498.823323) (xy 95.214801 -498.85311) (xy 95.100553 -498.875068)
			(xy 94.985062 -498.889091) (xy 94.868879 -498.895113) (xy 94.752557 -498.893105) (xy 94.636651 -498.883076)
			(xy 94.521714 -498.865075) (xy 94.408291 -498.839187) (xy 94.296926 -498.805536) (xy 94.188147 -498.764282)
			(xy 94.082473 -498.715621) (xy 93.980409 -498.659785) (xy 93.88244 -498.597042) (xy 93.789033 -498.527688)
			(xy 93.700633 -498.452056) (xy 93.617662 -498.370505) (xy 93.540515 -498.283424) (xy 93.46956 -498.191228)
			(xy 93.405134 -498.094356) (xy 93.347545 -497.993271) (xy 93.297068 -497.888453) (xy 93.253942 -497.780402)
			(xy 93.218373 -497.669634) (xy 93.190531 -497.556675) (xy 93.170549 -497.442065) (xy 93.158522 -497.32635)
			(xy 93.154506 -497.21008) (xy 92.324428 -497.21008) (xy 92.324428 -497.988082) (xy 90.770202 -499.542308)
			(xy 85.220048 -499.542308) (xy 83.956652 -498.278658) (xy 83.956652 -494.436146) (xy 90.644726 -487.747818)
			(xy 90.654378 -487.721402) (xy 90.665215 -487.693504) (xy 90.694322 -487.641213) (xy 90.731245 -487.594116)
			(xy 90.775078 -487.55337) (xy 90.824741 -487.519977) (xy 90.879014 -487.494758) (xy 90.907616 -487.485944)
			(xy 90.939112 -487.4768) (xy 92.234512 -486.1814) (xy 93.795088 -486.1814) (xy 94.73819 -485.238298)
			(xy 94.75433 -485.2214) (xy 94.780764 -485.182874) (xy 94.799713 -485.140167) (xy 94.810539 -485.094715)
			(xy 94.812876 -485.048051) (xy 94.806647 -485.001745) (xy 94.79206 -484.957358) (xy 94.769608 -484.916383)
			(xy 94.740046 -484.880202) (xy 94.70437 -484.850032) (xy 94.684342 -484.837994) (xy 94.649697 -484.817682)
			(xy 94.584457 -484.770839) (xy 94.524503 -484.717398) (xy 94.470497 -484.657952) (xy 94.42304 -484.593158)
			(xy 94.382656 -484.523735) (xy 94.349792 -484.450452) (xy 94.324813 -484.37412) (xy 94.307996 -484.295586)
			(xy 94.299527 -484.215719) (xy 94.299024 -484.175562) (xy 94.299024 -484.168196) (xy 94.299474 -484.130659)
			(xy 94.306856 -484.055949) (xy 94.321547 -483.982326) (xy 94.343406 -483.910505) (xy 94.37222 -483.84118)
			(xy 94.40771 -483.775025) (xy 94.449533 -483.712679) (xy 94.497283 -483.654748) (xy 94.52356 -483.627938)
			(xy 94.534472 -483.616345) (xy 94.550729 -483.588984) (xy 94.55972 -483.558454) (xy 94.560888 -483.526649)
			(xy 94.554159 -483.495543) (xy 94.539952 -483.467063) (xy 94.52991 -483.45471) (xy 94.506017 -483.426533)
			(xy 94.463198 -483.366327) (xy 94.426401 -483.302262) (xy 94.410784 -483.268782) (xy 94.390718 -483.220014)
			(xy 94.376748 -483.182676) (xy 94.311724 -483.137464) (xy 93.254576 -483.137464) (xy 93.225874 -483.153212)
			(xy 93.201927 -483.165878) (xy 93.151268 -483.185065) (xy 93.098403 -483.196889) (xy 93.044396 -483.201114)
			(xy 92.990335 -483.197652) (xy 92.937308 -483.186576) (xy 92.886383 -483.168106) (xy 92.838584 -483.142615)
			(xy 92.794873 -483.110616) (xy 92.75613 -483.072754) (xy 92.723136 -483.02979) (xy 92.696554 -482.982589)
			(xy 92.676919 -482.932101) (xy 92.664627 -482.879342) (xy 92.659925 -482.825375) (xy 92.662908 -482.771286)
			(xy 92.673515 -482.718163) (xy 92.68206 -482.692456) (xy 92.673486 -482.666736) (xy 92.66286 -482.613573)
			(xy 92.659871 -482.559441) (xy 92.664577 -482.505431) (xy 92.676883 -482.452631) (xy 92.696543 -482.402107)
			(xy 92.72316 -482.354876) (xy 92.756197 -482.311889) (xy 92.794988 -482.274015) (xy 92.838751 -482.242015)
			(xy 92.886606 -482.216536) (xy 92.937586 -482.198089) (xy 92.990664 -482.187048) (xy 93.044771 -482.183635)
			(xy 93.098816 -482.187918) (xy 93.15171 -482.199811) (xy 93.202387 -482.219075) (xy 93.226382 -482.2317)
			(xy 93.255084 -482.247448) (xy 93.75521 -482.247448) (xy 96.614488 -479.388424) (xy 96.62584 -479.376277)
			(xy 96.642433 -479.347482) (xy 96.65103 -479.315379) (xy 96.651572 -479.298762) (xy 96.651572 -458.086714)
			(xy 94.87281 -456.307952) (xy 84.900516 -456.307952) (xy 82.90814 -454.315576) (xy 82.90814 -453.563736)
			(xy 82.906485 -453.541754) (xy 82.896559 -453.498808) (xy 82.879374 -453.458218) (xy 82.855446 -453.421201)
			(xy 82.825491 -453.388865) (xy 82.790409 -453.362181) (xy 82.751249 -453.341947) (xy 82.709186 -453.328771)
			(xy 82.665481 -453.323048) (xy 82.621444 -453.324949) (xy 82.578395 -453.334417) (xy 82.537624 -453.351168)
			(xy 82.518758 -453.362568) (xy 82.486374 -453.38236) (xy 82.418191 -453.415706) (xy 82.346846 -453.441608)
			(xy 82.273151 -453.45977) (xy 82.197941 -453.469988) (xy 82.122071 -453.472144) (xy 82.046402 -453.466215)
			(xy 81.971794 -453.452267) (xy 81.899094 -453.430459) (xy 81.829127 -453.401039) (xy 81.762688 -453.364341)
			(xy 81.700531 -453.320781) (xy 81.643362 -453.270855) (xy 81.591831 -453.215128) (xy 81.546522 -453.154235)
			(xy 81.50795 -453.088866) (xy 81.476553 -453.019763) (xy 81.452688 -452.947712) (xy 81.436625 -452.873531)
			(xy 81.428548 -452.798061) (xy 81.428547 -452.72216) (xy 81.436622 -452.64669) (xy 81.452683 -452.572508)
			(xy 81.476546 -452.500457) (xy 81.50794 -452.431353) (xy 81.54651 -452.365983) (xy 81.591817 -452.305088)
			(xy 81.643347 -452.24936) (xy 81.700514 -452.199432) (xy 81.76267 -452.15587) (xy 81.829108 -452.11917)
			(xy 81.899074 -452.089748) (xy 81.971773 -452.067938) (xy 82.046381 -452.053988) (xy 82.122049 -452.048057)
			(xy 82.19792 -452.050211) (xy 82.27313 -452.060426) (xy 82.346826 -452.078586) (xy 82.418171 -452.104485)
			(xy 82.486355 -452.13783) (xy 82.518758 -452.157592) (xy 82.537643 -452.168957) (xy 82.578411 -452.185702)
			(xy 82.621455 -452.195166) (xy 82.665487 -452.197065) (xy 82.709187 -452.191342) (xy 82.751244 -452.178169)
			(xy 82.7904 -452.15794) (xy 82.825481 -452.131262) (xy 82.855436 -452.098933) (xy 82.879367 -452.061924)
			(xy 82.896557 -452.021342) (xy 82.90649 -451.978403) (xy 82.90814 -451.956424) (xy 82.90814 -450.863716)
			(xy 82.906484 -450.841735) (xy 82.896555 -450.798793) (xy 82.879369 -450.758206) (xy 82.85544 -450.721191)
			(xy 82.825486 -450.688859) (xy 82.790404 -450.662177) (xy 82.751246 -450.641945) (xy 82.709186 -450.62877)
			(xy 82.665483 -450.623047) (xy 82.621449 -450.624947) (xy 82.578401 -450.634414) (xy 82.537632 -450.651162)
			(xy 82.518758 -450.662548) (xy 82.486375 -450.68234) (xy 82.418194 -450.715687) (xy 82.346851 -450.741588)
			(xy 82.273158 -450.759752) (xy 82.19795 -450.76997) (xy 82.122082 -450.772127) (xy 82.046415 -450.766199)
			(xy 81.971808 -450.752253) (xy 81.899109 -450.730447) (xy 81.829144 -450.701029) (xy 81.762706 -450.664332)
			(xy 81.70055 -450.620775) (xy 81.643382 -450.57085) (xy 81.591851 -450.515126) (xy 81.546542 -450.454234)
			(xy 81.50797 -450.388867) (xy 81.476573 -450.319767) (xy 81.452707 -450.247718) (xy 81.436644 -450.173538)
			(xy 81.428565 -450.098071) (xy 81.428563 -450.022172) (xy 81.436637 -449.946704) (xy 81.452696 -449.872523)
			(xy 81.476558 -449.800473) (xy 81.507951 -449.731371) (xy 81.546519 -449.666001) (xy 81.591824 -449.605107)
			(xy 81.643351 -449.54938) (xy 81.700516 -449.499452) (xy 81.762669 -449.45589) (xy 81.829105 -449.41919)
			(xy 81.899069 -449.389768) (xy 81.971767 -449.367957) (xy 82.046373 -449.354006) (xy 82.122039 -449.348074)
			(xy 82.197908 -449.350227) (xy 82.273116 -449.36044) (xy 82.346811 -449.378599) (xy 82.418155 -449.404497)
			(xy 82.486338 -449.437839) (xy 82.518758 -449.457572) (xy 82.537643 -449.468938) (xy 82.578409 -449.485684)
			(xy 82.621453 -449.495148) (xy 82.665485 -449.497048) (xy 82.709184 -449.491325) (xy 82.751241 -449.478152)
			(xy 82.790396 -449.457922) (xy 82.825476 -449.431243) (xy 82.855429 -449.398914) (xy 82.879358 -449.361904)
			(xy 82.896545 -449.321321) (xy 82.906476 -449.278382) (xy 82.90814 -449.256404) (xy 82.90814 -449.162424)
			(xy 80.45704 -446.711324) (xy 41.226994 -446.711324) (xy 40.299894 -445.784224) (xy 36.585144 -445.784224)
			(xy 36.56212 -445.785995) (xy 36.517231 -445.796812) (xy 36.475033 -445.815556) (xy 36.436912 -445.84161)
			(xy 36.404121 -445.874118) (xy 36.377738 -445.912011) (xy 36.35863 -445.954046) (xy 36.347425 -445.998839)
			(xy 36.34449 -446.044919) (xy 36.349923 -446.090772) (xy 36.363545 -446.134891) (xy 36.373816 -446.155572)
			(xy 36.393617 -446.194692) (xy 36.426699 -446.275898) (xy 36.452078 -446.359831) (xy 36.469534 -446.445762)
			(xy 36.478915 -446.532945) (xy 36.48014 -446.620622) (xy 36.473198 -446.708033) (xy 36.458149 -446.794418)
			(xy 36.435124 -446.879027) (xy 36.404324 -446.961125) (xy 36.366014 -447.04) (xy 36.320529 -447.114966)
			(xy 36.268263 -447.185373) (xy 36.209671 -447.250609) (xy 36.14526 -447.310107) (xy 36.07559 -447.363351)
			(xy 36.001266 -447.409879) (xy 35.922934 -447.449286) (xy 35.841274 -447.481231) (xy 35.756995 -447.505435)
			(xy 35.670828 -447.521689) (xy 35.583523 -447.529851) (xy 35.495837 -447.529851) (xy 35.408532 -447.521689)
			(xy 35.322365 -447.505435) (xy 35.238086 -447.481231) (xy 35.156426 -447.449286) (xy 35.078094 -447.409879)
			(xy 35.00377 -447.363351) (xy 34.9341 -447.310107) (xy 34.869689 -447.250609) (xy 34.811097 -447.185373)
			(xy 34.758831 -447.114966) (xy 34.713346 -447.04) (xy 34.675036 -446.961125) (xy 34.644236 -446.879027)
			(xy 34.621211 -446.794418) (xy 34.606162 -446.708033) (xy 34.59922 -446.620622) (xy 34.600445 -446.532945)
			(xy 34.609826 -446.445762) (xy 34.627282 -446.359831) (xy 34.652661 -446.275898) (xy 34.685743 -446.194692)
			(xy 34.705544 -446.155572) (xy 34.715778 -446.134876) (xy 34.7294 -446.090767) (xy 34.734833 -446.044922)
			(xy 34.7319 -445.998851) (xy 34.720696 -445.954066) (xy 34.70159 -445.91204) (xy 34.67521 -445.874155)
			(xy 34.642423 -445.841655) (xy 34.604306 -445.81561) (xy 34.562114 -445.796875) (xy 34.517232 -445.786065)
			(xy 34.494216 -445.784224) (xy 31.757874 -445.784224) (xy 31.742871 -445.785863) (xy 31.714205 -445.79528)
			(xy 31.68855 -445.811163) (xy 31.67761 -445.821562) (xy 31.372302 -446.12687) (xy 31.361776 -446.138006)
			(xy 31.345869 -446.164186) (xy 31.33668 -446.193409) (xy 31.334739 -446.223981) (xy 31.336996 -446.239138)
			(xy 31.341314 -446.262506) (xy 31.34487 -446.272412) (xy 31.359156 -446.313723) (xy 31.380903 -446.398391)
			(xy 31.394699 -446.484712) (xy 31.400426 -446.571941) (xy 31.398032 -446.659325) (xy 31.387541 -446.746109)
			(xy 31.369041 -446.831546) (xy 31.342692 -446.914897) (xy 31.308723 -446.995444) (xy 31.267425 -447.07249)
			(xy 31.219156 -447.145372) (xy 31.164332 -447.21346) (xy 31.103427 -447.276167) (xy 31.036965 -447.332951)
			(xy 30.96552 -447.383323) (xy 30.889709 -447.426848) (xy 30.810186 -447.463149) (xy 30.727638 -447.491915)
			(xy 30.642777 -447.512896) (xy 30.556335 -447.525912) (xy 30.469058 -447.530849) (xy 30.381699 -447.527667)
			(xy 30.295013 -447.516391) (xy 30.209747 -447.49712) (xy 30.126637 -447.47002) (xy 30.046401 -447.435324)
			(xy 29.96973 -447.393332) (xy 29.897288 -447.344406) (xy 29.829698 -447.28897) (xy 29.767544 -447.2275)
			(xy 29.711362 -447.160527) (xy 29.661638 -447.08863) (xy 29.6188 -447.012429) (xy 29.583219 -446.932582)
			(xy 29.5552 -446.849777) (xy 29.534987 -446.76473) (xy 29.522753 -446.678173) (xy 29.518604 -446.590855)
			(xy 29.522575 -446.503529) (xy 29.534634 -446.416948) (xy 29.554674 -446.33186) (xy 29.582525 -446.248998)
			(xy 29.617944 -446.169079) (xy 29.660627 -446.092791) (xy 29.710205 -446.020793) (xy 29.76625 -445.953707)
			(xy 29.828279 -445.892111) (xy 29.895757 -445.836537) (xy 29.9681 -445.787464) (xy 30.044685 -445.745317)
			(xy 30.124851 -445.710458) (xy 30.207905 -445.683189) (xy 30.293132 -445.663745) (xy 30.379795 -445.652293)
			(xy 30.467147 -445.648933) (xy 30.554434 -445.653694) (xy 30.640902 -445.666534) (xy 30.725806 -445.687343)
			(xy 30.767274 -445.701166) (xy 30.787594 -445.708278) (xy 30.891734 -445.708278) (xy 31.05658 -445.543432)
			(xy 31.068032 -445.531297) (xy 31.084729 -445.50242) (xy 31.093376 -445.470204) (xy 31.093383 -445.436848)
			(xy 31.084749 -445.404628) (xy 31.068065 -445.375745) (xy 31.044468 -445.352168) (xy 31.01557 -445.335509)
			(xy 30.983343 -445.326903) (xy 30.966664 -445.326516) (xy 25.891236 -445.326516) (xy 25.874617 -445.327052)
			(xy 25.842508 -445.335638) (xy 25.813711 -445.352235) (xy 25.801574 -445.3636) (xy 21.99223 -449.173362)
			(xy 29.519874 -449.173362) (xy 29.519874 -449.086462) (xy 29.527892 -448.999933) (xy 29.54386 -448.914513)
			(xy 29.567641 -448.830931) (xy 29.599033 -448.749899) (xy 29.637767 -448.67211) (xy 29.683514 -448.598226)
			(xy 29.735883 -448.528879) (xy 29.794427 -448.464659) (xy 29.858647 -448.406115) (xy 29.927994 -448.353746)
			(xy 30.001878 -448.307999) (xy 30.079667 -448.269265) (xy 30.160699 -448.237873) (xy 30.244281 -448.214092)
			(xy 30.329701 -448.198124) (xy 30.41623 -448.190106) (xy 30.50313 -448.190106) (xy 30.589659 -448.198124)
			(xy 30.675079 -448.214092) (xy 30.758661 -448.237873) (xy 30.839693 -448.269265) (xy 30.917482 -448.307999)
			(xy 30.991366 -448.353746) (xy 31.060713 -448.406115) (xy 31.124933 -448.464659) (xy 31.183477 -448.528879)
			(xy 31.235846 -448.598226) (xy 31.281593 -448.67211) (xy 31.320327 -448.749899) (xy 31.351719 -448.830931)
			(xy 31.3755 -448.914513) (xy 31.391468 -448.999933) (xy 31.399486 -449.086462) (xy 31.399988 -449.129912)
			(xy 31.399486 -449.173362) (xy 34.599874 -449.173362) (xy 34.599874 -449.086462) (xy 34.607892 -448.999933)
			(xy 34.62386 -448.914513) (xy 34.647641 -448.830931) (xy 34.679033 -448.749899) (xy 34.717767 -448.67211)
			(xy 34.763514 -448.598226) (xy 34.815883 -448.528879) (xy 34.874427 -448.464659) (xy 34.938647 -448.406115)
			(xy 35.007994 -448.353746) (xy 35.081878 -448.307999) (xy 35.159667 -448.269265) (xy 35.240699 -448.237873)
			(xy 35.324281 -448.214092) (xy 35.409701 -448.198124) (xy 35.49623 -448.190106) (xy 35.58313 -448.190106)
			(xy 35.669659 -448.198124) (xy 35.755079 -448.214092) (xy 35.838661 -448.237873) (xy 35.919693 -448.269265)
			(xy 35.997482 -448.307999) (xy 36.071366 -448.353746) (xy 36.140713 -448.406115) (xy 36.204933 -448.464659)
			(xy 36.263477 -448.528879) (xy 36.315846 -448.598226) (xy 36.361593 -448.67211) (xy 36.400327 -448.749899)
			(xy 36.431719 -448.830931) (xy 36.4555 -448.914513) (xy 36.471468 -448.999933) (xy 36.479486 -449.086462)
			(xy 36.479988 -449.129912) (xy 36.479486 -449.173362) (xy 36.471468 -449.259891) (xy 36.4555 -449.345311)
			(xy 36.431719 -449.428893) (xy 36.400327 -449.509925) (xy 36.361593 -449.587714) (xy 36.315846 -449.661598)
			(xy 36.263477 -449.730945) (xy 36.204933 -449.795165) (xy 36.140713 -449.853709) (xy 36.071366 -449.906078)
			(xy 35.997482 -449.951825) (xy 35.919693 -449.990559) (xy 35.838661 -450.021951) (xy 35.755079 -450.045732)
			(xy 35.669659 -450.0617) (xy 35.58313 -450.069718) (xy 35.49623 -450.069718) (xy 35.409701 -450.0617)
			(xy 35.324281 -450.045732) (xy 35.240699 -450.021951) (xy 35.159667 -449.990559) (xy 35.081878 -449.951825)
			(xy 35.007994 -449.906078) (xy 34.938647 -449.853709) (xy 34.874427 -449.795165) (xy 34.815883 -449.730945)
			(xy 34.763514 -449.661598) (xy 34.717767 -449.587714) (xy 34.679033 -449.509925) (xy 34.647641 -449.428893)
			(xy 34.62386 -449.345311) (xy 34.607892 -449.259891) (xy 34.599874 -449.173362) (xy 31.399486 -449.173362)
			(xy 31.391468 -449.259891) (xy 31.3755 -449.345311) (xy 31.351719 -449.428893) (xy 31.320327 -449.509925)
			(xy 31.281593 -449.587714) (xy 31.235846 -449.661598) (xy 31.183477 -449.730945) (xy 31.124933 -449.795165)
			(xy 31.060713 -449.853709) (xy 30.991366 -449.906078) (xy 30.917482 -449.951825) (xy 30.839693 -449.990559)
			(xy 30.758661 -450.021951) (xy 30.675079 -450.045732) (xy 30.589659 -450.0617) (xy 30.50313 -450.069718)
			(xy 30.41623 -450.069718) (xy 30.329701 -450.0617) (xy 30.244281 -450.045732) (xy 30.160699 -450.021951)
			(xy 30.079667 -449.990559) (xy 30.001878 -449.951825) (xy 29.927994 -449.906078) (xy 29.858647 -449.853709)
			(xy 29.794427 -449.795165) (xy 29.735883 -449.730945) (xy 29.683514 -449.661598) (xy 29.637767 -449.587714)
			(xy 29.599033 -449.509925) (xy 29.567641 -449.428893) (xy 29.54386 -449.345311) (xy 29.527892 -449.259891)
			(xy 29.519874 -449.173362) (xy 21.99223 -449.173362) (xy 21.474651 -449.690998) (xy 26.886152 -449.690998)
			(xy 26.890223 -449.635376) (xy 26.902349 -449.580939) (xy 26.922272 -449.528848) (xy 26.949568 -449.480213)
			(xy 26.983654 -449.43607) (xy 27.023803 -449.397361) (xy 27.069161 -449.36491) (xy 27.118761 -449.339409)
			(xy 27.171545 -449.321402) (xy 27.226388 -449.311272) (xy 27.282122 -449.309235) (xy 27.337559 -449.315335)
			(xy 27.391516 -449.329441) (xy 27.442845 -449.351253) (xy 27.490451 -449.380307) (xy 27.533319 -449.415982)
			(xy 27.570536 -449.457519) (xy 27.601309 -449.504032) (xy 27.624981 -449.554529) (xy 27.641049 -449.607936)
			(xy 27.649169 -449.663112) (xy 27.649678 -449.690998) (xy 27.649169 -449.718884) (xy 27.641049 -449.77406)
			(xy 27.624981 -449.827467) (xy 27.601309 -449.877964) (xy 27.570536 -449.924477) (xy 27.533319 -449.966014)
			(xy 27.490451 -450.001689) (xy 27.442845 -450.030743) (xy 27.391516 -450.052555) (xy 27.337559 -450.066661)
			(xy 27.282122 -450.072761) (xy 27.226388 -450.070724) (xy 27.171545 -450.060594) (xy 27.118761 -450.042587)
			(xy 27.069161 -450.017086) (xy 27.023803 -449.984635) (xy 26.983654 -449.945926) (xy 26.949568 -449.901783)
			(xy 26.922272 -449.853148) (xy 26.902349 -449.801057) (xy 26.890223 -449.74662) (xy 26.886152 -449.690998)
			(xy 21.474651 -449.690998) (xy 21.178012 -449.98767) (xy 21.178012 -451.004686) (xy 21.177523 -451.043331)
			(xy 21.169703 -451.120225) (xy 21.154145 -451.195933) (xy 21.131007 -451.269679) (xy 21.100527 -451.340706)
			(xy 21.063018 -451.408284) (xy 21.018864 -451.471722) (xy 20.968519 -451.530366) (xy 20.9125 -451.583617)
			(xy 20.851381 -451.630927) (xy 20.785788 -451.671811) (xy 20.716397 -451.705849) (xy 20.696111 -451.713362)
			(xy 29.519874 -451.713362) (xy 29.519874 -451.626462) (xy 29.527892 -451.539933) (xy 29.54386 -451.454513)
			(xy 29.567641 -451.370931) (xy 29.599033 -451.289899) (xy 29.637767 -451.21211) (xy 29.683514 -451.138226)
			(xy 29.735883 -451.068879) (xy 29.794427 -451.004659) (xy 29.858647 -450.946115) (xy 29.927994 -450.893746)
			(xy 30.001878 -450.847999) (xy 30.079667 -450.809265) (xy 30.160699 -450.777873) (xy 30.244281 -450.754092)
			(xy 30.329701 -450.738124) (xy 30.41623 -450.730106) (xy 30.50313 -450.730106) (xy 30.589659 -450.738124)
			(xy 30.675079 -450.754092) (xy 30.758661 -450.777873) (xy 30.839693 -450.809265) (xy 30.917482 -450.847999)
			(xy 30.991366 -450.893746) (xy 31.060713 -450.946115) (xy 31.124933 -451.004659) (xy 31.183477 -451.068879)
			(xy 31.235846 -451.138226) (xy 31.281593 -451.21211) (xy 31.320327 -451.289899) (xy 31.351719 -451.370931)
			(xy 31.3755 -451.454513) (xy 31.391468 -451.539933) (xy 31.399486 -451.626462) (xy 31.399988 -451.669912)
			(xy 31.399486 -451.713362) (xy 34.599874 -451.713362) (xy 34.599874 -451.626462) (xy 34.607892 -451.539933)
			(xy 34.62386 -451.454513) (xy 34.647641 -451.370931) (xy 34.679033 -451.289899) (xy 34.717767 -451.21211)
			(xy 34.763514 -451.138226) (xy 34.815883 -451.068879) (xy 34.874427 -451.004659) (xy 34.938647 -450.946115)
			(xy 35.007994 -450.893746) (xy 35.081878 -450.847999) (xy 35.159667 -450.809265) (xy 35.240699 -450.777873)
			(xy 35.324281 -450.754092) (xy 35.409701 -450.738124) (xy 35.49623 -450.730106) (xy 35.58313 -450.730106)
			(xy 35.669659 -450.738124) (xy 35.755079 -450.754092) (xy 35.838661 -450.777873) (xy 35.919693 -450.809265)
			(xy 35.997482 -450.847999) (xy 36.071366 -450.893746) (xy 36.140713 -450.946115) (xy 36.204933 -451.004659)
			(xy 36.263477 -451.068879) (xy 36.315846 -451.138226) (xy 36.361593 -451.21211) (xy 36.400327 -451.289899)
			(xy 36.431719 -451.370931) (xy 36.442855 -451.41007) (xy 39.818564 -451.41007) (xy 39.819058 -451.352661)
			(xy 39.826902 -451.238113) (xy 39.842544 -451.124366) (xy 39.865911 -451.011952) (xy 39.896896 -450.901394)
			(xy 39.935352 -450.793209) (xy 39.981101 -450.6879) (xy 40.03393 -450.585958) (xy 40.093592 -450.487859)
			(xy 40.159809 -450.39406) (xy 40.232272 -450.304998) (xy 40.310645 -450.221089) (xy 40.39456 -450.142723)
			(xy 40.483627 -450.070266) (xy 40.577431 -450.004056) (xy 40.675535 -449.944402) (xy 40.777481 -449.891581)
			(xy 40.882793 -449.845839) (xy 40.990981 -449.807391) (xy 41.101541 -449.776415) (xy 41.213957 -449.753056)
			(xy 41.327705 -449.737423) (xy 41.442254 -449.729588) (xy 41.557072 -449.729588) (xy 41.671621 -449.737423)
			(xy 41.785369 -449.753056) (xy 41.897785 -449.776415) (xy 42.008345 -449.807391) (xy 42.116533 -449.845839)
			(xy 42.221845 -449.891581) (xy 42.323791 -449.944402) (xy 42.421895 -450.004056) (xy 42.501239 -450.06006)
			(xy 63.647577 -450.06006) (xy 63.651612 -449.984356) (xy 63.663671 -449.909511) (xy 63.683617 -449.83637)
			(xy 63.711224 -449.765765) (xy 63.74618 -449.698494) (xy 63.788088 -449.635319) (xy 63.836474 -449.576957)
			(xy 63.89079 -449.524069) (xy 63.950419 -449.477254) (xy 64.014687 -449.437042) (xy 64.082864 -449.40389)
			(xy 64.15418 -449.378172) (xy 64.227825 -449.36018) (xy 64.302965 -449.350118) (xy 64.378749 -449.348099)
			(xy 64.454319 -449.354148) (xy 64.528817 -449.368195) (xy 64.6014 -449.390081) (xy 64.671246 -449.419558)
			(xy 64.737563 -449.456293) (xy 64.799599 -449.499868) (xy 64.856652 -449.54979) (xy 64.908076 -449.605494)
			(xy 64.953287 -449.666349) (xy 64.991774 -449.731664) (xy 65.0231 -449.8007) (xy 65.04691 -449.872675)
			(xy 65.062935 -449.946773) (xy 65.070994 -450.022154) (xy 65.071498 -450.06006) (xy 66.187577 -450.06006)
			(xy 66.191612 -449.984356) (xy 66.203671 -449.909511) (xy 66.223617 -449.83637) (xy 66.251224 -449.765765)
			(xy 66.28618 -449.698494) (xy 66.328088 -449.635319) (xy 66.376474 -449.576957) (xy 66.43079 -449.524069)
			(xy 66.490419 -449.477254) (xy 66.554687 -449.437042) (xy 66.622864 -449.40389) (xy 66.69418 -449.378172)
			(xy 66.767825 -449.36018) (xy 66.842965 -449.350118) (xy 66.918749 -449.348099) (xy 66.994319 -449.354148)
			(xy 67.068817 -449.368195) (xy 67.1414 -449.390081) (xy 67.211246 -449.419558) (xy 67.277563 -449.456293)
			(xy 67.339599 -449.499868) (xy 67.396652 -449.54979) (xy 67.448076 -449.605494) (xy 67.493287 -449.666349)
			(xy 67.531774 -449.731664) (xy 67.5631 -449.8007) (xy 67.58691 -449.872675) (xy 67.602935 -449.946773)
			(xy 67.610994 -450.022154) (xy 67.611498 -450.06006) (xy 68.727577 -450.06006) (xy 68.731612 -449.984356)
			(xy 68.743671 -449.909511) (xy 68.763617 -449.83637) (xy 68.791224 -449.765765) (xy 68.82618 -449.698494)
			(xy 68.868088 -449.635319) (xy 68.916474 -449.576957) (xy 68.97079 -449.524069) (xy 69.030419 -449.477254)
			(xy 69.094687 -449.437042) (xy 69.162864 -449.40389) (xy 69.23418 -449.378172) (xy 69.307825 -449.36018)
			(xy 69.382965 -449.350118) (xy 69.458749 -449.348099) (xy 69.534319 -449.354148) (xy 69.608817 -449.368195)
			(xy 69.6814 -449.390081) (xy 69.751246 -449.419558) (xy 69.817563 -449.456293) (xy 69.879599 -449.499868)
			(xy 69.936652 -449.54979) (xy 69.988076 -449.605494) (xy 70.033287 -449.666349) (xy 70.071774 -449.731664)
			(xy 70.1031 -449.8007) (xy 70.12691 -449.872675) (xy 70.142935 -449.946773) (xy 70.150994 -450.022154)
			(xy 70.151498 -450.06006) (xy 71.267577 -450.06006) (xy 71.271612 -449.984356) (xy 71.283671 -449.909511)
			(xy 71.303617 -449.83637) (xy 71.331224 -449.765765) (xy 71.36618 -449.698494) (xy 71.408088 -449.635319)
			(xy 71.456474 -449.576957) (xy 71.51079 -449.524069) (xy 71.570419 -449.477254) (xy 71.634687 -449.437042)
			(xy 71.702864 -449.40389) (xy 71.77418 -449.378172) (xy 71.847825 -449.36018) (xy 71.922965 -449.350118)
			(xy 71.998749 -449.348099) (xy 72.074319 -449.354148) (xy 72.148817 -449.368195) (xy 72.2214 -449.390081)
			(xy 72.291246 -449.419558) (xy 72.357563 -449.456293) (xy 72.419599 -449.499868) (xy 72.476652 -449.54979)
			(xy 72.528076 -449.605494) (xy 72.573287 -449.666349) (xy 72.611774 -449.731664) (xy 72.6431 -449.8007)
			(xy 72.66691 -449.872675) (xy 72.682935 -449.946773) (xy 72.690994 -450.022154) (xy 72.691498 -450.06006)
			(xy 73.807577 -450.06006) (xy 73.811612 -449.984356) (xy 73.823671 -449.909511) (xy 73.843617 -449.83637)
			(xy 73.871224 -449.765765) (xy 73.90618 -449.698494) (xy 73.948088 -449.635319) (xy 73.996474 -449.576957)
			(xy 74.05079 -449.524069) (xy 74.110419 -449.477254) (xy 74.174687 -449.437042) (xy 74.242864 -449.40389)
			(xy 74.31418 -449.378172) (xy 74.387825 -449.36018) (xy 74.462965 -449.350118) (xy 74.538749 -449.348099)
			(xy 74.614319 -449.354148) (xy 74.688817 -449.368195) (xy 74.7614 -449.390081) (xy 74.831246 -449.419558)
			(xy 74.897563 -449.456293) (xy 74.959599 -449.499868) (xy 75.016652 -449.54979) (xy 75.068076 -449.605494)
			(xy 75.113287 -449.666349) (xy 75.151774 -449.731664) (xy 75.1831 -449.8007) (xy 75.20691 -449.872675)
			(xy 75.222935 -449.946773) (xy 75.230994 -450.022154) (xy 75.231498 -450.06006) (xy 76.347577 -450.06006)
			(xy 76.351612 -449.984356) (xy 76.363671 -449.909511) (xy 76.383617 -449.83637) (xy 76.411224 -449.765765)
			(xy 76.44618 -449.698494) (xy 76.488088 -449.635319) (xy 76.536474 -449.576957) (xy 76.59079 -449.524069)
			(xy 76.650419 -449.477254) (xy 76.714687 -449.437042) (xy 76.782864 -449.40389) (xy 76.85418 -449.378172)
			(xy 76.927825 -449.36018) (xy 77.002965 -449.350118) (xy 77.078749 -449.348099) (xy 77.154319 -449.354148)
			(xy 77.228817 -449.368195) (xy 77.3014 -449.390081) (xy 77.371246 -449.419558) (xy 77.437563 -449.456293)
			(xy 77.499599 -449.499868) (xy 77.556652 -449.54979) (xy 77.608076 -449.605494) (xy 77.653287 -449.666349)
			(xy 77.691774 -449.731664) (xy 77.7231 -449.8007) (xy 77.74691 -449.872675) (xy 77.762935 -449.946773)
			(xy 77.770994 -450.022154) (xy 77.771498 -450.06006) (xy 78.887577 -450.06006) (xy 78.891612 -449.984356)
			(xy 78.903671 -449.909511) (xy 78.923617 -449.83637) (xy 78.951224 -449.765765) (xy 78.98618 -449.698494)
			(xy 79.028088 -449.635319) (xy 79.076474 -449.576957) (xy 79.13079 -449.524069) (xy 79.190419 -449.477254)
			(xy 79.254687 -449.437042) (xy 79.322864 -449.40389) (xy 79.39418 -449.378172) (xy 79.467825 -449.36018)
			(xy 79.542965 -449.350118) (xy 79.618749 -449.348099) (xy 79.694319 -449.354148) (xy 79.768817 -449.368195)
			(xy 79.8414 -449.390081) (xy 79.911246 -449.419558) (xy 79.977563 -449.456293) (xy 80.039599 -449.499868)
			(xy 80.096652 -449.54979) (xy 80.148076 -449.605494) (xy 80.193287 -449.666349) (xy 80.231774 -449.731664)
			(xy 80.2631 -449.8007) (xy 80.28691 -449.872675) (xy 80.302935 -449.946773) (xy 80.310994 -450.022154)
			(xy 80.311498 -450.06006) (xy 80.310994 -450.097966) (xy 80.302935 -450.173347) (xy 80.28691 -450.247445)
			(xy 80.2631 -450.31942) (xy 80.231774 -450.388456) (xy 80.193287 -450.453771) (xy 80.148076 -450.514626)
			(xy 80.096652 -450.57033) (xy 80.039599 -450.620252) (xy 79.977563 -450.663827) (xy 79.911246 -450.700562)
			(xy 79.8414 -450.730039) (xy 79.768817 -450.751925) (xy 79.694319 -450.765972) (xy 79.618749 -450.772021)
			(xy 79.542965 -450.770002) (xy 79.467825 -450.75994) (xy 79.39418 -450.741948) (xy 79.322864 -450.71623)
			(xy 79.254687 -450.683078) (xy 79.190419 -450.642866) (xy 79.13079 -450.596051) (xy 79.076474 -450.543163)
			(xy 79.028088 -450.484801) (xy 78.98618 -450.421626) (xy 78.951224 -450.354355) (xy 78.923617 -450.28375)
			(xy 78.903671 -450.210609) (xy 78.891612 -450.135764) (xy 78.887577 -450.06006) (xy 77.771498 -450.06006)
			(xy 77.770994 -450.097966) (xy 77.762935 -450.173347) (xy 77.74691 -450.247445) (xy 77.7231 -450.31942)
			(xy 77.691774 -450.388456) (xy 77.653287 -450.453771) (xy 77.608076 -450.514626) (xy 77.556652 -450.57033)
			(xy 77.499599 -450.620252) (xy 77.437563 -450.663827) (xy 77.371246 -450.700562) (xy 77.3014 -450.730039)
			(xy 77.228817 -450.751925) (xy 77.154319 -450.765972) (xy 77.078749 -450.772021) (xy 77.002965 -450.770002)
			(xy 76.927825 -450.75994) (xy 76.85418 -450.741948) (xy 76.782864 -450.71623) (xy 76.714687 -450.683078)
			(xy 76.650419 -450.642866) (xy 76.59079 -450.596051) (xy 76.536474 -450.543163) (xy 76.488088 -450.484801)
			(xy 76.44618 -450.421626) (xy 76.411224 -450.354355) (xy 76.383617 -450.28375) (xy 76.363671 -450.210609)
			(xy 76.351612 -450.135764) (xy 76.347577 -450.06006) (xy 75.231498 -450.06006) (xy 75.230994 -450.097966)
			(xy 75.222935 -450.173347) (xy 75.20691 -450.247445) (xy 75.1831 -450.31942) (xy 75.151774 -450.388456)
			(xy 75.113287 -450.453771) (xy 75.068076 -450.514626) (xy 75.016652 -450.57033) (xy 74.959599 -450.620252)
			(xy 74.897563 -450.663827) (xy 74.831246 -450.700562) (xy 74.7614 -450.730039) (xy 74.688817 -450.751925)
			(xy 74.614319 -450.765972) (xy 74.538749 -450.772021) (xy 74.462965 -450.770002) (xy 74.387825 -450.75994)
			(xy 74.31418 -450.741948) (xy 74.242864 -450.71623) (xy 74.174687 -450.683078) (xy 74.110419 -450.642866)
			(xy 74.05079 -450.596051) (xy 73.996474 -450.543163) (xy 73.948088 -450.484801) (xy 73.90618 -450.421626)
			(xy 73.871224 -450.354355) (xy 73.843617 -450.28375) (xy 73.823671 -450.210609) (xy 73.811612 -450.135764)
			(xy 73.807577 -450.06006) (xy 72.691498 -450.06006) (xy 72.690994 -450.097966) (xy 72.682935 -450.173347)
			(xy 72.66691 -450.247445) (xy 72.6431 -450.31942) (xy 72.611774 -450.388456) (xy 72.573287 -450.453771)
			(xy 72.528076 -450.514626) (xy 72.476652 -450.57033) (xy 72.419599 -450.620252) (xy 72.357563 -450.663827)
			(xy 72.291246 -450.700562) (xy 72.2214 -450.730039) (xy 72.148817 -450.751925) (xy 72.074319 -450.765972)
			(xy 71.998749 -450.772021) (xy 71.922965 -450.770002) (xy 71.847825 -450.75994) (xy 71.77418 -450.741948)
			(xy 71.702864 -450.71623) (xy 71.634687 -450.683078) (xy 71.570419 -450.642866) (xy 71.51079 -450.596051)
			(xy 71.456474 -450.543163) (xy 71.408088 -450.484801) (xy 71.36618 -450.421626) (xy 71.331224 -450.354355)
			(xy 71.303617 -450.28375) (xy 71.283671 -450.210609) (xy 71.271612 -450.135764) (xy 71.267577 -450.06006)
			(xy 70.151498 -450.06006) (xy 70.150994 -450.097966) (xy 70.142935 -450.173347) (xy 70.12691 -450.247445)
			(xy 70.1031 -450.31942) (xy 70.071774 -450.388456) (xy 70.033287 -450.453771) (xy 69.988076 -450.514626)
			(xy 69.936652 -450.57033) (xy 69.879599 -450.620252) (xy 69.817563 -450.663827) (xy 69.751246 -450.700562)
			(xy 69.6814 -450.730039) (xy 69.608817 -450.751925) (xy 69.534319 -450.765972) (xy 69.458749 -450.772021)
			(xy 69.382965 -450.770002) (xy 69.307825 -450.75994) (xy 69.23418 -450.741948) (xy 69.162864 -450.71623)
			(xy 69.094687 -450.683078) (xy 69.030419 -450.642866) (xy 68.97079 -450.596051) (xy 68.916474 -450.543163)
			(xy 68.868088 -450.484801) (xy 68.82618 -450.421626) (xy 68.791224 -450.354355) (xy 68.763617 -450.28375)
			(xy 68.743671 -450.210609) (xy 68.731612 -450.135764) (xy 68.727577 -450.06006) (xy 67.611498 -450.06006)
			(xy 67.610994 -450.097966) (xy 67.602935 -450.173347) (xy 67.58691 -450.247445) (xy 67.5631 -450.31942)
			(xy 67.531774 -450.388456) (xy 67.493287 -450.453771) (xy 67.448076 -450.514626) (xy 67.396652 -450.57033)
			(xy 67.339599 -450.620252) (xy 67.277563 -450.663827) (xy 67.211246 -450.700562) (xy 67.1414 -450.730039)
			(xy 67.068817 -450.751925) (xy 66.994319 -450.765972) (xy 66.918749 -450.772021) (xy 66.842965 -450.770002)
			(xy 66.767825 -450.75994) (xy 66.69418 -450.741948) (xy 66.622864 -450.71623) (xy 66.554687 -450.683078)
			(xy 66.490419 -450.642866) (xy 66.43079 -450.596051) (xy 66.376474 -450.543163) (xy 66.328088 -450.484801)
			(xy 66.28618 -450.421626) (xy 66.251224 -450.354355) (xy 66.223617 -450.28375) (xy 66.203671 -450.210609)
			(xy 66.191612 -450.135764) (xy 66.187577 -450.06006) (xy 65.071498 -450.06006) (xy 65.070994 -450.097966)
			(xy 65.062935 -450.173347) (xy 65.04691 -450.247445) (xy 65.0231 -450.31942) (xy 64.991774 -450.388456)
			(xy 64.953287 -450.453771) (xy 64.908076 -450.514626) (xy 64.856652 -450.57033) (xy 64.799599 -450.620252)
			(xy 64.737563 -450.663827) (xy 64.671246 -450.700562) (xy 64.6014 -450.730039) (xy 64.528817 -450.751925)
			(xy 64.454319 -450.765972) (xy 64.378749 -450.772021) (xy 64.302965 -450.770002) (xy 64.227825 -450.75994)
			(xy 64.15418 -450.741948) (xy 64.082864 -450.71623) (xy 64.014687 -450.683078) (xy 63.950419 -450.642866)
			(xy 63.89079 -450.596051) (xy 63.836474 -450.543163) (xy 63.788088 -450.484801) (xy 63.74618 -450.421626)
			(xy 63.711224 -450.354355) (xy 63.683617 -450.28375) (xy 63.663671 -450.210609) (xy 63.651612 -450.135764)
			(xy 63.647577 -450.06006) (xy 42.501239 -450.06006) (xy 42.515699 -450.070266) (xy 42.604766 -450.142723)
			(xy 42.688681 -450.221089) (xy 42.767054 -450.304998) (xy 42.839517 -450.39406) (xy 42.905734 -450.487859)
			(xy 42.965396 -450.585958) (xy 43.018225 -450.6879) (xy 43.063974 -450.793209) (xy 43.10243 -450.901394)
			(xy 43.133415 -451.011952) (xy 43.156782 -451.124366) (xy 43.172424 -451.238113) (xy 43.180268 -451.352661)
			(xy 43.180762 -451.41007) (xy 43.180576 -451.443253) (xy 43.177909 -451.509567) (xy 43.175428 -451.542658)
			(xy 43.170272 -451.600942) (xy 43.152948 -451.716671) (xy 43.127616 -451.830914) (xy 43.094401 -451.943119)
			(xy 43.053462 -452.052742) (xy 43.004999 -452.159253) (xy 42.949245 -452.262135) (xy 42.886471 -452.360891)
			(xy 42.816981 -452.455042) (xy 42.741111 -452.544132) (xy 42.659229 -452.627729) (xy 42.571732 -452.70543)
			(xy 42.500813 -452.76008) (xy 63.647577 -452.76008) (xy 63.651612 -452.684376) (xy 63.663671 -452.609531)
			(xy 63.683617 -452.53639) (xy 63.711224 -452.465785) (xy 63.74618 -452.398514) (xy 63.788088 -452.335339)
			(xy 63.836474 -452.276977) (xy 63.89079 -452.224089) (xy 63.950419 -452.177274) (xy 64.014687 -452.137062)
			(xy 64.082864 -452.10391) (xy 64.15418 -452.078192) (xy 64.227825 -452.0602) (xy 64.302965 -452.050138)
			(xy 64.378749 -452.048119) (xy 64.454319 -452.054168) (xy 64.528817 -452.068215) (xy 64.6014 -452.090101)
			(xy 64.671246 -452.119578) (xy 64.737563 -452.156313) (xy 64.799599 -452.199888) (xy 64.856652 -452.24981)
			(xy 64.908076 -452.305514) (xy 64.953287 -452.366369) (xy 64.991774 -452.431684) (xy 65.0231 -452.50072)
			(xy 65.04691 -452.572695) (xy 65.062935 -452.646793) (xy 65.070994 -452.722174) (xy 65.071498 -452.76008)
			(xy 66.187577 -452.76008) (xy 66.191612 -452.684376) (xy 66.203671 -452.609531) (xy 66.223617 -452.53639)
			(xy 66.251224 -452.465785) (xy 66.28618 -452.398514) (xy 66.328088 -452.335339) (xy 66.376474 -452.276977)
			(xy 66.43079 -452.224089) (xy 66.490419 -452.177274) (xy 66.554687 -452.137062) (xy 66.622864 -452.10391)
			(xy 66.69418 -452.078192) (xy 66.767825 -452.0602) (xy 66.842965 -452.050138) (xy 66.918749 -452.048119)
			(xy 66.994319 -452.054168) (xy 67.068817 -452.068215) (xy 67.1414 -452.090101) (xy 67.211246 -452.119578)
			(xy 67.277563 -452.156313) (xy 67.339599 -452.199888) (xy 67.396652 -452.24981) (xy 67.448076 -452.305514)
			(xy 67.493287 -452.366369) (xy 67.531774 -452.431684) (xy 67.5631 -452.50072) (xy 67.58691 -452.572695)
			(xy 67.602935 -452.646793) (xy 67.610994 -452.722174) (xy 67.611498 -452.76008) (xy 68.727577 -452.76008)
			(xy 68.731612 -452.684376) (xy 68.743671 -452.609531) (xy 68.763617 -452.53639) (xy 68.791224 -452.465785)
			(xy 68.82618 -452.398514) (xy 68.868088 -452.335339) (xy 68.916474 -452.276977) (xy 68.97079 -452.224089)
			(xy 69.030419 -452.177274) (xy 69.094687 -452.137062) (xy 69.162864 -452.10391) (xy 69.23418 -452.078192)
			(xy 69.307825 -452.0602) (xy 69.382965 -452.050138) (xy 69.458749 -452.048119) (xy 69.534319 -452.054168)
			(xy 69.608817 -452.068215) (xy 69.6814 -452.090101) (xy 69.751246 -452.119578) (xy 69.817563 -452.156313)
			(xy 69.879599 -452.199888) (xy 69.936652 -452.24981) (xy 69.988076 -452.305514) (xy 70.033287 -452.366369)
			(xy 70.071774 -452.431684) (xy 70.1031 -452.50072) (xy 70.12691 -452.572695) (xy 70.142935 -452.646793)
			(xy 70.150994 -452.722174) (xy 70.151498 -452.76008) (xy 71.267577 -452.76008) (xy 71.271612 -452.684376)
			(xy 71.283671 -452.609531) (xy 71.303617 -452.53639) (xy 71.331224 -452.465785) (xy 71.36618 -452.398514)
			(xy 71.408088 -452.335339) (xy 71.456474 -452.276977) (xy 71.51079 -452.224089) (xy 71.570419 -452.177274)
			(xy 71.634687 -452.137062) (xy 71.702864 -452.10391) (xy 71.77418 -452.078192) (xy 71.847825 -452.0602)
			(xy 71.922965 -452.050138) (xy 71.998749 -452.048119) (xy 72.074319 -452.054168) (xy 72.148817 -452.068215)
			(xy 72.2214 -452.090101) (xy 72.291246 -452.119578) (xy 72.357563 -452.156313) (xy 72.419599 -452.199888)
			(xy 72.476652 -452.24981) (xy 72.528076 -452.305514) (xy 72.573287 -452.366369) (xy 72.611774 -452.431684)
			(xy 72.6431 -452.50072) (xy 72.66691 -452.572695) (xy 72.682935 -452.646793) (xy 72.690994 -452.722174)
			(xy 72.691498 -452.76008) (xy 73.807577 -452.76008) (xy 73.811612 -452.684376) (xy 73.823671 -452.609531)
			(xy 73.843617 -452.53639) (xy 73.871224 -452.465785) (xy 73.90618 -452.398514) (xy 73.948088 -452.335339)
			(xy 73.996474 -452.276977) (xy 74.05079 -452.224089) (xy 74.110419 -452.177274) (xy 74.174687 -452.137062)
			(xy 74.242864 -452.10391) (xy 74.31418 -452.078192) (xy 74.387825 -452.0602) (xy 74.462965 -452.050138)
			(xy 74.538749 -452.048119) (xy 74.614319 -452.054168) (xy 74.688817 -452.068215) (xy 74.7614 -452.090101)
			(xy 74.831246 -452.119578) (xy 74.897563 -452.156313) (xy 74.959599 -452.199888) (xy 75.016652 -452.24981)
			(xy 75.068076 -452.305514) (xy 75.113287 -452.366369) (xy 75.151774 -452.431684) (xy 75.1831 -452.50072)
			(xy 75.20691 -452.572695) (xy 75.222935 -452.646793) (xy 75.230994 -452.722174) (xy 75.231498 -452.76008)
			(xy 76.347577 -452.76008) (xy 76.351612 -452.684376) (xy 76.363671 -452.609531) (xy 76.383617 -452.53639)
			(xy 76.411224 -452.465785) (xy 76.44618 -452.398514) (xy 76.488088 -452.335339) (xy 76.536474 -452.276977)
			(xy 76.59079 -452.224089) (xy 76.650419 -452.177274) (xy 76.714687 -452.137062) (xy 76.782864 -452.10391)
			(xy 76.85418 -452.078192) (xy 76.927825 -452.0602) (xy 77.002965 -452.050138) (xy 77.078749 -452.048119)
			(xy 77.154319 -452.054168) (xy 77.228817 -452.068215) (xy 77.3014 -452.090101) (xy 77.371246 -452.119578)
			(xy 77.437563 -452.156313) (xy 77.499599 -452.199888) (xy 77.556652 -452.24981) (xy 77.608076 -452.305514)
			(xy 77.653287 -452.366369) (xy 77.691774 -452.431684) (xy 77.7231 -452.50072) (xy 77.74691 -452.572695)
			(xy 77.762935 -452.646793) (xy 77.770994 -452.722174) (xy 77.771498 -452.76008) (xy 78.887577 -452.76008)
			(xy 78.891612 -452.684376) (xy 78.903671 -452.609531) (xy 78.923617 -452.53639) (xy 78.951224 -452.465785)
			(xy 78.98618 -452.398514) (xy 79.028088 -452.335339) (xy 79.076474 -452.276977) (xy 79.13079 -452.224089)
			(xy 79.190419 -452.177274) (xy 79.254687 -452.137062) (xy 79.322864 -452.10391) (xy 79.39418 -452.078192)
			(xy 79.467825 -452.0602) (xy 79.542965 -452.050138) (xy 79.618749 -452.048119) (xy 79.694319 -452.054168)
			(xy 79.768817 -452.068215) (xy 79.8414 -452.090101) (xy 79.911246 -452.119578) (xy 79.977563 -452.156313)
			(xy 80.039599 -452.199888) (xy 80.096652 -452.24981) (xy 80.148076 -452.305514) (xy 80.193287 -452.366369)
			(xy 80.231774 -452.431684) (xy 80.2631 -452.50072) (xy 80.28691 -452.572695) (xy 80.302935 -452.646793)
			(xy 80.310994 -452.722174) (xy 80.311498 -452.76008) (xy 80.310994 -452.797986) (xy 80.302935 -452.873367)
			(xy 80.28691 -452.947465) (xy 80.2631 -453.01944) (xy 80.231774 -453.088476) (xy 80.193287 -453.153791)
			(xy 80.148076 -453.214646) (xy 80.096652 -453.27035) (xy 80.039599 -453.320272) (xy 79.977563 -453.363847)
			(xy 79.911246 -453.400582) (xy 79.8414 -453.430059) (xy 79.768817 -453.451945) (xy 79.694319 -453.465992)
			(xy 79.618749 -453.472041) (xy 79.542965 -453.470022) (xy 79.467825 -453.45996) (xy 79.39418 -453.441968)
			(xy 79.322864 -453.41625) (xy 79.254687 -453.383098) (xy 79.190419 -453.342886) (xy 79.13079 -453.296071)
			(xy 79.076474 -453.243183) (xy 79.028088 -453.184821) (xy 78.98618 -453.121646) (xy 78.951224 -453.054375)
			(xy 78.923617 -452.98377) (xy 78.903671 -452.910629) (xy 78.891612 -452.835784) (xy 78.887577 -452.76008)
			(xy 77.771498 -452.76008) (xy 77.770994 -452.797986) (xy 77.762935 -452.873367) (xy 77.74691 -452.947465)
			(xy 77.7231 -453.01944) (xy 77.691774 -453.088476) (xy 77.653287 -453.153791) (xy 77.608076 -453.214646)
			(xy 77.556652 -453.27035) (xy 77.499599 -453.320272) (xy 77.437563 -453.363847) (xy 77.371246 -453.400582)
			(xy 77.3014 -453.430059) (xy 77.228817 -453.451945) (xy 77.154319 -453.465992) (xy 77.078749 -453.472041)
			(xy 77.002965 -453.470022) (xy 76.927825 -453.45996) (xy 76.85418 -453.441968) (xy 76.782864 -453.41625)
			(xy 76.714687 -453.383098) (xy 76.650419 -453.342886) (xy 76.59079 -453.296071) (xy 76.536474 -453.243183)
			(xy 76.488088 -453.184821) (xy 76.44618 -453.121646) (xy 76.411224 -453.054375) (xy 76.383617 -452.98377)
			(xy 76.363671 -452.910629) (xy 76.351612 -452.835784) (xy 76.347577 -452.76008) (xy 75.231498 -452.76008)
			(xy 75.230994 -452.797986) (xy 75.222935 -452.873367) (xy 75.20691 -452.947465) (xy 75.1831 -453.01944)
			(xy 75.151774 -453.088476) (xy 75.113287 -453.153791) (xy 75.068076 -453.214646) (xy 75.016652 -453.27035)
			(xy 74.959599 -453.320272) (xy 74.897563 -453.363847) (xy 74.831246 -453.400582) (xy 74.7614 -453.430059)
			(xy 74.688817 -453.451945) (xy 74.614319 -453.465992) (xy 74.538749 -453.472041) (xy 74.462965 -453.470022)
			(xy 74.387825 -453.45996) (xy 74.31418 -453.441968) (xy 74.242864 -453.41625) (xy 74.174687 -453.383098)
			(xy 74.110419 -453.342886) (xy 74.05079 -453.296071) (xy 73.996474 -453.243183) (xy 73.948088 -453.184821)
			(xy 73.90618 -453.121646) (xy 73.871224 -453.054375) (xy 73.843617 -452.98377) (xy 73.823671 -452.910629)
			(xy 73.811612 -452.835784) (xy 73.807577 -452.76008) (xy 72.691498 -452.76008) (xy 72.690994 -452.797986)
			(xy 72.682935 -452.873367) (xy 72.66691 -452.947465) (xy 72.6431 -453.01944) (xy 72.611774 -453.088476)
			(xy 72.573287 -453.153791) (xy 72.528076 -453.214646) (xy 72.476652 -453.27035) (xy 72.419599 -453.320272)
			(xy 72.357563 -453.363847) (xy 72.291246 -453.400582) (xy 72.2214 -453.430059) (xy 72.148817 -453.451945)
			(xy 72.074319 -453.465992) (xy 71.998749 -453.472041) (xy 71.922965 -453.470022) (xy 71.847825 -453.45996)
			(xy 71.77418 -453.441968) (xy 71.702864 -453.41625) (xy 71.634687 -453.383098) (xy 71.570419 -453.342886)
			(xy 71.51079 -453.296071) (xy 71.456474 -453.243183) (xy 71.408088 -453.184821) (xy 71.36618 -453.121646)
			(xy 71.331224 -453.054375) (xy 71.303617 -452.98377) (xy 71.283671 -452.910629) (xy 71.271612 -452.835784)
			(xy 71.267577 -452.76008) (xy 70.151498 -452.76008) (xy 70.150994 -452.797986) (xy 70.142935 -452.873367)
			(xy 70.12691 -452.947465) (xy 70.1031 -453.01944) (xy 70.071774 -453.088476) (xy 70.033287 -453.153791)
			(xy 69.988076 -453.214646) (xy 69.936652 -453.27035) (xy 69.879599 -453.320272) (xy 69.817563 -453.363847)
			(xy 69.751246 -453.400582) (xy 69.6814 -453.430059) (xy 69.608817 -453.451945) (xy 69.534319 -453.465992)
			(xy 69.458749 -453.472041) (xy 69.382965 -453.470022) (xy 69.307825 -453.45996) (xy 69.23418 -453.441968)
			(xy 69.162864 -453.41625) (xy 69.094687 -453.383098) (xy 69.030419 -453.342886) (xy 68.97079 -453.296071)
			(xy 68.916474 -453.243183) (xy 68.868088 -453.184821) (xy 68.82618 -453.121646) (xy 68.791224 -453.054375)
			(xy 68.763617 -452.98377) (xy 68.743671 -452.910629) (xy 68.731612 -452.835784) (xy 68.727577 -452.76008)
			(xy 67.611498 -452.76008) (xy 67.610994 -452.797986) (xy 67.602935 -452.873367) (xy 67.58691 -452.947465)
			(xy 67.5631 -453.01944) (xy 67.531774 -453.088476) (xy 67.493287 -453.153791) (xy 67.448076 -453.214646)
			(xy 67.396652 -453.27035) (xy 67.339599 -453.320272) (xy 67.277563 -453.363847) (xy 67.211246 -453.400582)
			(xy 67.1414 -453.430059) (xy 67.068817 -453.451945) (xy 66.994319 -453.465992) (xy 66.918749 -453.472041)
			(xy 66.842965 -453.470022) (xy 66.767825 -453.45996) (xy 66.69418 -453.441968) (xy 66.622864 -453.41625)
			(xy 66.554687 -453.383098) (xy 66.490419 -453.342886) (xy 66.43079 -453.296071) (xy 66.376474 -453.243183)
			(xy 66.328088 -453.184821) (xy 66.28618 -453.121646) (xy 66.251224 -453.054375) (xy 66.223617 -452.98377)
			(xy 66.203671 -452.910629) (xy 66.191612 -452.835784) (xy 66.187577 -452.76008) (xy 65.071498 -452.76008)
			(xy 65.070994 -452.797986) (xy 65.062935 -452.873367) (xy 65.04691 -452.947465) (xy 65.0231 -453.01944)
			(xy 64.991774 -453.088476) (xy 64.953287 -453.153791) (xy 64.908076 -453.214646) (xy 64.856652 -453.27035)
			(xy 64.799599 -453.320272) (xy 64.737563 -453.363847) (xy 64.671246 -453.400582) (xy 64.6014 -453.430059)
			(xy 64.528817 -453.451945) (xy 64.454319 -453.465992) (xy 64.378749 -453.472041) (xy 64.302965 -453.470022)
			(xy 64.227825 -453.45996) (xy 64.15418 -453.441968) (xy 64.082864 -453.41625) (xy 64.014687 -453.383098)
			(xy 63.950419 -453.342886) (xy 63.89079 -453.296071) (xy 63.836474 -453.243183) (xy 63.788088 -453.184821)
			(xy 63.74618 -453.121646) (xy 63.711224 -453.054375) (xy 63.683617 -452.98377) (xy 63.663671 -452.910629)
			(xy 63.651612 -452.835784) (xy 63.647577 -452.76008) (xy 42.500813 -452.76008) (xy 42.479042 -452.776857)
			(xy 42.381609 -452.841665) (xy 42.279905 -452.89954) (xy 42.174422 -452.950202) (xy 42.065671 -452.993404)
			(xy 41.954179 -453.028939) (xy 41.840485 -453.056634) (xy 41.725141 -453.076354) (xy 41.608704 -453.088005)
			(xy 41.491739 -453.09153) (xy 41.374812 -453.086912) (xy 41.258489 -453.074173) (xy 41.143334 -453.053375)
			(xy 41.029905 -453.024618) (xy 40.91875 -452.988042) (xy 40.810407 -452.943825) (xy 40.705403 -452.892179)
			(xy 40.604244 -452.833356) (xy 40.507421 -452.76764) (xy 40.415403 -452.695349) (xy 40.328636 -452.616834)
			(xy 40.247539 -452.532474) (xy 40.172506 -452.442679) (xy 40.103899 -452.347883) (xy 40.042051 -452.248544)
			(xy 39.987262 -452.145145) (xy 39.939796 -452.038186) (xy 39.899884 -451.928185) (xy 39.86772 -451.815674)
			(xy 39.843457 -451.701199) (xy 39.827215 -451.585313) (xy 39.819072 -451.468579) (xy 39.818564 -451.41007)
			(xy 36.442855 -451.41007) (xy 36.4555 -451.454513) (xy 36.471468 -451.539933) (xy 36.479486 -451.626462)
			(xy 36.479988 -451.669912) (xy 36.479486 -451.713362) (xy 36.471468 -451.799891) (xy 36.4555 -451.885311)
			(xy 36.431719 -451.968893) (xy 36.400327 -452.049925) (xy 36.361593 -452.127714) (xy 36.315846 -452.201598)
			(xy 36.263477 -452.270945) (xy 36.204933 -452.335165) (xy 36.140713 -452.393709) (xy 36.071366 -452.446078)
			(xy 35.997482 -452.491825) (xy 35.919693 -452.530559) (xy 35.838661 -452.561951) (xy 35.755079 -452.585732)
			(xy 35.669659 -452.6017) (xy 35.58313 -452.609718) (xy 35.49623 -452.609718) (xy 35.409701 -452.6017)
			(xy 35.324281 -452.585732) (xy 35.240699 -452.561951) (xy 35.159667 -452.530559) (xy 35.081878 -452.491825)
			(xy 35.007994 -452.446078) (xy 34.938647 -452.393709) (xy 34.874427 -452.335165) (xy 34.815883 -452.270945)
			(xy 34.763514 -452.201598) (xy 34.717767 -452.127714) (xy 34.679033 -452.049925) (xy 34.647641 -451.968893)
			(xy 34.62386 -451.885311) (xy 34.607892 -451.799891) (xy 34.599874 -451.713362) (xy 31.399486 -451.713362)
			(xy 31.391468 -451.799891) (xy 31.3755 -451.885311) (xy 31.351719 -451.968893) (xy 31.320327 -452.049925)
			(xy 31.281593 -452.127714) (xy 31.235846 -452.201598) (xy 31.183477 -452.270945) (xy 31.124933 -452.335165)
			(xy 31.060713 -452.393709) (xy 30.991366 -452.446078) (xy 30.917482 -452.491825) (xy 30.839693 -452.530559)
			(xy 30.758661 -452.561951) (xy 30.675079 -452.585732) (xy 30.589659 -452.6017) (xy 30.50313 -452.609718)
			(xy 30.41623 -452.609718) (xy 30.329701 -452.6017) (xy 30.244281 -452.585732) (xy 30.160699 -452.561951)
			(xy 30.079667 -452.530559) (xy 30.001878 -452.491825) (xy 29.927994 -452.446078) (xy 29.858647 -452.393709)
			(xy 29.794427 -452.335165) (xy 29.735883 -452.270945) (xy 29.683514 -452.201598) (xy 29.637767 -452.127714)
			(xy 29.599033 -452.049925) (xy 29.567641 -451.968893) (xy 29.54386 -451.885311) (xy 29.527892 -451.799891)
			(xy 29.519874 -451.713362) (xy 20.696111 -451.713362) (xy 20.643917 -451.732692) (xy 20.569094 -451.752065)
			(xy 20.492695 -451.763769) (xy 20.415504 -451.767684) (xy 20.338313 -451.763769) (xy 20.261914 -451.752065)
			(xy 20.187091 -451.732692) (xy 20.114611 -451.705849) (xy 20.04522 -451.671811) (xy 19.979627 -451.630927)
			(xy 19.918508 -451.583617) (xy 19.862489 -451.530366) (xy 19.812144 -451.471722) (xy 19.76799 -451.408284)
			(xy 19.730481 -451.340706) (xy 19.700001 -451.269679) (xy 19.676863 -451.195933) (xy 19.661305 -451.120225)
			(xy 19.653485 -451.043331) (xy 19.652996 -451.004686) (xy 19.652996 -449.215764) (xy 19.653555 -449.175541)
			(xy 19.662102 -449.095548) (xy 19.679023 -449.016901) (xy 19.691096 -448.978528) (xy 19.702608 -448.944679)
			(xy 19.731127 -448.879112) (xy 19.765664 -448.816505) (xy 19.805916 -448.75741) (xy 19.851527 -448.702346)
			(xy 19.876516 -448.676776) (xy 24.751284 -443.802008) (xy 29.473144 -443.802008) (xy 29.495257 -443.800303)
			(xy 29.538442 -443.790213) (xy 29.579222 -443.772787) (xy 29.616364 -443.748554) (xy 29.64874 -443.718248)
			(xy 29.675371 -443.682787) (xy 29.69545 -443.643245) (xy 29.708367 -443.60082) (xy 29.713733 -443.556799)
			(xy 29.711384 -443.512513) (xy 29.701392 -443.469306) (xy 29.684058 -443.428486) (xy 29.659909 -443.39129)
			(xy 29.645102 -443.37478) (xy 25.606756 -439.33618) (xy 25.606756 -380.947168) (xy 14.417548 -369.75796)
			(xy 14.417548 -333.03464) (xy 14.641068 -332.81112) (xy 14.641068 -331.73289) (xy 13.980668 -331.07249)
			(xy 13.980668 -322.022978) (xy 13.980125 -322.006362) (xy 13.971526 -321.974263) (xy 13.954919 -321.945478)
			(xy 13.943584 -321.933316) (xy 8.99795 -316.987936) (xy 7.069328 -316.987936) (xy 7.054238 -316.988338)
			(xy 7.024891 -316.995377) (xy 6.998019 -317.009115) (xy 6.975129 -317.028782) (xy 6.96595 -317.040768)
			(xy 6.944787 -317.069373) (xy 6.897071 -317.122162) (xy 6.843756 -317.169291) (xy 6.785511 -317.21017)
			(xy 6.723064 -317.244286) (xy 6.657197 -317.271214) (xy 6.588735 -317.290615) (xy 6.518534 -317.302248)
			(xy 6.447472 -317.305966) (xy 6.37644 -317.301723) (xy 6.306327 -317.289573) (xy 6.238009 -317.269666)
			(xy 6.172343 -317.242253) (xy 6.11015 -317.207677) (xy 6.052208 -317.166369) (xy 5.999243 -317.118848)
			(xy 5.951917 -317.065708) (xy 5.910824 -317.007615) (xy 5.876477 -316.945294) (xy 5.849306 -316.879527)
			(xy 5.829652 -316.811137) (xy 5.81776 -316.740979) (xy 5.81378 -316.669932) (xy 5.81776 -316.598884)
			(xy 5.829651 -316.528727) (xy 5.849305 -316.460336) (xy 5.876476 -316.394569) (xy 5.910822 -316.332248)
			(xy 5.951915 -316.274154) (xy 5.99924 -316.221014) (xy 6.052205 -316.173493) (xy 6.110147 -316.132185)
			(xy 6.17234 -316.097608) (xy 6.238006 -316.070195) (xy 6.306323 -316.050288) (xy 6.376437 -316.038137)
			(xy 6.447469 -316.033894) (xy 6.51853 -316.037612) (xy 6.588732 -316.049244) (xy 6.657194 -316.068645)
			(xy 6.723061 -316.095572) (xy 6.785508 -316.129689) (xy 6.843754 -316.170567) (xy 6.897068 -316.217695)
			(xy 6.944785 -316.270484) (xy 6.96595 -316.299088) (xy 6.97511 -316.31109) (xy 6.998002 -316.330764)
			(xy 7.02488 -316.3445) (xy 7.054235 -316.351526) (xy 7.069328 -316.35192) (xy 7.670038 -316.35192)
			(xy 7.691797 -316.351478) (xy 7.73468 -316.344072) (xy 7.775674 -316.329465) (xy 7.813578 -316.308085)
			(xy 7.847284 -316.280559) (xy 7.875806 -316.24769) (xy 7.898308 -316.210441) (xy 7.914133 -316.169902)
			(xy 7.922817 -316.127259) (xy 7.924106 -316.08376) (xy 7.917963 -316.040678) (xy 7.904567 -315.999273)
			(xy 7.894828 -315.97981) (xy 7.877725 -315.948156) (xy 7.849967 -315.881775) (xy 7.829882 -315.812683)
			(xy 7.817727 -315.741766) (xy 7.813658 -315.66993) (xy 7.817727 -315.598094) (xy 7.829882 -315.527177)
			(xy 7.849967 -315.458085) (xy 7.877725 -315.391704) (xy 7.894828 -315.36005) (xy 7.904548 -315.340583)
			(xy 7.917923 -315.299181) (xy 7.92405 -315.256106) (xy 7.922749 -315.212617) (xy 7.91406 -315.169984)
			(xy 7.898235 -315.129456) (xy 7.875738 -315.092215) (xy 7.847226 -315.05935) (xy 7.813532 -315.031823)
			(xy 7.775642 -315.010437) (xy 7.734663 -314.995819) (xy 7.691792 -314.988394) (xy 7.670038 -314.98794)
			(xy 7.069328 -314.98794) (xy 6.967474 -315.040264) (xy 6.950202 -315.062108) (xy 6.945884 -315.067696)
			(xy 6.923814 -315.094484) (xy 6.874756 -315.143585) (xy 6.820638 -315.187048) (xy 6.762106 -315.224353)
			(xy 6.699857 -315.255056) (xy 6.634631 -315.278792) (xy 6.567208 -315.295277) (xy 6.498389 -315.304315)
			(xy 6.428995 -315.305799) (xy 6.359853 -315.29971) (xy 6.291786 -315.286122) (xy 6.225606 -315.265196)
			(xy 6.162101 -315.237181) (xy 6.102028 -315.202412) (xy 6.046102 -315.161303) (xy 5.99499 -315.114342)
			(xy 5.971794 -315.088524) (xy 5.947745 -315.060287) (xy 5.905687 -314.99919) (xy 5.87103 -314.933611)
			(xy 5.844246 -314.864442) (xy 5.825699 -314.792625) (xy 5.81564 -314.719136) (xy 5.814208 -314.644977)
			(xy 5.821422 -314.571155) (xy 5.828792 -314.534804) (xy 5.830062 -314.528962) (xy 5.834407 -314.506686)
			(xy 5.836045 -314.461335) (xy 5.829603 -314.416415) (xy 5.815286 -314.373352) (xy 5.793549 -314.333516)
			(xy 5.765083 -314.298174) (xy 5.730793 -314.268449) (xy 5.691769 -314.245287) (xy 5.649253 -314.229422)
			(xy 5.604594 -314.22136) (xy 5.581904 -314.22086) (xy 4.817872 -314.22086) (xy 4.795185 -314.221363)
			(xy 4.750534 -314.229426) (xy 4.708025 -314.245292) (xy 4.669009 -314.268456) (xy 4.634728 -314.29818)
			(xy 4.606271 -314.333521) (xy 4.584544 -314.373354) (xy 4.570236 -314.416413) (xy 4.563804 -314.461328)
			(xy 4.565451 -314.506672) (xy 4.569714 -314.528962) (xy 4.577134 -314.563836) (xy 4.585068 -314.634695)
			(xy 4.585022 -314.705997) (xy 4.576995 -314.776847) (xy 4.56109 -314.846352) (xy 4.537506 -314.913641)
			(xy 4.506539 -314.977868) (xy 4.468579 -315.038225) (xy 4.424102 -315.093955) (xy 4.373667 -315.144356)
			(xy 4.317908 -315.188797) (xy 4.257526 -315.226718) (xy 4.19328 -315.257643) (xy 4.125975 -315.281183)
			(xy 4.056459 -315.297043) (xy 3.985605 -315.305023) (xy 3.914303 -315.305023) (xy 3.843449 -315.297043)
			(xy 3.773933 -315.281183) (xy 3.706628 -315.257643) (xy 3.642382 -315.226718) (xy 3.582 -315.188797)
			(xy 3.526241 -315.144356) (xy 3.475806 -315.093955) (xy 3.431329 -315.038225) (xy 3.393369 -314.977868)
			(xy 3.362402 -314.913641) (xy 3.338818 -314.846352) (xy 3.322913 -314.776847) (xy 3.314886 -314.705997)
			(xy 3.31484 -314.634695) (xy 3.322774 -314.563836) (xy 3.330194 -314.528962) (xy 3.334538 -314.506686)
			(xy 3.336177 -314.461335) (xy 3.329735 -314.416414) (xy 3.315418 -314.373352) (xy 3.293681 -314.333516)
			(xy 3.265215 -314.298174) (xy 3.230925 -314.268448) (xy 3.191902 -314.245285) (xy 3.149385 -314.229421)
			(xy 3.104726 -314.221359) (xy 3.082036 -314.22086) (xy 2.26822 -314.22086) (xy 2.240788 -314.23483)
			(xy 2.208446 -314.250924) (xy 2.140889 -314.276518) (xy 2.070865 -314.294287) (xy 1.999279 -314.304002)
			(xy 1.927052 -314.305537) (xy 1.855117 -314.298873) (xy 1.819656 -314.29198) (xy 1.797849 -314.288922)
			(xy 1.753823 -314.289477) (xy 1.710551 -314.297611) (xy 1.669329 -314.313083) (xy 1.63139 -314.335428)
			(xy 1.59787 -314.363978) (xy 1.569773 -314.397877) (xy 1.54794 -314.436113) (xy 1.533024 -314.477539)
			(xy 1.525471 -314.520917) (xy 1.525016 -314.542932) (xy 1.525016 -314.796932) (xy 1.525461 -314.818949)
			(xy 1.533006 -314.862332) (xy 1.547917 -314.903765) (xy 1.569749 -314.942006) (xy 1.597847 -314.97591)
			(xy 1.631369 -315.004462) (xy 1.669313 -315.026807) (xy 1.71054 -315.042275) (xy 1.753818 -315.050403)
			(xy 1.797848 -315.050948) (xy 1.819656 -315.047884) (xy 1.854312 -315.041115) (xy 1.924607 -315.034388)
			(xy 1.995215 -315.035494) (xy 2.065265 -315.044421) (xy 2.133893 -315.061058) (xy 2.200254 -315.0852)
			(xy 2.26353 -315.116549) (xy 2.322941 -315.154719) (xy 2.377755 -315.199241) (xy 2.427295 -315.249563)
			(xy 2.470952 -315.305068) (xy 2.508187 -315.365069) (xy 2.538541 -315.428829) (xy 2.56164 -315.49556)
			(xy 2.577199 -315.564441) (xy 2.585027 -315.634622) (xy 2.585027 -315.705238) (xy 2.577199 -315.775419)
			(xy 2.56164 -315.8443) (xy 2.538541 -315.911031) (xy 2.508187 -315.974791) (xy 2.470952 -316.034792)
			(xy 2.427295 -316.090297) (xy 2.377755 -316.140619) (xy 2.322941 -316.185141) (xy 2.26353 -316.223311)
			(xy 2.200254 -316.25466) (xy 2.133893 -316.278802) (xy 2.065265 -316.295439) (xy 1.995215 -316.304366)
			(xy 1.924607 -316.305472) (xy 1.854312 -316.298745) (xy 1.819656 -316.291976) (xy 1.797849 -316.288918)
			(xy 1.753823 -316.289473) (xy 1.71055 -316.297607) (xy 1.669328 -316.313079) (xy 1.631389 -316.335424)
			(xy 1.597869 -316.363973) (xy 1.569772 -316.397873) (xy 1.547938 -316.436109) (xy 1.533021 -316.477535)
			(xy 1.525467 -316.520913) (xy 1.525016 -316.542928) (xy 1.525016 -316.796928) (xy 1.525462 -316.818945)
			(xy 1.533007 -316.862327) (xy 1.547919 -316.903758) (xy 1.569751 -316.941998) (xy 1.597849 -316.975902)
			(xy 1.631371 -317.004453) (xy 1.669314 -317.026797) (xy 1.710541 -317.042265) (xy 1.753818 -317.050393)
			(xy 1.797848 -317.050938) (xy 1.819656 -317.04788) (xy 1.854312 -317.041111) (xy 1.924607 -317.034384)
			(xy 1.995215 -317.035491) (xy 2.065264 -317.044418) (xy 2.133892 -317.061055) (xy 2.200253 -317.085197)
			(xy 2.263529 -317.116546) (xy 2.32294 -317.154716) (xy 2.377753 -317.199237) (xy 2.427293 -317.24956)
			(xy 2.47095 -317.305065) (xy 2.508184 -317.365066) (xy 2.538538 -317.428826) (xy 2.561637 -317.495557)
			(xy 2.577197 -317.564437) (xy 2.585025 -317.634618) (xy 2.585025 -317.705234) (xy 2.577197 -317.775415)
			(xy 2.561637 -317.844295) (xy 2.538538 -317.911026) (xy 2.508184 -317.974786) (xy 2.47095 -318.034787)
			(xy 2.427293 -318.090292) (xy 2.377753 -318.140615) (xy 2.32294 -318.185136) (xy 2.263529 -318.223306)
			(xy 2.200253 -318.254655) (xy 2.133892 -318.278797) (xy 2.065264 -318.295434) (xy 1.995215 -318.304361)
			(xy 1.924607 -318.305468) (xy 1.854312 -318.298741) (xy 1.819656 -318.291972) (xy 1.797849 -318.288914)
			(xy 1.753823 -318.289469) (xy 1.710551 -318.297603) (xy 1.669329 -318.313075) (xy 1.63139 -318.33542)
			(xy 1.597871 -318.36397) (xy 1.569774 -318.39787) (xy 1.547941 -318.436105) (xy 1.533025 -318.477531)
			(xy 1.525473 -318.520909) (xy 1.525016 -318.542924) (xy 1.525016 -318.705585) (xy 3.314946 -318.705585)
			(xy 3.314946 -318.634263) (xy 3.322932 -318.563389) (xy 3.338802 -318.493854) (xy 3.362359 -318.426534)
			(xy 3.393304 -318.362275) (xy 3.43125 -318.301884) (xy 3.475719 -318.246122) (xy 3.526152 -318.195689)
			(xy 3.581914 -318.15122) (xy 3.642305 -318.113274) (xy 3.706564 -318.082329) (xy 3.773884 -318.058772)
			(xy 3.843419 -318.042902) (xy 3.914293 -318.034916) (xy 3.985615 -318.034916) (xy 4.056489 -318.042902)
			(xy 4.126024 -318.058772) (xy 4.193344 -318.082329) (xy 4.257603 -318.113274) (xy 4.317994 -318.15122)
			(xy 4.373756 -318.195689) (xy 4.424189 -318.246122) (xy 4.468658 -318.301884) (xy 4.506604 -318.362275)
			(xy 4.537549 -318.426534) (xy 4.561106 -318.493854) (xy 4.576976 -318.563389) (xy 4.584962 -318.634263)
			(xy 4.585462 -318.669924) (xy 4.584962 -318.705585) (xy 5.814814 -318.705585) (xy 5.814814 -318.634263)
			(xy 5.8228 -318.563389) (xy 5.83867 -318.493854) (xy 5.862227 -318.426534) (xy 5.893172 -318.362275)
			(xy 5.931118 -318.301884) (xy 5.975587 -318.246122) (xy 6.02602 -318.195689) (xy 6.081782 -318.15122)
			(xy 6.142173 -318.113274) (xy 6.206432 -318.082329) (xy 6.273752 -318.058772) (xy 6.343287 -318.042902)
			(xy 6.414161 -318.034916) (xy 6.485483 -318.034916) (xy 6.556357 -318.042902) (xy 6.625892 -318.058772)
			(xy 6.693212 -318.082329) (xy 6.757471 -318.113274) (xy 6.817862 -318.15122) (xy 6.873624 -318.195689)
			(xy 6.924057 -318.246122) (xy 6.968526 -318.301884) (xy 7.006472 -318.362275) (xy 7.037417 -318.426534)
			(xy 7.060974 -318.493854) (xy 7.076844 -318.563389) (xy 7.08483 -318.634263) (xy 7.08533 -318.669924)
			(xy 7.08483 -318.705585) (xy 7.076844 -318.776459) (xy 7.060974 -318.845994) (xy 7.037417 -318.913314)
			(xy 7.006472 -318.977573) (xy 6.968526 -319.037964) (xy 6.924057 -319.093726) (xy 6.873624 -319.144159)
			(xy 6.817862 -319.188628) (xy 6.757471 -319.226574) (xy 6.693212 -319.257519) (xy 6.625892 -319.281076)
			(xy 6.556357 -319.296946) (xy 6.485483 -319.304932) (xy 6.414161 -319.304932) (xy 6.343287 -319.296946)
			(xy 6.273752 -319.281076) (xy 6.206432 -319.257519) (xy 6.142173 -319.226574) (xy 6.081782 -319.188628)
			(xy 6.02602 -319.144159) (xy 5.975587 -319.093726) (xy 5.931118 -319.037964) (xy 5.893172 -318.977573)
			(xy 5.862227 -318.913314) (xy 5.83867 -318.845994) (xy 5.8228 -318.776459) (xy 5.814814 -318.705585)
			(xy 4.584962 -318.705585) (xy 4.576976 -318.776459) (xy 4.561106 -318.845994) (xy 4.537549 -318.913314)
			(xy 4.506604 -318.977573) (xy 4.468658 -319.037964) (xy 4.424189 -319.093726) (xy 4.373756 -319.144159)
			(xy 4.317994 -319.188628) (xy 4.257603 -319.226574) (xy 4.193344 -319.257519) (xy 4.126024 -319.281076)
			(xy 4.056489 -319.296946) (xy 3.985615 -319.304932) (xy 3.914293 -319.304932) (xy 3.843419 -319.296946)
			(xy 3.773884 -319.281076) (xy 3.706564 -319.257519) (xy 3.642305 -319.226574) (xy 3.581914 -319.188628)
			(xy 3.526152 -319.144159) (xy 3.475719 -319.093726) (xy 3.43125 -319.037964) (xy 3.393304 -318.977573)
			(xy 3.362359 -318.913314) (xy 3.338802 -318.845994) (xy 3.322932 -318.776459) (xy 3.314946 -318.705585)
			(xy 1.525016 -318.705585) (xy 1.525016 -318.796924) (xy 1.525461 -318.818941) (xy 1.533006 -318.862324)
			(xy 1.547918 -318.903756) (xy 1.569749 -318.941997) (xy 1.597847 -318.9759) (xy 1.63137 -319.004452)
			(xy 1.669313 -319.026797) (xy 1.710541 -319.042265) (xy 1.753818 -319.050393) (xy 1.797848 -319.050938)
			(xy 1.819656 -319.047876) (xy 1.854312 -319.041107) (xy 1.924607 -319.03438) (xy 1.995214 -319.035486)
			(xy 2.065264 -319.044413) (xy 2.133892 -319.061049) (xy 2.200253 -319.085191) (xy 2.263529 -319.116541)
			(xy 2.32294 -319.154711) (xy 2.377753 -319.199232) (xy 2.427293 -319.249554) (xy 2.47095 -319.305059)
			(xy 2.508185 -319.36506) (xy 2.538539 -319.428819) (xy 2.561638 -319.49555) (xy 2.577197 -319.564431)
			(xy 2.585025 -319.634612) (xy 2.585025 -319.705228) (xy 2.584985 -319.705583) (xy 7.81481 -319.705583)
			(xy 7.81481 -319.634261) (xy 7.822796 -319.563387) (xy 7.838666 -319.493852) (xy 7.862223 -319.426532)
			(xy 7.893168 -319.362273) (xy 7.931114 -319.301882) (xy 7.975583 -319.24612) (xy 8.026016 -319.195687)
			(xy 8.081778 -319.151218) (xy 8.142169 -319.113272) (xy 8.206428 -319.082327) (xy 8.273748 -319.05877)
			(xy 8.343283 -319.0429) (xy 8.414157 -319.034914) (xy 8.485479 -319.034914) (xy 8.556353 -319.0429)
			(xy 8.625888 -319.05877) (xy 8.693208 -319.082327) (xy 8.757467 -319.113272) (xy 8.817858 -319.151218)
			(xy 8.87362 -319.195687) (xy 8.924053 -319.24612) (xy 8.968522 -319.301882) (xy 9.006468 -319.362273)
			(xy 9.037413 -319.426532) (xy 9.06097 -319.493852) (xy 9.07684 -319.563387) (xy 9.084826 -319.634261)
			(xy 9.085326 -319.669922) (xy 9.084826 -319.705583) (xy 9.07684 -319.776457) (xy 9.06097 -319.845992)
			(xy 9.037413 -319.913312) (xy 9.006468 -319.977571) (xy 8.968522 -320.037962) (xy 8.924053 -320.093724)
			(xy 8.87362 -320.144157) (xy 8.817858 -320.188626) (xy 8.757467 -320.226572) (xy 8.693208 -320.257517)
			(xy 8.625888 -320.281074) (xy 8.556353 -320.296944) (xy 8.485479 -320.30493) (xy 8.414157 -320.30493)
			(xy 8.343283 -320.296944) (xy 8.273748 -320.281074) (xy 8.206428 -320.257517) (xy 8.142169 -320.226572)
			(xy 8.081778 -320.188626) (xy 8.026016 -320.144157) (xy 7.975583 -320.093724) (xy 7.931114 -320.037962)
			(xy 7.893168 -319.977571) (xy 7.862223 -319.913312) (xy 7.838666 -319.845992) (xy 7.822796 -319.776457)
			(xy 7.81481 -319.705583) (xy 2.584985 -319.705583) (xy 2.577197 -319.775408) (xy 2.561638 -319.844289)
			(xy 2.538539 -319.91102) (xy 2.508185 -319.974779) (xy 2.47095 -320.034781) (xy 2.427294 -320.090285)
			(xy 2.377754 -320.140608) (xy 2.32294 -320.185129) (xy 2.26353 -320.223299) (xy 2.200254 -320.254648)
			(xy 2.133893 -320.27879) (xy 2.065265 -320.295427) (xy 1.995215 -320.304354) (xy 1.924608 -320.30546)
			(xy 1.854313 -320.298733) (xy 1.819656 -320.291968) (xy 1.797849 -320.28891) (xy 1.753823 -320.289465)
			(xy 1.710551 -320.297599) (xy 1.669328 -320.313071) (xy 1.631389 -320.335416) (xy 1.59787 -320.363966)
			(xy 1.569773 -320.397865) (xy 1.547939 -320.436101) (xy 1.533022 -320.477527) (xy 1.525469 -320.520905)
			(xy 1.525016 -320.54292) (xy 1.525016 -320.705581) (xy 3.314946 -320.705581) (xy 3.314946 -320.634259)
			(xy 3.322932 -320.563385) (xy 3.338802 -320.49385) (xy 3.362359 -320.42653) (xy 3.393304 -320.362271)
			(xy 3.43125 -320.30188) (xy 3.475719 -320.246118) (xy 3.526152 -320.195685) (xy 3.581914 -320.151216)
			(xy 3.642305 -320.11327) (xy 3.706564 -320.082325) (xy 3.773884 -320.058768) (xy 3.843419 -320.042898)
			(xy 3.914293 -320.034912) (xy 3.985615 -320.034912) (xy 4.056489 -320.042898) (xy 4.126024 -320.058768)
			(xy 4.193344 -320.082325) (xy 4.257603 -320.11327) (xy 4.317994 -320.151216) (xy 4.373756 -320.195685)
			(xy 4.424189 -320.246118) (xy 4.468658 -320.30188) (xy 4.506604 -320.362271) (xy 4.537549 -320.42653)
			(xy 4.561106 -320.49385) (xy 4.576976 -320.563385) (xy 4.584962 -320.634259) (xy 4.585462 -320.66992)
			(xy 4.584962 -320.705581) (xy 4.576976 -320.776455) (xy 4.561106 -320.84599) (xy 4.537549 -320.91331)
			(xy 4.506604 -320.977569) (xy 4.468658 -321.03796) (xy 4.424189 -321.093722) (xy 4.373756 -321.144155)
			(xy 4.317994 -321.188624) (xy 4.257603 -321.22657) (xy 4.193344 -321.257515) (xy 4.126024 -321.281072)
			(xy 4.056489 -321.296942) (xy 3.985615 -321.304928) (xy 3.914293 -321.304928) (xy 3.843419 -321.296942)
			(xy 3.773884 -321.281072) (xy 3.706564 -321.257515) (xy 3.642305 -321.22657) (xy 3.581914 -321.188624)
			(xy 3.526152 -321.144155) (xy 3.475719 -321.093722) (xy 3.43125 -321.03796) (xy 3.393304 -320.977569)
			(xy 3.362359 -320.91331) (xy 3.338802 -320.84599) (xy 3.322932 -320.776455) (xy 3.314946 -320.705581)
			(xy 1.525016 -320.705581) (xy 1.525016 -321.705579) (xy 7.81481 -321.705579) (xy 7.81481 -321.634257)
			(xy 7.822796 -321.563383) (xy 7.838666 -321.493848) (xy 7.862223 -321.426528) (xy 7.893168 -321.362269)
			(xy 7.931114 -321.301878) (xy 7.975583 -321.246116) (xy 8.026016 -321.195683) (xy 8.081778 -321.151214)
			(xy 8.142169 -321.113268) (xy 8.206428 -321.082323) (xy 8.273748 -321.058766) (xy 8.343283 -321.042896)
			(xy 8.414157 -321.03491) (xy 8.485479 -321.03491) (xy 8.556353 -321.042896) (xy 8.625888 -321.058766)
			(xy 8.693208 -321.082323) (xy 8.757467 -321.113268) (xy 8.817858 -321.151214) (xy 8.87362 -321.195683)
			(xy 8.924053 -321.246116) (xy 8.968522 -321.301878) (xy 9.006468 -321.362269) (xy 9.037413 -321.426528)
			(xy 9.06097 -321.493848) (xy 9.07684 -321.563383) (xy 9.084826 -321.634257) (xy 9.085326 -321.669918)
			(xy 9.084826 -321.705579) (xy 9.07684 -321.776453) (xy 9.06097 -321.845988) (xy 9.037413 -321.913308)
			(xy 9.006468 -321.977567) (xy 8.968522 -322.037958) (xy 8.924053 -322.09372) (xy 8.87362 -322.144153)
			(xy 8.817858 -322.188622) (xy 8.757467 -322.226568) (xy 8.693208 -322.257513) (xy 8.625888 -322.28107)
			(xy 8.556353 -322.29694) (xy 8.485479 -322.304926) (xy 8.414157 -322.304926) (xy 8.343283 -322.29694)
			(xy 8.273748 -322.28107) (xy 8.206428 -322.257513) (xy 8.142169 -322.226568) (xy 8.081778 -322.188622)
			(xy 8.026016 -322.144153) (xy 7.975583 -322.09372) (xy 7.931114 -322.037958) (xy 7.893168 -321.977567)
			(xy 7.862223 -321.913308) (xy 7.838666 -321.845988) (xy 7.822796 -321.776453) (xy 7.81481 -321.705579)
			(xy 1.525016 -321.705579) (xy 1.525016 -322.705577) (xy 3.314946 -322.705577) (xy 3.314946 -322.634255)
			(xy 3.322932 -322.563381) (xy 3.338802 -322.493846) (xy 3.362359 -322.426526) (xy 3.393304 -322.362267)
			(xy 3.43125 -322.301876) (xy 3.475719 -322.246114) (xy 3.526152 -322.195681) (xy 3.581914 -322.151212)
			(xy 3.642305 -322.113266) (xy 3.706564 -322.082321) (xy 3.773884 -322.058764) (xy 3.843419 -322.042894)
			(xy 3.914293 -322.034908) (xy 3.985615 -322.034908) (xy 4.056489 -322.042894) (xy 4.126024 -322.058764)
			(xy 4.193344 -322.082321) (xy 4.257603 -322.113266) (xy 4.317994 -322.151212) (xy 4.373756 -322.195681)
			(xy 4.424189 -322.246114) (xy 4.468658 -322.301876) (xy 4.506604 -322.362267) (xy 4.537549 -322.426526)
			(xy 4.561106 -322.493846) (xy 4.576976 -322.563381) (xy 4.584962 -322.634255) (xy 4.585462 -322.669916)
			(xy 4.584962 -322.705577) (xy 4.576976 -322.776451) (xy 4.561106 -322.845986) (xy 4.537549 -322.913306)
			(xy 4.506604 -322.977565) (xy 4.468658 -323.037956) (xy 4.424189 -323.093718) (xy 4.373756 -323.144151)
			(xy 4.317994 -323.18862) (xy 4.257603 -323.226566) (xy 4.193344 -323.257511) (xy 4.126024 -323.281068)
			(xy 4.056489 -323.296938) (xy 3.985615 -323.304924) (xy 3.914293 -323.304924) (xy 3.843419 -323.296938)
			(xy 3.773884 -323.281068) (xy 3.706564 -323.257511) (xy 3.642305 -323.226566) (xy 3.581914 -323.18862)
			(xy 3.526152 -323.144151) (xy 3.475719 -323.093718) (xy 3.43125 -323.037956) (xy 3.393304 -322.977565)
			(xy 3.362359 -322.913306) (xy 3.338802 -322.845986) (xy 3.322932 -322.776451) (xy 3.314946 -322.705577)
			(xy 1.525016 -322.705577) (xy 1.525016 -322.796916) (xy 1.525462 -322.818933) (xy 1.533007 -322.862315)
			(xy 1.547918 -322.903747) (xy 1.56975 -322.941988) (xy 1.597848 -322.975891) (xy 1.63137 -323.004443)
			(xy 1.669314 -323.026787) (xy 1.710541 -323.042255) (xy 1.753818 -323.050383) (xy 1.797848 -323.050928)
			(xy 1.819656 -323.047868) (xy 1.854312 -323.041099) (xy 1.924607 -323.034372) (xy 1.995215 -323.035479)
			(xy 2.065264 -323.044406) (xy 2.133892 -323.061043) (xy 2.200253 -323.085185) (xy 2.263529 -323.116534)
			(xy 2.32294 -323.154704) (xy 2.377753 -323.199225) (xy 2.427293 -323.249548) (xy 2.47095 -323.305053)
			(xy 2.508184 -323.365054) (xy 2.538538 -323.428814) (xy 2.561637 -323.495545) (xy 2.577197 -323.564425)
			(xy 2.585025 -323.634606) (xy 2.585025 -323.705222) (xy 2.584986 -323.705575) (xy 7.81481 -323.705575)
			(xy 7.81481 -323.634253) (xy 7.822796 -323.563379) (xy 7.838666 -323.493844) (xy 7.862223 -323.426524)
			(xy 7.893168 -323.362265) (xy 7.931114 -323.301874) (xy 7.975583 -323.246112) (xy 8.026016 -323.195679)
			(xy 8.081778 -323.15121) (xy 8.142169 -323.113264) (xy 8.206428 -323.082319) (xy 8.273748 -323.058762)
			(xy 8.343283 -323.042892) (xy 8.414157 -323.034906) (xy 8.485479 -323.034906) (xy 8.556353 -323.042892)
			(xy 8.625888 -323.058762) (xy 8.693208 -323.082319) (xy 8.757467 -323.113264) (xy 8.817858 -323.15121)
			(xy 8.87362 -323.195679) (xy 8.924053 -323.246112) (xy 8.968522 -323.301874) (xy 9.006468 -323.362265)
			(xy 9.037413 -323.426524) (xy 9.06097 -323.493844) (xy 9.07684 -323.563379) (xy 9.084826 -323.634253)
			(xy 9.085326 -323.669914) (xy 9.084826 -323.705575) (xy 9.07684 -323.776449) (xy 9.06097 -323.845984)
			(xy 9.037413 -323.913304) (xy 9.006468 -323.977563) (xy 8.968522 -324.037954) (xy 8.924053 -324.093716)
			(xy 8.87362 -324.144149) (xy 8.817858 -324.188618) (xy 8.757467 -324.226564) (xy 8.693208 -324.257509)
			(xy 8.625888 -324.281066) (xy 8.556353 -324.296936) (xy 8.485479 -324.304922) (xy 8.414157 -324.304922)
			(xy 8.343283 -324.296936) (xy 8.273748 -324.281066) (xy 8.206428 -324.257509) (xy 8.142169 -324.226564)
			(xy 8.081778 -324.188618) (xy 8.026016 -324.144149) (xy 7.975583 -324.093716) (xy 7.931114 -324.037954)
			(xy 7.893168 -323.977563) (xy 7.862223 -323.913304) (xy 7.838666 -323.845984) (xy 7.822796 -323.776449)
			(xy 7.81481 -323.705575) (xy 2.584986 -323.705575) (xy 2.577197 -323.775403) (xy 2.561637 -323.844283)
			(xy 2.538538 -323.911014) (xy 2.508184 -323.974774) (xy 2.47095 -324.034775) (xy 2.427293 -324.09028)
			(xy 2.377753 -324.140603) (xy 2.32294 -324.185124) (xy 2.263529 -324.223294) (xy 2.200253 -324.254643)
			(xy 2.133892 -324.278785) (xy 2.065264 -324.295422) (xy 1.995215 -324.304349) (xy 1.924607 -324.305456)
			(xy 1.854312 -324.298729) (xy 1.819656 -324.29196) (xy 1.797849 -324.288902) (xy 1.753823 -324.289457)
			(xy 1.710551 -324.297591) (xy 1.669329 -324.313063) (xy 1.63139 -324.335408) (xy 1.59787 -324.363958)
			(xy 1.569773 -324.397857) (xy 1.54794 -324.436093) (xy 1.533024 -324.477519) (xy 1.525471 -324.520897)
			(xy 1.525016 -324.542912) (xy 1.525016 -324.705573) (xy 3.314946 -324.705573) (xy 3.314946 -324.634251)
			(xy 3.322932 -324.563377) (xy 3.338802 -324.493842) (xy 3.362359 -324.426522) (xy 3.393304 -324.362263)
			(xy 3.43125 -324.301872) (xy 3.475719 -324.24611) (xy 3.526152 -324.195677) (xy 3.581914 -324.151208)
			(xy 3.642305 -324.113262) (xy 3.706564 -324.082317) (xy 3.773884 -324.05876) (xy 3.843419 -324.04289)
			(xy 3.914293 -324.034904) (xy 3.985615 -324.034904) (xy 4.056489 -324.04289) (xy 4.126024 -324.05876)
			(xy 4.193344 -324.082317) (xy 4.257603 -324.113262) (xy 4.317994 -324.151208) (xy 4.373756 -324.195677)
			(xy 4.424189 -324.24611) (xy 4.468658 -324.301872) (xy 4.506604 -324.362263) (xy 4.537549 -324.426522)
			(xy 4.561106 -324.493842) (xy 4.576976 -324.563377) (xy 4.584962 -324.634251) (xy 4.585462 -324.669912)
			(xy 4.584962 -324.705573) (xy 5.814814 -324.705573) (xy 5.814814 -324.634251) (xy 5.8228 -324.563377)
			(xy 5.83867 -324.493842) (xy 5.862227 -324.426522) (xy 5.893172 -324.362263) (xy 5.931118 -324.301872)
			(xy 5.975587 -324.24611) (xy 6.02602 -324.195677) (xy 6.081782 -324.151208) (xy 6.142173 -324.113262)
			(xy 6.206432 -324.082317) (xy 6.273752 -324.05876) (xy 6.343287 -324.04289) (xy 6.414161 -324.034904)
			(xy 6.485483 -324.034904) (xy 6.556357 -324.04289) (xy 6.625892 -324.05876) (xy 6.693212 -324.082317)
			(xy 6.757471 -324.113262) (xy 6.817862 -324.151208) (xy 6.873624 -324.195677) (xy 6.924057 -324.24611)
			(xy 6.968526 -324.301872) (xy 7.006472 -324.362263) (xy 7.037417 -324.426522) (xy 7.060974 -324.493842)
			(xy 7.076844 -324.563377) (xy 7.08483 -324.634251) (xy 7.08533 -324.669912) (xy 7.08483 -324.705573)
			(xy 7.083353 -324.71868) (xy 11.195556 -324.71868) (xy 11.199627 -324.663058) (xy 11.211753 -324.608621)
			(xy 11.231676 -324.55653) (xy 11.258972 -324.507895) (xy 11.293058 -324.463752) (xy 11.333207 -324.425043)
			(xy 11.378565 -324.392592) (xy 11.428165 -324.367091) (xy 11.480949 -324.349084) (xy 11.535792 -324.338954)
			(xy 11.591526 -324.336917) (xy 11.646963 -324.343017) (xy 11.70092 -324.357123) (xy 11.752249 -324.378935)
			(xy 11.799855 -324.407989) (xy 11.842723 -324.443664) (xy 11.87994 -324.485201) (xy 11.910713 -324.531714)
			(xy 11.934385 -324.582211) (xy 11.950453 -324.635618) (xy 11.958573 -324.690794) (xy 11.959082 -324.71868)
			(xy 11.958573 -324.746566) (xy 11.950453 -324.801742) (xy 11.934385 -324.855149) (xy 11.910713 -324.905646)
			(xy 11.87994 -324.952159) (xy 11.842723 -324.993696) (xy 11.799855 -325.029371) (xy 11.752249 -325.058425)
			(xy 11.70092 -325.080237) (xy 11.646963 -325.094343) (xy 11.591526 -325.100443) (xy 11.535792 -325.098406)
			(xy 11.480949 -325.088276) (xy 11.428165 -325.070269) (xy 11.378565 -325.044768) (xy 11.333207 -325.012317)
			(xy 11.293058 -324.973608) (xy 11.258972 -324.929465) (xy 11.231676 -324.88083) (xy 11.211753 -324.828739)
			(xy 11.199627 -324.774302) (xy 11.195556 -324.71868) (xy 7.083353 -324.71868) (xy 7.076844 -324.776447)
			(xy 7.060974 -324.845982) (xy 7.037417 -324.913302) (xy 7.006472 -324.977561) (xy 6.968526 -325.037952)
			(xy 6.924057 -325.093714) (xy 6.873624 -325.144147) (xy 6.817862 -325.188616) (xy 6.757471 -325.226562)
			(xy 6.693212 -325.257507) (xy 6.625892 -325.281064) (xy 6.556357 -325.296934) (xy 6.485483 -325.30492)
			(xy 6.414161 -325.30492) (xy 6.343287 -325.296934) (xy 6.273752 -325.281064) (xy 6.206432 -325.257507)
			(xy 6.142173 -325.226562) (xy 6.081782 -325.188616) (xy 6.02602 -325.144147) (xy 5.975587 -325.093714)
			(xy 5.931118 -325.037952) (xy 5.893172 -324.977561) (xy 5.862227 -324.913302) (xy 5.83867 -324.845982)
			(xy 5.8228 -324.776447) (xy 5.814814 -324.705573) (xy 4.584962 -324.705573) (xy 4.576976 -324.776447)
			(xy 4.561106 -324.845982) (xy 4.537549 -324.913302) (xy 4.506604 -324.977561) (xy 4.468658 -325.037952)
			(xy 4.424189 -325.093714) (xy 4.373756 -325.144147) (xy 4.317994 -325.188616) (xy 4.257603 -325.226562)
			(xy 4.193344 -325.257507) (xy 4.126024 -325.281064) (xy 4.056489 -325.296934) (xy 3.985615 -325.30492)
			(xy 3.914293 -325.30492) (xy 3.843419 -325.296934) (xy 3.773884 -325.281064) (xy 3.706564 -325.257507)
			(xy 3.642305 -325.226562) (xy 3.581914 -325.188616) (xy 3.526152 -325.144147) (xy 3.475719 -325.093714)
			(xy 3.43125 -325.037952) (xy 3.393304 -324.977561) (xy 3.362359 -324.913302) (xy 3.338802 -324.845982)
			(xy 3.322932 -324.776447) (xy 3.314946 -324.705573) (xy 1.525016 -324.705573) (xy 1.525016 -325.705571)
			(xy 7.81481 -325.705571) (xy 7.81481 -325.634249) (xy 7.822796 -325.563375) (xy 7.838666 -325.49384)
			(xy 7.862223 -325.42652) (xy 7.893168 -325.362261) (xy 7.931114 -325.30187) (xy 7.975583 -325.246108)
			(xy 8.026016 -325.195675) (xy 8.081778 -325.151206) (xy 8.142169 -325.11326) (xy 8.206428 -325.082315)
			(xy 8.273748 -325.058758) (xy 8.343283 -325.042888) (xy 8.414157 -325.034902) (xy 8.485479 -325.034902)
			(xy 8.556353 -325.042888) (xy 8.625888 -325.058758) (xy 8.693208 -325.082315) (xy 8.757467 -325.11326)
			(xy 8.817858 -325.151206) (xy 8.87362 -325.195675) (xy 8.924053 -325.246108) (xy 8.968522 -325.30187)
			(xy 9.006468 -325.362261) (xy 9.037413 -325.42652) (xy 9.06097 -325.49384) (xy 9.07684 -325.563375)
			(xy 9.084826 -325.634249) (xy 9.085326 -325.66991) (xy 9.084826 -325.705571) (xy 9.07684 -325.776445)
			(xy 9.06097 -325.84598) (xy 9.037413 -325.9133) (xy 9.006468 -325.977559) (xy 8.968522 -326.03795)
			(xy 8.946236 -326.065896) (xy 11.152884 -326.065896) (xy 11.156955 -326.010274) (xy 11.169081 -325.955837)
			(xy 11.189004 -325.903746) (xy 11.2163 -325.855111) (xy 11.250386 -325.810968) (xy 11.290535 -325.772259)
			(xy 11.335893 -325.739808) (xy 11.385493 -325.714307) (xy 11.438277 -325.6963) (xy 11.49312 -325.68617)
			(xy 11.548854 -325.684133) (xy 11.604291 -325.690233) (xy 11.658248 -325.704339) (xy 11.709577 -325.726151)
			(xy 11.757183 -325.755205) (xy 11.800051 -325.79088) (xy 11.837268 -325.832417) (xy 11.868041 -325.87893)
			(xy 11.891713 -325.929427) (xy 11.907781 -325.982834) (xy 11.915901 -326.03801) (xy 11.91641 -326.065896)
			(xy 11.915901 -326.093782) (xy 11.907781 -326.148958) (xy 11.891713 -326.202365) (xy 11.868041 -326.252862)
			(xy 11.837268 -326.299375) (xy 11.800051 -326.340912) (xy 11.757183 -326.376587) (xy 11.709577 -326.405641)
			(xy 11.658248 -326.427453) (xy 11.604291 -326.441559) (xy 11.548854 -326.447659) (xy 11.49312 -326.445622)
			(xy 11.438277 -326.435492) (xy 11.385493 -326.417485) (xy 11.335893 -326.391984) (xy 11.290535 -326.359533)
			(xy 11.250386 -326.320824) (xy 11.2163 -326.276681) (xy 11.189004 -326.228046) (xy 11.169081 -326.175955)
			(xy 11.156955 -326.121518) (xy 11.152884 -326.065896) (xy 8.946236 -326.065896) (xy 8.924053 -326.093712)
			(xy 8.87362 -326.144145) (xy 8.817858 -326.188614) (xy 8.757467 -326.22656) (xy 8.693208 -326.257505)
			(xy 8.625888 -326.281062) (xy 8.556353 -326.296932) (xy 8.485479 -326.304918) (xy 8.414157 -326.304918)
			(xy 8.343283 -326.296932) (xy 8.273748 -326.281062) (xy 8.206428 -326.257505) (xy 8.142169 -326.22656)
			(xy 8.081778 -326.188614) (xy 8.026016 -326.144145) (xy 7.975583 -326.093712) (xy 7.931114 -326.03795)
			(xy 7.893168 -325.977559) (xy 7.862223 -325.9133) (xy 7.838666 -325.84598) (xy 7.822796 -325.776445)
			(xy 7.81481 -325.705571) (xy 1.525016 -325.705571) (xy 1.525016 -326.705569) (xy 3.314946 -326.705569)
			(xy 3.314946 -326.634247) (xy 3.322932 -326.563373) (xy 3.338802 -326.493838) (xy 3.362359 -326.426518)
			(xy 3.393304 -326.362259) (xy 3.43125 -326.301868) (xy 3.475719 -326.246106) (xy 3.526152 -326.195673)
			(xy 3.581914 -326.151204) (xy 3.642305 -326.113258) (xy 3.706564 -326.082313) (xy 3.773884 -326.058756)
			(xy 3.843419 -326.042886) (xy 3.914293 -326.0349) (xy 3.985615 -326.0349) (xy 4.056489 -326.042886)
			(xy 4.126024 -326.058756) (xy 4.193344 -326.082313) (xy 4.257603 -326.113258) (xy 4.317994 -326.151204)
			(xy 4.373756 -326.195673) (xy 4.424189 -326.246106) (xy 4.468658 -326.301868) (xy 4.506604 -326.362259)
			(xy 4.537549 -326.426518) (xy 4.561106 -326.493838) (xy 4.576976 -326.563373) (xy 4.584962 -326.634247)
			(xy 4.585462 -326.669908) (xy 4.584962 -326.705569) (xy 4.576976 -326.776443) (xy 4.561106 -326.845978)
			(xy 4.537549 -326.913298) (xy 4.506604 -326.977557) (xy 4.468658 -327.037948) (xy 4.424189 -327.09371)
			(xy 4.373756 -327.144143) (xy 4.317994 -327.188612) (xy 4.257603 -327.226558) (xy 4.193344 -327.257503)
			(xy 4.126024 -327.28106) (xy 4.056489 -327.29693) (xy 3.985615 -327.304916) (xy 3.914293 -327.304916)
			(xy 3.843419 -327.29693) (xy 3.773884 -327.28106) (xy 3.706564 -327.257503) (xy 3.642305 -327.226558)
			(xy 3.581914 -327.188612) (xy 3.526152 -327.144143) (xy 3.475719 -327.09371) (xy 3.43125 -327.037948)
			(xy 3.393304 -326.977557) (xy 3.362359 -326.913298) (xy 3.338802 -326.845978) (xy 3.322932 -326.776443)
			(xy 3.314946 -326.705569) (xy 1.525016 -326.705569) (xy 1.525016 -326.796908) (xy 1.525462 -326.818925)
			(xy 1.533007 -326.862307) (xy 1.547919 -326.903738) (xy 1.569751 -326.941978) (xy 1.597849 -326.975882)
			(xy 1.631371 -327.004433) (xy 1.669314 -327.026777) (xy 1.710541 -327.042245) (xy 1.753818 -327.050373)
			(xy 1.797848 -327.050918) (xy 1.819656 -327.04786) (xy 1.854312 -327.041091) (xy 1.924607 -327.034364)
			(xy 1.995215 -327.035471) (xy 2.065264 -327.044398) (xy 2.133892 -327.061035) (xy 2.200253 -327.085177)
			(xy 2.263529 -327.116526) (xy 2.32294 -327.154696) (xy 2.377753 -327.199217) (xy 2.427293 -327.24954)
			(xy 2.47095 -327.305045) (xy 2.508184 -327.365046) (xy 2.538538 -327.428806) (xy 2.561637 -327.495537)
			(xy 2.577197 -327.564417) (xy 2.585025 -327.634598) (xy 2.585025 -327.705214) (xy 2.584986 -327.705567)
			(xy 7.81481 -327.705567) (xy 7.81481 -327.634245) (xy 7.822796 -327.563371) (xy 7.838666 -327.493836)
			(xy 7.862223 -327.426516) (xy 7.893168 -327.362257) (xy 7.931114 -327.301866) (xy 7.975583 -327.246104)
			(xy 8.026016 -327.195671) (xy 8.081778 -327.151202) (xy 8.142169 -327.113256) (xy 8.206428 -327.082311)
			(xy 8.273748 -327.058754) (xy 8.343283 -327.042884) (xy 8.414157 -327.034898) (xy 8.485479 -327.034898)
			(xy 8.556353 -327.042884) (xy 8.625888 -327.058754) (xy 8.693208 -327.082311) (xy 8.757467 -327.113256)
			(xy 8.817858 -327.151202) (xy 8.87362 -327.195671) (xy 8.924053 -327.246104) (xy 8.968522 -327.301866)
			(xy 9.006468 -327.362257) (xy 9.035728 -327.423018) (xy 11.109958 -327.423018) (xy 11.114029 -327.367396)
			(xy 11.126155 -327.312959) (xy 11.146078 -327.260868) (xy 11.173374 -327.212233) (xy 11.20746 -327.16809)
			(xy 11.247609 -327.129381) (xy 11.292967 -327.09693) (xy 11.342567 -327.071429) (xy 11.395351 -327.053422)
			(xy 11.450194 -327.043292) (xy 11.505928 -327.041255) (xy 11.561365 -327.047355) (xy 11.615322 -327.061461)
			(xy 11.666651 -327.083273) (xy 11.714257 -327.112327) (xy 11.757125 -327.148002) (xy 11.794342 -327.189539)
			(xy 11.825115 -327.236052) (xy 11.848787 -327.286549) (xy 11.864855 -327.339956) (xy 11.872975 -327.395132)
			(xy 11.873484 -327.423018) (xy 11.872975 -327.450904) (xy 11.864855 -327.50608) (xy 11.848787 -327.559487)
			(xy 11.825115 -327.609984) (xy 11.794342 -327.656497) (xy 11.757125 -327.698034) (xy 11.714257 -327.733709)
			(xy 11.666651 -327.762763) (xy 11.615322 -327.784575) (xy 11.561365 -327.798681) (xy 11.505928 -327.804781)
			(xy 11.450194 -327.802744) (xy 11.395351 -327.792614) (xy 11.342567 -327.774607) (xy 11.292967 -327.749106)
			(xy 11.247609 -327.716655) (xy 11.20746 -327.677946) (xy 11.173374 -327.633803) (xy 11.146078 -327.585168)
			(xy 11.126155 -327.533077) (xy 11.114029 -327.47864) (xy 11.109958 -327.423018) (xy 9.035728 -327.423018)
			(xy 9.037413 -327.426516) (xy 9.06097 -327.493836) (xy 9.07684 -327.563371) (xy 9.084826 -327.634245)
			(xy 9.085326 -327.669906) (xy 9.084826 -327.705567) (xy 9.07684 -327.776441) (xy 9.06097 -327.845976)
			(xy 9.037413 -327.913296) (xy 9.006468 -327.977555) (xy 8.968522 -328.037946) (xy 8.924053 -328.093708)
			(xy 8.87362 -328.144141) (xy 8.817858 -328.18861) (xy 8.757467 -328.226556) (xy 8.693208 -328.257501)
			(xy 8.625888 -328.281058) (xy 8.556353 -328.296928) (xy 8.485479 -328.304914) (xy 8.414157 -328.304914)
			(xy 8.343283 -328.296928) (xy 8.273748 -328.281058) (xy 8.206428 -328.257501) (xy 8.142169 -328.226556)
			(xy 8.081778 -328.18861) (xy 8.026016 -328.144141) (xy 7.975583 -328.093708) (xy 7.931114 -328.037946)
			(xy 7.893168 -327.977555) (xy 7.862223 -327.913296) (xy 7.838666 -327.845976) (xy 7.822796 -327.776441)
			(xy 7.81481 -327.705567) (xy 2.584986 -327.705567) (xy 2.577197 -327.775395) (xy 2.561637 -327.844275)
			(xy 2.538538 -327.911006) (xy 2.508184 -327.974766) (xy 2.47095 -328.034767) (xy 2.427293 -328.090272)
			(xy 2.377753 -328.140595) (xy 2.32294 -328.185116) (xy 2.263529 -328.223286) (xy 2.200253 -328.254635)
			(xy 2.133892 -328.278777) (xy 2.065264 -328.295414) (xy 1.995215 -328.304341) (xy 1.924607 -328.305448)
			(xy 1.854312 -328.298721) (xy 1.819656 -328.291952) (xy 1.797849 -328.288894) (xy 1.753823 -328.289449)
			(xy 1.710551 -328.297583) (xy 1.669329 -328.313055) (xy 1.63139 -328.3354) (xy 1.597871 -328.36395)
			(xy 1.569774 -328.39785) (xy 1.547941 -328.436085) (xy 1.533025 -328.477511) (xy 1.525473 -328.520889)
			(xy 1.525016 -328.542904) (xy 1.525016 -328.705565) (xy 3.314946 -328.705565) (xy 3.314946 -328.634243)
			(xy 3.322932 -328.563369) (xy 3.338802 -328.493834) (xy 3.362359 -328.426514) (xy 3.393304 -328.362255)
			(xy 3.43125 -328.301864) (xy 3.475719 -328.246102) (xy 3.526152 -328.195669) (xy 3.581914 -328.1512)
			(xy 3.642305 -328.113254) (xy 3.706564 -328.082309) (xy 3.773884 -328.058752) (xy 3.843419 -328.042882)
			(xy 3.914293 -328.034896) (xy 3.985615 -328.034896) (xy 4.056489 -328.042882) (xy 4.126024 -328.058752)
			(xy 4.193344 -328.082309) (xy 4.257603 -328.113254) (xy 4.317994 -328.1512) (xy 4.373756 -328.195669)
			(xy 4.424189 -328.246102) (xy 4.468658 -328.301864) (xy 4.506604 -328.362255) (xy 4.537549 -328.426514)
			(xy 4.561106 -328.493834) (xy 4.576976 -328.563369) (xy 4.584962 -328.634243) (xy 4.585462 -328.669904)
			(xy 4.584962 -328.705565) (xy 5.814814 -328.705565) (xy 5.814814 -328.634243) (xy 5.8228 -328.563369)
			(xy 5.83867 -328.493834) (xy 5.862227 -328.426514) (xy 5.893172 -328.362255) (xy 5.931118 -328.301864)
			(xy 5.975587 -328.246102) (xy 6.02602 -328.195669) (xy 6.081782 -328.1512) (xy 6.142173 -328.113254)
			(xy 6.206432 -328.082309) (xy 6.273752 -328.058752) (xy 6.343287 -328.042882) (xy 6.414161 -328.034896)
			(xy 6.485483 -328.034896) (xy 6.556357 -328.042882) (xy 6.625892 -328.058752) (xy 6.693212 -328.082309)
			(xy 6.757471 -328.113254) (xy 6.817862 -328.1512) (xy 6.873624 -328.195669) (xy 6.924057 -328.246102)
			(xy 6.968526 -328.301864) (xy 7.006472 -328.362255) (xy 7.037417 -328.426514) (xy 7.060974 -328.493834)
			(xy 7.076844 -328.563369) (xy 7.08483 -328.634243) (xy 7.08533 -328.669904) (xy 7.08483 -328.705565)
			(xy 7.082351 -328.727562) (xy 11.1158 -328.727562) (xy 11.119871 -328.67194) (xy 11.131997 -328.617503)
			(xy 11.15192 -328.565412) (xy 11.179216 -328.516777) (xy 11.213302 -328.472634) (xy 11.253451 -328.433925)
			(xy 11.298809 -328.401474) (xy 11.348409 -328.375973) (xy 11.401193 -328.357966) (xy 11.456036 -328.347836)
			(xy 11.51177 -328.345799) (xy 11.567207 -328.351899) (xy 11.621164 -328.366005) (xy 11.672493 -328.387817)
			(xy 11.720099 -328.416871) (xy 11.762967 -328.452546) (xy 11.800184 -328.494083) (xy 11.830957 -328.540596)
			(xy 11.854629 -328.591093) (xy 11.870697 -328.6445) (xy 11.878817 -328.699676) (xy 11.879326 -328.727562)
			(xy 11.878817 -328.755448) (xy 11.870697 -328.810624) (xy 11.854629 -328.864031) (xy 11.830957 -328.914528)
			(xy 11.800184 -328.961041) (xy 11.762967 -329.002578) (xy 11.720099 -329.038253) (xy 11.672493 -329.067307)
			(xy 11.621164 -329.089119) (xy 11.567207 -329.103225) (xy 11.51177 -329.109325) (xy 11.456036 -329.107288)
			(xy 11.401193 -329.097158) (xy 11.348409 -329.079151) (xy 11.298809 -329.05365) (xy 11.253451 -329.021199)
			(xy 11.213302 -328.98249) (xy 11.179216 -328.938347) (xy 11.15192 -328.889712) (xy 11.131997 -328.837621)
			(xy 11.119871 -328.783184) (xy 11.1158 -328.727562) (xy 7.082351 -328.727562) (xy 7.076844 -328.776439)
			(xy 7.060974 -328.845974) (xy 7.037417 -328.913294) (xy 7.006472 -328.977553) (xy 6.968526 -329.037944)
			(xy 6.924057 -329.093706) (xy 6.873624 -329.144139) (xy 6.817862 -329.188608) (xy 6.757471 -329.226554)
			(xy 6.693212 -329.257499) (xy 6.625892 -329.281056) (xy 6.556357 -329.296926) (xy 6.485483 -329.304912)
			(xy 6.414161 -329.304912) (xy 6.343287 -329.296926) (xy 6.273752 -329.281056) (xy 6.206432 -329.257499)
			(xy 6.142173 -329.226554) (xy 6.081782 -329.188608) (xy 6.02602 -329.144139) (xy 5.975587 -329.093706)
			(xy 5.931118 -329.037944) (xy 5.893172 -328.977553) (xy 5.862227 -328.913294) (xy 5.83867 -328.845974)
			(xy 5.8228 -328.776439) (xy 5.814814 -328.705565) (xy 4.584962 -328.705565) (xy 4.576976 -328.776439)
			(xy 4.561106 -328.845974) (xy 4.537549 -328.913294) (xy 4.506604 -328.977553) (xy 4.468658 -329.037944)
			(xy 4.424189 -329.093706) (xy 4.373756 -329.144139) (xy 4.317994 -329.188608) (xy 4.257603 -329.226554)
			(xy 4.193344 -329.257499) (xy 4.126024 -329.281056) (xy 4.056489 -329.296926) (xy 3.985615 -329.304912)
			(xy 3.914293 -329.304912) (xy 3.843419 -329.296926) (xy 3.773884 -329.281056) (xy 3.706564 -329.257499)
			(xy 3.642305 -329.226554) (xy 3.581914 -329.188608) (xy 3.526152 -329.144139) (xy 3.475719 -329.093706)
			(xy 3.43125 -329.037944) (xy 3.393304 -328.977553) (xy 3.362359 -328.913294) (xy 3.338802 -328.845974)
			(xy 3.322932 -328.776439) (xy 3.314946 -328.705565) (xy 1.525016 -328.705565) (xy 1.525016 -328.796904)
			(xy 1.525461 -328.818921) (xy 1.533006 -328.862304) (xy 1.547918 -328.903736) (xy 1.569749 -328.941977)
			(xy 1.597847 -328.97588) (xy 1.63137 -329.004432) (xy 1.669313 -329.026777) (xy 1.710541 -329.042245)
			(xy 1.753818 -329.050373) (xy 1.797848 -329.050918) (xy 1.819656 -329.047856) (xy 1.854312 -329.041087)
			(xy 1.924607 -329.03436) (xy 1.995214 -329.035466) (xy 2.065264 -329.044393) (xy 2.133892 -329.061029)
			(xy 2.200253 -329.085171) (xy 2.263529 -329.116521) (xy 2.32294 -329.154691) (xy 2.377753 -329.199212)
			(xy 2.427293 -329.249534) (xy 2.47095 -329.305039) (xy 2.508185 -329.36504) (xy 2.538539 -329.428799)
			(xy 2.561638 -329.49553) (xy 2.577197 -329.564411) (xy 2.585025 -329.634592) (xy 2.585025 -329.705208)
			(xy 2.584985 -329.705563) (xy 7.81481 -329.705563) (xy 7.81481 -329.634241) (xy 7.822796 -329.563367)
			(xy 7.838666 -329.493832) (xy 7.862223 -329.426512) (xy 7.893168 -329.362253) (xy 7.931114 -329.301862)
			(xy 7.975583 -329.2461) (xy 8.026016 -329.195667) (xy 8.081778 -329.151198) (xy 8.142169 -329.113252)
			(xy 8.206428 -329.082307) (xy 8.273748 -329.05875) (xy 8.343283 -329.04288) (xy 8.414157 -329.034894)
			(xy 8.485479 -329.034894) (xy 8.556353 -329.04288) (xy 8.625888 -329.05875) (xy 8.693208 -329.082307)
			(xy 8.757467 -329.113252) (xy 8.817858 -329.151198) (xy 8.87362 -329.195667) (xy 8.924053 -329.2461)
			(xy 8.968522 -329.301862) (xy 9.006468 -329.362253) (xy 9.037413 -329.426512) (xy 9.06097 -329.493832)
			(xy 9.07684 -329.563367) (xy 9.084826 -329.634241) (xy 9.085326 -329.669902) (xy 9.084826 -329.705563)
			(xy 9.07684 -329.776437) (xy 9.06097 -329.845972) (xy 9.037413 -329.913292) (xy 9.006468 -329.977551)
			(xy 8.968522 -330.037942) (xy 8.924053 -330.093704) (xy 8.894719 -330.123038) (xy 11.136882 -330.123038)
			(xy 11.140953 -330.067416) (xy 11.153079 -330.012979) (xy 11.173002 -329.960888) (xy 11.200298 -329.912253)
			(xy 11.234384 -329.86811) (xy 11.274533 -329.829401) (xy 11.319891 -329.79695) (xy 11.369491 -329.771449)
			(xy 11.422275 -329.753442) (xy 11.477118 -329.743312) (xy 11.532852 -329.741275) (xy 11.588289 -329.747375)
			(xy 11.642246 -329.761481) (xy 11.693575 -329.783293) (xy 11.741181 -329.812347) (xy 11.784049 -329.848022)
			(xy 11.821266 -329.889559) (xy 11.852039 -329.936072) (xy 11.875711 -329.986569) (xy 11.891779 -330.039976)
			(xy 11.899899 -330.095152) (xy 11.900408 -330.123038) (xy 11.899899 -330.150924) (xy 11.891779 -330.2061)
			(xy 11.875711 -330.259507) (xy 11.852039 -330.310004) (xy 11.821266 -330.356517) (xy 11.784049 -330.398054)
			(xy 11.741181 -330.433729) (xy 11.693575 -330.462783) (xy 11.642246 -330.484595) (xy 11.588289 -330.498701)
			(xy 11.532852 -330.504801) (xy 11.477118 -330.502764) (xy 11.422275 -330.492634) (xy 11.369491 -330.474627)
			(xy 11.319891 -330.449126) (xy 11.274533 -330.416675) (xy 11.234384 -330.377966) (xy 11.200298 -330.333823)
			(xy 11.173002 -330.285188) (xy 11.153079 -330.233097) (xy 11.140953 -330.17866) (xy 11.136882 -330.123038)
			(xy 8.894719 -330.123038) (xy 8.87362 -330.144137) (xy 8.817858 -330.188606) (xy 8.757467 -330.226552)
			(xy 8.693208 -330.257497) (xy 8.625888 -330.281054) (xy 8.556353 -330.296924) (xy 8.485479 -330.30491)
			(xy 8.414157 -330.30491) (xy 8.343283 -330.296924) (xy 8.273748 -330.281054) (xy 8.206428 -330.257497)
			(xy 8.142169 -330.226552) (xy 8.081778 -330.188606) (xy 8.026016 -330.144137) (xy 7.975583 -330.093704)
			(xy 7.931114 -330.037942) (xy 7.893168 -329.977551) (xy 7.862223 -329.913292) (xy 7.838666 -329.845972)
			(xy 7.822796 -329.776437) (xy 7.81481 -329.705563) (xy 2.584985 -329.705563) (xy 2.577197 -329.775388)
			(xy 2.561638 -329.844269) (xy 2.538539 -329.911) (xy 2.508185 -329.974759) (xy 2.47095 -330.034761)
			(xy 2.427294 -330.090265) (xy 2.377754 -330.140588) (xy 2.32294 -330.185109) (xy 2.26353 -330.223279)
			(xy 2.200254 -330.254628) (xy 2.133893 -330.27877) (xy 2.065265 -330.295407) (xy 1.995215 -330.304334)
			(xy 1.924608 -330.30544) (xy 1.854313 -330.298713) (xy 1.819656 -330.291948) (xy 1.797849 -330.28889)
			(xy 1.753823 -330.289445) (xy 1.710551 -330.297579) (xy 1.669328 -330.313051) (xy 1.631389 -330.335396)
			(xy 1.59787 -330.363946) (xy 1.569773 -330.397845) (xy 1.547939 -330.436081) (xy 1.533022 -330.477507)
			(xy 1.525469 -330.520885) (xy 1.525016 -330.5429) (xy 1.525016 -330.705561) (xy 3.314946 -330.705561)
			(xy 3.314946 -330.634239) (xy 3.322932 -330.563365) (xy 3.338802 -330.49383) (xy 3.362359 -330.42651)
			(xy 3.393304 -330.362251) (xy 3.43125 -330.30186) (xy 3.475719 -330.246098) (xy 3.526152 -330.195665)
			(xy 3.581914 -330.151196) (xy 3.642305 -330.11325) (xy 3.706564 -330.082305) (xy 3.773884 -330.058748)
			(xy 3.843419 -330.042878) (xy 3.914293 -330.034892) (xy 3.985615 -330.034892) (xy 4.056489 -330.042878)
			(xy 4.126024 -330.058748) (xy 4.193344 -330.082305) (xy 4.257603 -330.11325) (xy 4.317994 -330.151196)
			(xy 4.373756 -330.195665) (xy 4.424189 -330.246098) (xy 4.468658 -330.30186) (xy 4.506604 -330.362251)
			(xy 4.537549 -330.42651) (xy 4.561106 -330.49383) (xy 4.576976 -330.563365) (xy 4.584962 -330.634239)
			(xy 4.585462 -330.6699) (xy 4.584962 -330.705561) (xy 5.814814 -330.705561) (xy 5.814814 -330.634239)
			(xy 5.8228 -330.563365) (xy 5.83867 -330.49383) (xy 5.862227 -330.42651) (xy 5.893172 -330.362251)
			(xy 5.931118 -330.30186) (xy 5.975587 -330.246098) (xy 6.02602 -330.195665) (xy 6.081782 -330.151196)
			(xy 6.142173 -330.11325) (xy 6.206432 -330.082305) (xy 6.273752 -330.058748) (xy 6.343287 -330.042878)
			(xy 6.414161 -330.034892) (xy 6.485483 -330.034892) (xy 6.556357 -330.042878) (xy 6.625892 -330.058748)
			(xy 6.693212 -330.082305) (xy 6.757471 -330.11325) (xy 6.817862 -330.151196) (xy 6.873624 -330.195665)
			(xy 6.924057 -330.246098) (xy 6.968526 -330.30186) (xy 7.006472 -330.362251) (xy 7.037417 -330.42651)
			(xy 7.060974 -330.49383) (xy 7.076844 -330.563365) (xy 7.08483 -330.634239) (xy 7.08533 -330.6699)
			(xy 7.08483 -330.705561) (xy 7.076844 -330.776435) (xy 7.060974 -330.84597) (xy 7.037417 -330.91329)
			(xy 7.006472 -330.977549) (xy 6.968526 -331.03794) (xy 6.924057 -331.093702) (xy 6.873624 -331.144135)
			(xy 6.817862 -331.188604) (xy 6.757471 -331.22655) (xy 6.693212 -331.257495) (xy 6.625892 -331.281052)
			(xy 6.556357 -331.296922) (xy 6.485483 -331.304908) (xy 6.414161 -331.304908) (xy 6.343287 -331.296922)
			(xy 6.273752 -331.281052) (xy 6.206432 -331.257495) (xy 6.142173 -331.22655) (xy 6.081782 -331.188604)
			(xy 6.02602 -331.144135) (xy 5.975587 -331.093702) (xy 5.931118 -331.03794) (xy 5.893172 -330.977549)
			(xy 5.862227 -330.91329) (xy 5.83867 -330.84597) (xy 5.8228 -330.776435) (xy 5.814814 -330.705561)
			(xy 4.584962 -330.705561) (xy 4.576976 -330.776435) (xy 4.561106 -330.84597) (xy 4.537549 -330.91329)
			(xy 4.506604 -330.977549) (xy 4.468658 -331.03794) (xy 4.424189 -331.093702) (xy 4.373756 -331.144135)
			(xy 4.317994 -331.188604) (xy 4.257603 -331.22655) (xy 4.193344 -331.257495) (xy 4.126024 -331.281052)
			(xy 4.056489 -331.296922) (xy 3.985615 -331.304908) (xy 3.914293 -331.304908) (xy 3.843419 -331.296922)
			(xy 3.773884 -331.281052) (xy 3.706564 -331.257495) (xy 3.642305 -331.22655) (xy 3.581914 -331.188604)
			(xy 3.526152 -331.144135) (xy 3.475719 -331.093702) (xy 3.43125 -331.03794) (xy 3.393304 -330.977549)
			(xy 3.362359 -330.91329) (xy 3.338802 -330.84597) (xy 3.322932 -330.776435) (xy 3.314946 -330.705561)
			(xy 1.525016 -330.705561) (xy 1.525016 -330.7969) (xy 1.525462 -330.818917) (xy 1.533008 -330.862299)
			(xy 1.54792 -330.90373) (xy 1.569751 -330.941969) (xy 1.597849 -330.975872) (xy 1.631372 -331.004423)
			(xy 1.669314 -331.026767) (xy 1.710541 -331.042235) (xy 1.753818 -331.050363) (xy 1.797847 -331.050908)
			(xy 1.819656 -331.047852) (xy 1.854313 -331.041083) (xy 1.924608 -331.034356) (xy 1.995215 -331.035462)
			(xy 2.065265 -331.044389) (xy 2.133894 -331.061026) (xy 2.200255 -331.085168) (xy 2.263532 -331.116518)
			(xy 2.322943 -331.154688) (xy 2.377756 -331.199209) (xy 2.427297 -331.249532) (xy 2.470954 -331.305037)
			(xy 2.508188 -331.365039) (xy 2.538543 -331.428799) (xy 2.561642 -331.49553) (xy 2.577201 -331.564411)
			(xy 2.585029 -331.634592) (xy 2.585029 -331.705209) (xy 2.58499 -331.705559) (xy 7.81481 -331.705559)
			(xy 7.81481 -331.634237) (xy 7.822796 -331.563363) (xy 7.838666 -331.493828) (xy 7.862223 -331.426508)
			(xy 7.893168 -331.362249) (xy 7.931114 -331.301858) (xy 7.975583 -331.246096) (xy 8.026016 -331.195663)
			(xy 8.081778 -331.151194) (xy 8.142169 -331.113248) (xy 8.206428 -331.082303) (xy 8.273748 -331.058746)
			(xy 8.343283 -331.042876) (xy 8.414157 -331.03489) (xy 8.485479 -331.03489) (xy 8.556353 -331.042876)
			(xy 8.625888 -331.058746) (xy 8.693208 -331.082303) (xy 8.757467 -331.113248) (xy 8.817858 -331.151194)
			(xy 8.87362 -331.195663) (xy 8.924053 -331.246096) (xy 8.968522 -331.301858) (xy 9.006468 -331.362249)
			(xy 9.037413 -331.426508) (xy 9.06097 -331.493828) (xy 9.07684 -331.563363) (xy 9.084826 -331.634237)
			(xy 9.085326 -331.669898) (xy 11.109958 -331.669898) (xy 11.114029 -331.614276) (xy 11.126155 -331.559839)
			(xy 11.146078 -331.507748) (xy 11.173374 -331.459113) (xy 11.20746 -331.41497) (xy 11.247609 -331.376261)
			(xy 11.292967 -331.34381) (xy 11.342567 -331.318309) (xy 11.395351 -331.300302) (xy 11.450194 -331.290172)
			(xy 11.505928 -331.288135) (xy 11.561365 -331.294235) (xy 11.615322 -331.308341) (xy 11.666651 -331.330153)
			(xy 11.714257 -331.359207) (xy 11.757125 -331.394882) (xy 11.794342 -331.436419) (xy 11.825115 -331.482932)
			(xy 11.848787 -331.533429) (xy 11.864855 -331.586836) (xy 11.872975 -331.642012) (xy 11.873484 -331.669898)
			(xy 11.872975 -331.697784) (xy 11.864855 -331.75296) (xy 11.848787 -331.806367) (xy 11.825115 -331.856864)
			(xy 11.794342 -331.903377) (xy 11.757125 -331.944914) (xy 11.714257 -331.980589) (xy 11.666651 -332.009643)
			(xy 11.615322 -332.031455) (xy 11.561365 -332.045561) (xy 11.505928 -332.051661) (xy 11.450194 -332.049624)
			(xy 11.395351 -332.039494) (xy 11.342567 -332.021487) (xy 11.292967 -331.995986) (xy 11.247609 -331.963535)
			(xy 11.20746 -331.924826) (xy 11.173374 -331.880683) (xy 11.146078 -331.832048) (xy 11.126155 -331.779957)
			(xy 11.114029 -331.72552) (xy 11.109958 -331.669898) (xy 9.085326 -331.669898) (xy 9.084826 -331.705559)
			(xy 9.07684 -331.776433) (xy 9.06097 -331.845968) (xy 9.037413 -331.913288) (xy 9.006468 -331.977547)
			(xy 8.968522 -332.037938) (xy 8.924053 -332.0937) (xy 8.87362 -332.144133) (xy 8.817858 -332.188602)
			(xy 8.757467 -332.226548) (xy 8.693208 -332.257493) (xy 8.625888 -332.28105) (xy 8.556353 -332.29692)
			(xy 8.485479 -332.304906) (xy 8.414157 -332.304906) (xy 8.343283 -332.29692) (xy 8.273748 -332.28105)
			(xy 8.206428 -332.257493) (xy 8.142169 -332.226548) (xy 8.081778 -332.188602) (xy 8.026016 -332.144133)
			(xy 7.975583 -332.0937) (xy 7.931114 -332.037938) (xy 7.893168 -331.977547) (xy 7.862223 -331.913288)
			(xy 7.838666 -331.845968) (xy 7.822796 -331.776433) (xy 7.81481 -331.705559) (xy 2.58499 -331.705559)
			(xy 2.577201 -331.77539) (xy 2.561641 -331.844271) (xy 2.538542 -331.911002) (xy 2.508188 -331.974762)
			(xy 2.470953 -332.034764) (xy 2.427296 -332.090268) (xy 2.377756 -332.140591) (xy 2.322942 -332.185112)
			(xy 2.263531 -332.223283) (xy 2.200255 -332.254632) (xy 2.133893 -332.278774) (xy 2.065265 -332.295411)
			(xy 1.995215 -332.304338) (xy 1.924607 -332.305444) (xy 1.854312 -332.298717) (xy 1.819656 -332.291944)
			(xy 1.797849 -332.288886) (xy 1.753822 -332.289441) (xy 1.71055 -332.297575) (xy 1.669327 -332.313047)
			(xy 1.631388 -332.335392) (xy 1.597868 -332.363941) (xy 1.569771 -332.397841) (xy 1.547936 -332.436077)
			(xy 1.533019 -332.477503) (xy 1.525465 -332.52088) (xy 1.525016 -332.542896) (xy 1.525016 -332.705557)
			(xy 3.314946 -332.705557) (xy 3.314946 -332.634235) (xy 3.322932 -332.563361) (xy 3.338802 -332.493826)
			(xy 3.362359 -332.426506) (xy 3.393304 -332.362247) (xy 3.43125 -332.301856) (xy 3.475719 -332.246094)
			(xy 3.526152 -332.195661) (xy 3.581914 -332.151192) (xy 3.642305 -332.113246) (xy 3.706564 -332.082301)
			(xy 3.773884 -332.058744) (xy 3.843419 -332.042874) (xy 3.914293 -332.034888) (xy 3.985615 -332.034888)
			(xy 4.056489 -332.042874) (xy 4.126024 -332.058744) (xy 4.193344 -332.082301) (xy 4.257603 -332.113246)
			(xy 4.317994 -332.151192) (xy 4.373756 -332.195661) (xy 4.424189 -332.246094) (xy 4.468658 -332.301856)
			(xy 4.506604 -332.362247) (xy 4.537549 -332.426506) (xy 4.561106 -332.493826) (xy 4.576976 -332.563361)
			(xy 4.584962 -332.634235) (xy 4.585462 -332.669896) (xy 4.584962 -332.705557) (xy 5.814814 -332.705557)
			(xy 5.814814 -332.634235) (xy 5.8228 -332.563361) (xy 5.83867 -332.493826) (xy 5.862227 -332.426506)
			(xy 5.893172 -332.362247) (xy 5.931118 -332.301856) (xy 5.975587 -332.246094) (xy 6.02602 -332.195661)
			(xy 6.081782 -332.151192) (xy 6.142173 -332.113246) (xy 6.206432 -332.082301) (xy 6.273752 -332.058744)
			(xy 6.343287 -332.042874) (xy 6.414161 -332.034888) (xy 6.485483 -332.034888) (xy 6.556357 -332.042874)
			(xy 6.625892 -332.058744) (xy 6.693212 -332.082301) (xy 6.757471 -332.113246) (xy 6.817862 -332.151192)
			(xy 6.873624 -332.195661) (xy 6.924057 -332.246094) (xy 6.968526 -332.301856) (xy 7.006472 -332.362247)
			(xy 7.037417 -332.426506) (xy 7.057791 -332.48473) (xy 13.471904 -332.48473) (xy 13.475975 -332.429108)
			(xy 13.488101 -332.374671) (xy 13.508024 -332.32258) (xy 13.53532 -332.273945) (xy 13.569406 -332.229802)
			(xy 13.609555 -332.191093) (xy 13.654913 -332.158642) (xy 13.704513 -332.133141) (xy 13.757297 -332.115134)
			(xy 13.81214 -332.105004) (xy 13.867874 -332.102967) (xy 13.923311 -332.109067) (xy 13.977268 -332.123173)
			(xy 14.028597 -332.144985) (xy 14.076203 -332.174039) (xy 14.119071 -332.209714) (xy 14.156288 -332.251251)
			(xy 14.187061 -332.297764) (xy 14.210733 -332.348261) (xy 14.226801 -332.401668) (xy 14.234921 -332.456844)
			(xy 14.23543 -332.48473) (xy 14.234921 -332.512616) (xy 14.226801 -332.567792) (xy 14.210733 -332.621199)
			(xy 14.187061 -332.671696) (xy 14.156288 -332.718209) (xy 14.119071 -332.759746) (xy 14.076203 -332.795421)
			(xy 14.028597 -332.824475) (xy 13.977268 -332.846287) (xy 13.923311 -332.860393) (xy 13.867874 -332.866493)
			(xy 13.81214 -332.864456) (xy 13.757297 -332.854326) (xy 13.704513 -332.836319) (xy 13.654913 -332.810818)
			(xy 13.609555 -332.778367) (xy 13.569406 -332.739658) (xy 13.53532 -332.695515) (xy 13.508024 -332.64688)
			(xy 13.488101 -332.594789) (xy 13.475975 -332.540352) (xy 13.471904 -332.48473) (xy 7.057791 -332.48473)
			(xy 7.060974 -332.493826) (xy 7.076844 -332.563361) (xy 7.08483 -332.634235) (xy 7.08533 -332.669896)
			(xy 7.08483 -332.705557) (xy 7.076844 -332.776431) (xy 7.060974 -332.845966) (xy 7.037417 -332.913286)
			(xy 7.011636 -332.966822) (xy 11.119356 -332.966822) (xy 11.123427 -332.9112) (xy 11.135553 -332.856763)
			(xy 11.155476 -332.804672) (xy 11.182772 -332.756037) (xy 11.216858 -332.711894) (xy 11.257007 -332.673185)
			(xy 11.302365 -332.640734) (xy 11.351965 -332.615233) (xy 11.404749 -332.597226) (xy 11.459592 -332.587096)
			(xy 11.515326 -332.585059) (xy 11.570763 -332.591159) (xy 11.62472 -332.605265) (xy 11.676049 -332.627077)
			(xy 11.723655 -332.656131) (xy 11.766523 -332.691806) (xy 11.80374 -332.733343) (xy 11.834513 -332.779856)
			(xy 11.858185 -332.830353) (xy 11.874253 -332.88376) (xy 11.882373 -332.938936) (xy 11.882882 -332.966822)
			(xy 11.882373 -332.994708) (xy 11.874253 -333.049884) (xy 11.858185 -333.103291) (xy 11.834513 -333.153788)
			(xy 11.80374 -333.200301) (xy 11.766523 -333.241838) (xy 11.723655 -333.277513) (xy 11.676049 -333.306567)
			(xy 11.62472 -333.328379) (xy 11.570763 -333.342485) (xy 11.515326 -333.348585) (xy 11.459592 -333.346548)
			(xy 11.404749 -333.336418) (xy 11.351965 -333.318411) (xy 11.302365 -333.29291) (xy 11.257007 -333.260459)
			(xy 11.216858 -333.22175) (xy 11.182772 -333.177607) (xy 11.155476 -333.128972) (xy 11.135553 -333.076881)
			(xy 11.123427 -333.022444) (xy 11.119356 -332.966822) (xy 7.011636 -332.966822) (xy 7.006472 -332.977545)
			(xy 6.968526 -333.037936) (xy 6.924057 -333.093698) (xy 6.873624 -333.144131) (xy 6.817862 -333.1886)
			(xy 6.757471 -333.226546) (xy 6.693212 -333.257491) (xy 6.625892 -333.281048) (xy 6.556357 -333.296918)
			(xy 6.485483 -333.304904) (xy 6.414161 -333.304904) (xy 6.343287 -333.296918) (xy 6.273752 -333.281048)
			(xy 6.206432 -333.257491) (xy 6.142173 -333.226546) (xy 6.081782 -333.1886) (xy 6.02602 -333.144131)
			(xy 5.975587 -333.093698) (xy 5.931118 -333.037936) (xy 5.893172 -332.977545) (xy 5.862227 -332.913286)
			(xy 5.83867 -332.845966) (xy 5.8228 -332.776431) (xy 5.814814 -332.705557) (xy 4.584962 -332.705557)
			(xy 4.576976 -332.776431) (xy 4.561106 -332.845966) (xy 4.537549 -332.913286) (xy 4.506604 -332.977545)
			(xy 4.468658 -333.037936) (xy 4.424189 -333.093698) (xy 4.373756 -333.144131) (xy 4.317994 -333.1886)
			(xy 4.257603 -333.226546) (xy 4.193344 -333.257491) (xy 4.126024 -333.281048) (xy 4.056489 -333.296918)
			(xy 3.985615 -333.304904) (xy 3.914293 -333.304904) (xy 3.843419 -333.296918) (xy 3.773884 -333.281048)
			(xy 3.706564 -333.257491) (xy 3.642305 -333.226546) (xy 3.581914 -333.1886) (xy 3.526152 -333.144131)
			(xy 3.475719 -333.093698) (xy 3.43125 -333.037936) (xy 3.393304 -332.977545) (xy 3.362359 -332.913286)
			(xy 3.338802 -332.845966) (xy 3.322932 -332.776431) (xy 3.314946 -332.705557) (xy 1.525016 -332.705557)
			(xy 1.525016 -333.705555) (xy 7.81481 -333.705555) (xy 7.81481 -333.634233) (xy 7.822796 -333.563359)
			(xy 7.838666 -333.493824) (xy 7.862223 -333.426504) (xy 7.893168 -333.362245) (xy 7.931114 -333.301854)
			(xy 7.975583 -333.246092) (xy 8.026016 -333.195659) (xy 8.081778 -333.15119) (xy 8.142169 -333.113244)
			(xy 8.206428 -333.082299) (xy 8.273748 -333.058742) (xy 8.343283 -333.042872) (xy 8.414157 -333.034886)
			(xy 8.485479 -333.034886) (xy 8.556353 -333.042872) (xy 8.625888 -333.058742) (xy 8.693208 -333.082299)
			(xy 8.757467 -333.113244) (xy 8.817858 -333.15119) (xy 8.87362 -333.195659) (xy 8.924053 -333.246092)
			(xy 8.968522 -333.301854) (xy 9.006468 -333.362245) (xy 9.037413 -333.426504) (xy 9.06097 -333.493824)
			(xy 9.07684 -333.563359) (xy 9.084826 -333.634233) (xy 9.085326 -333.669894) (xy 9.084826 -333.705555)
			(xy 9.07684 -333.776429) (xy 9.06097 -333.845964) (xy 9.037413 -333.913284) (xy 9.006468 -333.977543)
			(xy 8.968522 -334.037934) (xy 8.924053 -334.093696) (xy 8.87362 -334.144129) (xy 8.817858 -334.188598)
			(xy 8.761322 -334.224122) (xy 11.550902 -334.224122) (xy 11.554973 -334.1685) (xy 11.567099 -334.114063)
			(xy 11.587022 -334.061972) (xy 11.614318 -334.013337) (xy 11.648404 -333.969194) (xy 11.688553 -333.930485)
			(xy 11.733911 -333.898034) (xy 11.783511 -333.872533) (xy 11.836295 -333.854526) (xy 11.891138 -333.844396)
			(xy 11.946872 -333.842359) (xy 12.002309 -333.848459) (xy 12.056266 -333.862565) (xy 12.107595 -333.884377)
			(xy 12.155201 -333.913431) (xy 12.198069 -333.949106) (xy 12.235286 -333.990643) (xy 12.266059 -334.037156)
			(xy 12.289731 -334.087653) (xy 12.305799 -334.14106) (xy 12.313919 -334.196236) (xy 12.314428 -334.224122)
			(xy 12.313919 -334.252008) (xy 12.305799 -334.307184) (xy 12.289731 -334.360591) (xy 12.266059 -334.411088)
			(xy 12.235286 -334.457601) (xy 12.198069 -334.499138) (xy 12.155201 -334.534813) (xy 12.107595 -334.563867)
			(xy 12.056266 -334.585679) (xy 12.002309 -334.599785) (xy 11.946872 -334.605885) (xy 11.891138 -334.603848)
			(xy 11.836295 -334.593718) (xy 11.783511 -334.575711) (xy 11.733911 -334.55021) (xy 11.688553 -334.517759)
			(xy 11.648404 -334.47905) (xy 11.614318 -334.434907) (xy 11.587022 -334.386272) (xy 11.567099 -334.334181)
			(xy 11.554973 -334.279744) (xy 11.550902 -334.224122) (xy 8.761322 -334.224122) (xy 8.757467 -334.226544)
			(xy 8.693208 -334.257489) (xy 8.625888 -334.281046) (xy 8.556353 -334.296916) (xy 8.485479 -334.304902)
			(xy 8.414157 -334.304902) (xy 8.343283 -334.296916) (xy 8.273748 -334.281046) (xy 8.206428 -334.257489)
			(xy 8.142169 -334.226544) (xy 8.081778 -334.188598) (xy 8.026016 -334.144129) (xy 7.975583 -334.093696)
			(xy 7.931114 -334.037934) (xy 7.893168 -333.977543) (xy 7.862223 -333.913284) (xy 7.838666 -333.845964)
			(xy 7.822796 -333.776429) (xy 7.81481 -333.705555) (xy 1.525016 -333.705555) (xy 1.525016 -334.705553)
			(xy 3.314946 -334.705553) (xy 3.314946 -334.634231) (xy 3.322932 -334.563357) (xy 3.338802 -334.493822)
			(xy 3.362359 -334.426502) (xy 3.393304 -334.362243) (xy 3.43125 -334.301852) (xy 3.475719 -334.24609)
			(xy 3.526152 -334.195657) (xy 3.581914 -334.151188) (xy 3.642305 -334.113242) (xy 3.706564 -334.082297)
			(xy 3.773884 -334.05874) (xy 3.843419 -334.04287) (xy 3.914293 -334.034884) (xy 3.985615 -334.034884)
			(xy 4.056489 -334.04287) (xy 4.126024 -334.05874) (xy 4.193344 -334.082297) (xy 4.257603 -334.113242)
			(xy 4.317994 -334.151188) (xy 4.373756 -334.195657) (xy 4.424189 -334.24609) (xy 4.468658 -334.301852)
			(xy 4.506604 -334.362243) (xy 4.537549 -334.426502) (xy 4.561106 -334.493822) (xy 4.576976 -334.563357)
			(xy 4.584962 -334.634231) (xy 4.585462 -334.669892) (xy 4.584962 -334.705553) (xy 4.576976 -334.776427)
			(xy 4.561106 -334.845962) (xy 4.537549 -334.913282) (xy 4.506604 -334.977541) (xy 4.468658 -335.037932)
			(xy 4.424189 -335.093694) (xy 4.373756 -335.144127) (xy 4.317994 -335.188596) (xy 4.257603 -335.226542)
			(xy 4.193344 -335.257487) (xy 4.126024 -335.281044) (xy 4.056489 -335.296914) (xy 3.985615 -335.3049)
			(xy 3.914293 -335.3049) (xy 3.843419 -335.296914) (xy 3.773884 -335.281044) (xy 3.706564 -335.257487)
			(xy 3.642305 -335.226542) (xy 3.581914 -335.188596) (xy 3.526152 -335.144127) (xy 3.475719 -335.093694)
			(xy 3.43125 -335.037932) (xy 3.393304 -334.977541) (xy 3.362359 -334.913282) (xy 3.338802 -334.845962)
			(xy 3.322932 -334.776427) (xy 3.314946 -334.705553) (xy 1.525016 -334.705553) (xy 1.525016 -334.796892)
			(xy 1.525461 -334.818909) (xy 1.533006 -334.862292) (xy 1.547917 -334.903725) (xy 1.569749 -334.941966)
			(xy 1.597847 -334.97587) (xy 1.631369 -335.004422) (xy 1.669313 -335.026767) (xy 1.71054 -335.042235)
			(xy 1.753818 -335.050363) (xy 1.797848 -335.050908) (xy 1.819656 -335.047844) (xy 1.854312 -335.041075)
			(xy 1.924607 -335.034348) (xy 1.995215 -335.035454) (xy 2.065265 -335.044381) (xy 2.133893 -335.061018)
			(xy 2.200254 -335.08516) (xy 2.26353 -335.116509) (xy 2.322941 -335.154679) (xy 2.377755 -335.199201)
			(xy 2.427295 -335.249523) (xy 2.470952 -335.305028) (xy 2.508187 -335.365029) (xy 2.538541 -335.428789)
			(xy 2.56164 -335.49552) (xy 2.577199 -335.564401) (xy 2.585027 -335.634582) (xy 2.585027 -335.705198)
			(xy 2.584988 -335.705551) (xy 7.81481 -335.705551) (xy 7.81481 -335.634229) (xy 7.822796 -335.563355)
			(xy 7.838666 -335.49382) (xy 7.862223 -335.4265) (xy 7.893168 -335.362241) (xy 7.931114 -335.30185)
			(xy 7.975583 -335.246088) (xy 8.026016 -335.195655) (xy 8.081778 -335.151186) (xy 8.142169 -335.11324)
			(xy 8.206428 -335.082295) (xy 8.273748 -335.058738) (xy 8.343283 -335.042868) (xy 8.414157 -335.034882)
			(xy 8.485479 -335.034882) (xy 8.556353 -335.042868) (xy 8.625888 -335.058738) (xy 8.693208 -335.082295)
			(xy 8.757467 -335.11324) (xy 8.817858 -335.151186) (xy 8.87362 -335.195655) (xy 8.924053 -335.246088)
			(xy 8.968522 -335.30185) (xy 9.006468 -335.362241) (xy 9.037413 -335.4265) (xy 9.06097 -335.49382)
			(xy 9.061039 -335.494122) (xy 11.550902 -335.494122) (xy 11.554973 -335.4385) (xy 11.567099 -335.384063)
			(xy 11.587022 -335.331972) (xy 11.614318 -335.283337) (xy 11.648404 -335.239194) (xy 11.688553 -335.200485)
			(xy 11.733911 -335.168034) (xy 11.783511 -335.142533) (xy 11.836295 -335.124526) (xy 11.891138 -335.114396)
			(xy 11.946872 -335.112359) (xy 12.002309 -335.118459) (xy 12.056266 -335.132565) (xy 12.107595 -335.154377)
			(xy 12.155201 -335.183431) (xy 12.198069 -335.219106) (xy 12.235286 -335.260643) (xy 12.266059 -335.307156)
			(xy 12.289731 -335.357653) (xy 12.305799 -335.41106) (xy 12.313919 -335.466236) (xy 12.314428 -335.494122)
			(xy 12.313919 -335.522008) (xy 12.305799 -335.577184) (xy 12.289731 -335.630591) (xy 12.266059 -335.681088)
			(xy 12.235286 -335.727601) (xy 12.198069 -335.769138) (xy 12.155201 -335.804813) (xy 12.107595 -335.833867)
			(xy 12.056266 -335.855679) (xy 12.002309 -335.869785) (xy 11.946872 -335.875885) (xy 11.891138 -335.873848)
			(xy 11.836295 -335.863718) (xy 11.783511 -335.845711) (xy 11.733911 -335.82021) (xy 11.688553 -335.787759)
			(xy 11.648404 -335.74905) (xy 11.614318 -335.704907) (xy 11.587022 -335.656272) (xy 11.567099 -335.604181)
			(xy 11.554973 -335.549744) (xy 11.550902 -335.494122) (xy 9.061039 -335.494122) (xy 9.07684 -335.563355)
			(xy 9.084826 -335.634229) (xy 9.085326 -335.66989) (xy 9.084826 -335.705551) (xy 9.07684 -335.776425)
			(xy 9.06097 -335.84596) (xy 9.037413 -335.91328) (xy 9.006468 -335.977539) (xy 8.968522 -336.03793)
			(xy 8.924053 -336.093692) (xy 8.87362 -336.144125) (xy 8.817858 -336.188594) (xy 8.757467 -336.22654)
			(xy 8.693208 -336.257485) (xy 8.625888 -336.281042) (xy 8.556353 -336.296912) (xy 8.485479 -336.304898)
			(xy 8.414157 -336.304898) (xy 8.343283 -336.296912) (xy 8.273748 -336.281042) (xy 8.206428 -336.257485)
			(xy 8.142169 -336.22654) (xy 8.081778 -336.188594) (xy 8.026016 -336.144125) (xy 7.975583 -336.093692)
			(xy 7.931114 -336.03793) (xy 7.893168 -335.977539) (xy 7.862223 -335.91328) (xy 7.838666 -335.84596)
			(xy 7.822796 -335.776425) (xy 7.81481 -335.705551) (xy 2.584988 -335.705551) (xy 2.577199 -335.775379)
			(xy 2.56164 -335.84426) (xy 2.538541 -335.910991) (xy 2.508187 -335.974751) (xy 2.470952 -336.034752)
			(xy 2.427295 -336.090257) (xy 2.377755 -336.140579) (xy 2.322941 -336.185101) (xy 2.26353 -336.223271)
			(xy 2.200254 -336.25462) (xy 2.133893 -336.278762) (xy 2.065265 -336.295399) (xy 1.995215 -336.304326)
			(xy 1.924607 -336.305432) (xy 1.854312 -336.298705) (xy 1.819656 -336.291936) (xy 1.797849 -336.288878)
			(xy 1.753823 -336.289433) (xy 1.71055 -336.297567) (xy 1.669328 -336.313039) (xy 1.631389 -336.335384)
			(xy 1.597869 -336.363933) (xy 1.569772 -336.397833) (xy 1.547938 -336.436069) (xy 1.533021 -336.477495)
			(xy 1.525467 -336.520873) (xy 1.525016 -336.542888) (xy 1.525016 -336.705549) (xy 3.314946 -336.705549)
			(xy 3.314946 -336.634227) (xy 3.322932 -336.563353) (xy 3.338802 -336.493818) (xy 3.362359 -336.426498)
			(xy 3.393304 -336.362239) (xy 3.43125 -336.301848) (xy 3.475719 -336.246086) (xy 3.526152 -336.195653)
			(xy 3.581914 -336.151184) (xy 3.642305 -336.113238) (xy 3.706564 -336.082293) (xy 3.773884 -336.058736)
			(xy 3.843419 -336.042866) (xy 3.914293 -336.03488) (xy 3.985615 -336.03488) (xy 4.056489 -336.042866)
			(xy 4.126024 -336.058736) (xy 4.193344 -336.082293) (xy 4.257603 -336.113238) (xy 4.317994 -336.151184)
			(xy 4.373756 -336.195653) (xy 4.424189 -336.246086) (xy 4.468658 -336.301848) (xy 4.506604 -336.362239)
			(xy 4.537549 -336.426498) (xy 4.561106 -336.493818) (xy 4.576976 -336.563353) (xy 4.584962 -336.634227)
			(xy 4.585462 -336.669888) (xy 4.584962 -336.705549) (xy 5.814814 -336.705549) (xy 5.814814 -336.634227)
			(xy 5.8228 -336.563353) (xy 5.83867 -336.493818) (xy 5.862227 -336.426498) (xy 5.893172 -336.362239)
			(xy 5.931118 -336.301848) (xy 5.975587 -336.246086) (xy 6.02602 -336.195653) (xy 6.081782 -336.151184)
			(xy 6.142173 -336.113238) (xy 6.206432 -336.082293) (xy 6.273752 -336.058736) (xy 6.343287 -336.042866)
			(xy 6.414161 -336.03488) (xy 6.485483 -336.03488) (xy 6.556357 -336.042866) (xy 6.625892 -336.058736)
			(xy 6.693212 -336.082293) (xy 6.757471 -336.113238) (xy 6.817862 -336.151184) (xy 6.873624 -336.195653)
			(xy 6.924057 -336.246086) (xy 6.968526 -336.301848) (xy 7.006472 -336.362239) (xy 7.037417 -336.426498)
			(xy 7.060974 -336.493818) (xy 7.076844 -336.563353) (xy 7.08483 -336.634227) (xy 7.08533 -336.669888)
			(xy 7.08483 -336.705549) (xy 7.07823 -336.764122) (xy 11.550902 -336.764122) (xy 11.554973 -336.7085)
			(xy 11.567099 -336.654063) (xy 11.587022 -336.601972) (xy 11.614318 -336.553337) (xy 11.648404 -336.509194)
			(xy 11.688553 -336.470485) (xy 11.733911 -336.438034) (xy 11.783511 -336.412533) (xy 11.836295 -336.394526)
			(xy 11.891138 -336.384396) (xy 11.946872 -336.382359) (xy 12.002309 -336.388459) (xy 12.056266 -336.402565)
			(xy 12.107595 -336.424377) (xy 12.155201 -336.453431) (xy 12.198069 -336.489106) (xy 12.235286 -336.530643)
			(xy 12.266059 -336.577156) (xy 12.289731 -336.627653) (xy 12.305799 -336.68106) (xy 12.313919 -336.736236)
			(xy 12.314428 -336.764122) (xy 12.313919 -336.792008) (xy 12.305799 -336.847184) (xy 12.289731 -336.900591)
			(xy 12.266059 -336.951088) (xy 12.235286 -336.997601) (xy 12.198069 -337.039138) (xy 12.155201 -337.074813)
			(xy 12.107595 -337.103867) (xy 12.056266 -337.125679) (xy 12.002309 -337.139785) (xy 11.946872 -337.145885)
			(xy 11.891138 -337.143848) (xy 11.836295 -337.133718) (xy 11.783511 -337.115711) (xy 11.733911 -337.09021)
			(xy 11.688553 -337.057759) (xy 11.648404 -337.01905) (xy 11.614318 -336.974907) (xy 11.587022 -336.926272)
			(xy 11.567099 -336.874181) (xy 11.554973 -336.819744) (xy 11.550902 -336.764122) (xy 7.07823 -336.764122)
			(xy 7.076844 -336.776423) (xy 7.060974 -336.845958) (xy 7.037417 -336.913278) (xy 7.006472 -336.977537)
			(xy 6.968526 -337.037928) (xy 6.924057 -337.09369) (xy 6.873624 -337.144123) (xy 6.817862 -337.188592)
			(xy 6.757471 -337.226538) (xy 6.693212 -337.257483) (xy 6.625892 -337.28104) (xy 6.556357 -337.29691)
			(xy 6.485483 -337.304896) (xy 6.414161 -337.304896) (xy 6.343287 -337.29691) (xy 6.273752 -337.28104)
			(xy 6.206432 -337.257483) (xy 6.142173 -337.226538) (xy 6.081782 -337.188592) (xy 6.02602 -337.144123)
			(xy 5.975587 -337.09369) (xy 5.931118 -337.037928) (xy 5.893172 -336.977537) (xy 5.862227 -336.913278)
			(xy 5.83867 -336.845958) (xy 5.8228 -336.776423) (xy 5.814814 -336.705549) (xy 4.584962 -336.705549)
			(xy 4.576976 -336.776423) (xy 4.561106 -336.845958) (xy 4.537549 -336.913278) (xy 4.506604 -336.977537)
			(xy 4.468658 -337.037928) (xy 4.424189 -337.09369) (xy 4.373756 -337.144123) (xy 4.317994 -337.188592)
			(xy 4.257603 -337.226538) (xy 4.193344 -337.257483) (xy 4.126024 -337.28104) (xy 4.056489 -337.29691)
			(xy 3.985615 -337.304896) (xy 3.914293 -337.304896) (xy 3.843419 -337.29691) (xy 3.773884 -337.28104)
			(xy 3.706564 -337.257483) (xy 3.642305 -337.226538) (xy 3.581914 -337.188592) (xy 3.526152 -337.144123)
			(xy 3.475719 -337.09369) (xy 3.43125 -337.037928) (xy 3.393304 -336.977537) (xy 3.362359 -336.913278)
			(xy 3.338802 -336.845958) (xy 3.322932 -336.776423) (xy 3.314946 -336.705549) (xy 1.525016 -336.705549)
			(xy 1.525016 -336.796888) (xy 1.525462 -336.818905) (xy 1.533007 -336.862287) (xy 1.547919 -336.903718)
			(xy 1.569751 -336.941958) (xy 1.597849 -336.975862) (xy 1.631371 -337.004413) (xy 1.669314 -337.026757)
			(xy 1.710541 -337.042225) (xy 1.753818 -337.050353) (xy 1.797848 -337.050898) (xy 1.819656 -337.04784)
			(xy 1.854312 -337.041071) (xy 1.924607 -337.034344) (xy 1.995215 -337.035451) (xy 2.065264 -337.044378)
			(xy 2.133892 -337.061015) (xy 2.200253 -337.085157) (xy 2.263529 -337.116506) (xy 2.32294 -337.154676)
			(xy 2.377753 -337.199197) (xy 2.427293 -337.24952) (xy 2.47095 -337.305025) (xy 2.508184 -337.365026)
			(xy 2.538538 -337.428786) (xy 2.561637 -337.495517) (xy 2.577197 -337.564397) (xy 2.585025 -337.634578)
			(xy 2.585025 -337.705194) (xy 2.584986 -337.705547) (xy 7.81481 -337.705547) (xy 7.81481 -337.634225)
			(xy 7.822796 -337.563351) (xy 7.838666 -337.493816) (xy 7.862223 -337.426496) (xy 7.893168 -337.362237)
			(xy 7.931114 -337.301846) (xy 7.975583 -337.246084) (xy 8.026016 -337.195651) (xy 8.081778 -337.151182)
			(xy 8.142169 -337.113236) (xy 8.206428 -337.082291) (xy 8.273748 -337.058734) (xy 8.343283 -337.042864)
			(xy 8.414157 -337.034878) (xy 8.485479 -337.034878) (xy 8.556353 -337.042864) (xy 8.625888 -337.058734)
			(xy 8.693208 -337.082291) (xy 8.757467 -337.113236) (xy 8.817858 -337.151182) (xy 8.87362 -337.195651)
			(xy 8.924053 -337.246084) (xy 8.968522 -337.301846) (xy 9.006468 -337.362237) (xy 9.037413 -337.426496)
			(xy 9.06097 -337.493816) (xy 9.07684 -337.563351) (xy 9.084826 -337.634225) (xy 9.085326 -337.669886)
			(xy 9.084826 -337.705547) (xy 9.07684 -337.776421) (xy 9.06097 -337.845956) (xy 9.037413 -337.913276)
			(xy 9.006468 -337.977535) (xy 8.970912 -338.034122) (xy 11.550902 -338.034122) (xy 11.554973 -337.9785)
			(xy 11.567099 -337.924063) (xy 11.587022 -337.871972) (xy 11.614318 -337.823337) (xy 11.648404 -337.779194)
			(xy 11.688553 -337.740485) (xy 11.733911 -337.708034) (xy 11.783511 -337.682533) (xy 11.836295 -337.664526)
			(xy 11.891138 -337.654396) (xy 11.946872 -337.652359) (xy 12.002309 -337.658459) (xy 12.056266 -337.672565)
			(xy 12.107595 -337.694377) (xy 12.155201 -337.723431) (xy 12.198069 -337.759106) (xy 12.235286 -337.800643)
			(xy 12.266059 -337.847156) (xy 12.289731 -337.897653) (xy 12.305799 -337.95106) (xy 12.313919 -338.006236)
			(xy 12.314428 -338.034122) (xy 12.313919 -338.062008) (xy 12.305799 -338.117184) (xy 12.289731 -338.170591)
			(xy 12.266059 -338.221088) (xy 12.235286 -338.267601) (xy 12.198069 -338.309138) (xy 12.155201 -338.344813)
			(xy 12.107595 -338.373867) (xy 12.056266 -338.395679) (xy 12.002309 -338.409785) (xy 11.946872 -338.415885)
			(xy 11.891138 -338.413848) (xy 11.836295 -338.403718) (xy 11.783511 -338.385711) (xy 11.733911 -338.36021)
			(xy 11.688553 -338.327759) (xy 11.648404 -338.28905) (xy 11.614318 -338.244907) (xy 11.587022 -338.196272)
			(xy 11.567099 -338.144181) (xy 11.554973 -338.089744) (xy 11.550902 -338.034122) (xy 8.970912 -338.034122)
			(xy 8.968522 -338.037926) (xy 8.924053 -338.093688) (xy 8.87362 -338.144121) (xy 8.817858 -338.18859)
			(xy 8.757467 -338.226536) (xy 8.693208 -338.257481) (xy 8.625888 -338.281038) (xy 8.556353 -338.296908)
			(xy 8.485479 -338.304894) (xy 8.414157 -338.304894) (xy 8.343283 -338.296908) (xy 8.273748 -338.281038)
			(xy 8.206428 -338.257481) (xy 8.142169 -338.226536) (xy 8.081778 -338.18859) (xy 8.026016 -338.144121)
			(xy 7.975583 -338.093688) (xy 7.931114 -338.037926) (xy 7.893168 -337.977535) (xy 7.862223 -337.913276)
			(xy 7.838666 -337.845956) (xy 7.822796 -337.776421) (xy 7.81481 -337.705547) (xy 2.584986 -337.705547)
			(xy 2.577197 -337.775375) (xy 2.561637 -337.844255) (xy 2.538538 -337.910986) (xy 2.508184 -337.974746)
			(xy 2.47095 -338.034747) (xy 2.427293 -338.090252) (xy 2.377753 -338.140575) (xy 2.32294 -338.185096)
			(xy 2.263529 -338.223266) (xy 2.200253 -338.254615) (xy 2.133892 -338.278757) (xy 2.065264 -338.295394)
			(xy 1.995215 -338.304321) (xy 1.924607 -338.305428) (xy 1.854312 -338.298701) (xy 1.819656 -338.291932)
			(xy 1.797849 -338.288874) (xy 1.753823 -338.289429) (xy 1.710551 -338.297563) (xy 1.669329 -338.313035)
			(xy 1.63139 -338.33538) (xy 1.597871 -338.36393) (xy 1.569774 -338.39783) (xy 1.547941 -338.436065)
			(xy 1.533025 -338.477491) (xy 1.525473 -338.520869) (xy 1.525016 -338.542884) (xy 1.525016 -338.705545)
			(xy 3.314946 -338.705545) (xy 3.314946 -338.634223) (xy 3.322932 -338.563349) (xy 3.338802 -338.493814)
			(xy 3.362359 -338.426494) (xy 3.393304 -338.362235) (xy 3.43125 -338.301844) (xy 3.475719 -338.246082)
			(xy 3.526152 -338.195649) (xy 3.581914 -338.15118) (xy 3.642305 -338.113234) (xy 3.706564 -338.082289)
			(xy 3.773884 -338.058732) (xy 3.843419 -338.042862) (xy 3.914293 -338.034876) (xy 3.985615 -338.034876)
			(xy 4.056489 -338.042862) (xy 4.126024 -338.058732) (xy 4.193344 -338.082289) (xy 4.257603 -338.113234)
			(xy 4.317994 -338.15118) (xy 4.373756 -338.195649) (xy 4.424189 -338.246082) (xy 4.468658 -338.301844)
			(xy 4.506604 -338.362235) (xy 4.537549 -338.426494) (xy 4.561106 -338.493814) (xy 4.576976 -338.563349)
			(xy 4.584962 -338.634223) (xy 4.585462 -338.669884) (xy 4.584962 -338.705545) (xy 5.814814 -338.705545)
			(xy 5.814814 -338.634223) (xy 5.8228 -338.563349) (xy 5.83867 -338.493814) (xy 5.862227 -338.426494)
			(xy 5.893172 -338.362235) (xy 5.931118 -338.301844) (xy 5.975587 -338.246082) (xy 6.02602 -338.195649)
			(xy 6.081782 -338.15118) (xy 6.142173 -338.113234) (xy 6.206432 -338.082289) (xy 6.273752 -338.058732)
			(xy 6.343287 -338.042862) (xy 6.414161 -338.034876) (xy 6.485483 -338.034876) (xy 6.556357 -338.042862)
			(xy 6.625892 -338.058732) (xy 6.693212 -338.082289) (xy 6.757471 -338.113234) (xy 6.817862 -338.15118)
			(xy 6.873624 -338.195649) (xy 6.924057 -338.246082) (xy 6.968526 -338.301844) (xy 7.006472 -338.362235)
			(xy 7.037417 -338.426494) (xy 7.060974 -338.493814) (xy 7.076844 -338.563349) (xy 7.08483 -338.634223)
			(xy 7.08533 -338.669884) (xy 7.08483 -338.705545) (xy 7.076844 -338.776419) (xy 7.060974 -338.845954)
			(xy 7.037417 -338.913274) (xy 7.006472 -338.977533) (xy 6.968526 -339.037924) (xy 6.924057 -339.093686)
			(xy 6.873624 -339.144119) (xy 6.817862 -339.188588) (xy 6.757471 -339.226534) (xy 6.693212 -339.257479)
			(xy 6.625892 -339.281036) (xy 6.556357 -339.296906) (xy 6.485483 -339.304892) (xy 6.414161 -339.304892)
			(xy 6.343287 -339.296906) (xy 6.273752 -339.281036) (xy 6.206432 -339.257479) (xy 6.142173 -339.226534)
			(xy 6.081782 -339.188588) (xy 6.02602 -339.144119) (xy 5.975587 -339.093686) (xy 5.931118 -339.037924)
			(xy 5.893172 -338.977533) (xy 5.862227 -338.913274) (xy 5.83867 -338.845954) (xy 5.8228 -338.776419)
			(xy 5.814814 -338.705545) (xy 4.584962 -338.705545) (xy 4.576976 -338.776419) (xy 4.561106 -338.845954)
			(xy 4.537549 -338.913274) (xy 4.506604 -338.977533) (xy 4.468658 -339.037924) (xy 4.424189 -339.093686)
			(xy 4.373756 -339.144119) (xy 4.317994 -339.188588) (xy 4.257603 -339.226534) (xy 4.193344 -339.257479)
			(xy 4.126024 -339.281036) (xy 4.056489 -339.296906) (xy 3.985615 -339.304892) (xy 3.914293 -339.304892)
			(xy 3.843419 -339.296906) (xy 3.773884 -339.281036) (xy 3.706564 -339.257479) (xy 3.642305 -339.226534)
			(xy 3.581914 -339.188588) (xy 3.526152 -339.144119) (xy 3.475719 -339.093686) (xy 3.43125 -339.037924)
			(xy 3.393304 -338.977533) (xy 3.362359 -338.913274) (xy 3.338802 -338.845954) (xy 3.322932 -338.776419)
			(xy 3.314946 -338.705545) (xy 1.525016 -338.705545) (xy 1.525016 -338.796884) (xy 1.525461 -338.818901)
			(xy 1.533006 -338.862284) (xy 1.547918 -338.903716) (xy 1.569749 -338.941957) (xy 1.597847 -338.97586)
			(xy 1.63137 -339.004412) (xy 1.669313 -339.026757) (xy 1.710541 -339.042225) (xy 1.753818 -339.050353)
			(xy 1.797848 -339.050898) (xy 1.819656 -339.047836) (xy 1.854312 -339.041067) (xy 1.924607 -339.03434)
			(xy 1.995214 -339.035446) (xy 2.065264 -339.044373) (xy 2.133892 -339.061009) (xy 2.200253 -339.085151)
			(xy 2.263529 -339.116501) (xy 2.32294 -339.154671) (xy 2.377753 -339.199192) (xy 2.427293 -339.249514)
			(xy 2.47095 -339.305019) (xy 2.508185 -339.36502) (xy 2.538539 -339.428779) (xy 2.561638 -339.49551)
			(xy 2.577197 -339.564391) (xy 2.585025 -339.634572) (xy 2.585025 -339.705188) (xy 2.577197 -339.775368)
			(xy 2.561638 -339.844249) (xy 2.538539 -339.91098) (xy 2.508185 -339.974739) (xy 2.47095 -340.034741)
			(xy 2.427294 -340.090245) (xy 2.377754 -340.140568) (xy 2.32294 -340.185089) (xy 2.26353 -340.223259)
			(xy 2.200254 -340.254608) (xy 2.133893 -340.27875) (xy 2.065265 -340.295387) (xy 1.995215 -340.304314)
			(xy 1.924608 -340.30542) (xy 1.854313 -340.298693) (xy 1.819656 -340.291928) (xy 1.797849 -340.28887)
			(xy 1.753823 -340.289425) (xy 1.710551 -340.297559) (xy 1.669328 -340.313031) (xy 1.631389 -340.335376)
			(xy 1.59787 -340.363926) (xy 1.569773 -340.397825) (xy 1.547939 -340.436061) (xy 1.533022 -340.477487)
			(xy 1.525469 -340.520865) (xy 1.525016 -340.54288) (xy 1.525016 -342.652033) (xy 3.314157 -342.652033)
			(xy 3.32012 -342.581187) (xy 3.333954 -342.511448) (xy 3.355484 -342.44369) (xy 3.384443 -342.378758)
			(xy 3.420469 -342.317464) (xy 3.46311 -342.260574) (xy 3.511835 -342.208799) (xy 3.566034 -342.162786)
			(xy 3.62503 -342.12311) (xy 3.65633 -342.10625) (xy 3.675751 -342.095588) (xy 3.710895 -342.068619)
			(xy 3.740831 -342.035964) (xy 3.764651 -341.998614) (xy 3.781635 -341.957699) (xy 3.791266 -341.914459)
			(xy 3.793255 -341.870204) (xy 3.78754 -341.826274) (xy 3.774295 -341.784001) (xy 3.764534 -341.764112)
			(xy 3.739522 -341.714851) (xy 3.695492 -341.613513) (xy 3.658484 -341.509405) (xy 3.628672 -341.403013)
			(xy 3.606195 -341.294833) (xy 3.591158 -341.185371) (xy 3.583631 -341.075137) (xy 3.583178 -341.019892)
			(xy 3.583683 -340.962517) (xy 3.591825 -340.848057) (xy 3.608063 -340.734463) (xy 3.632316 -340.622306)
			(xy 3.664462 -340.512151) (xy 3.704339 -340.404554) (xy 3.751746 -340.300055) (xy 3.806444 -340.199181)
			(xy 3.868157 -340.10244) (xy 3.936576 -340.010319) (xy 4.011356 -339.923282) (xy 4.092119 -339.841768)
			(xy 4.17846 -339.766186) (xy 4.269943 -339.696917) (xy 4.366108 -339.63431) (xy 4.466471 -339.57868)
			(xy 4.570527 -339.530308) (xy 4.67775 -339.489436) (xy 4.787603 -339.456272) (xy 4.89953 -339.430981)
			(xy 5.012969 -339.413691) (xy 5.127349 -339.40449) (xy 5.242093 -339.403423) (xy 5.356624 -339.410496)
			(xy 5.470366 -339.425673) (xy 5.582744 -339.448878) (xy 5.693194 -339.479993) (xy 5.801159 -339.518864)
			(xy 5.906096 -339.565292) (xy 6.007476 -339.619046) (xy 6.104789 -339.679854) (xy 6.140061 -339.705543)
			(xy 7.81481 -339.705543) (xy 7.81481 -339.634221) (xy 7.822796 -339.563347) (xy 7.838666 -339.493812)
			(xy 7.862223 -339.426492) (xy 7.893168 -339.362233) (xy 7.931114 -339.301842) (xy 7.975583 -339.24608)
			(xy 8.026016 -339.195647) (xy 8.081778 -339.151178) (xy 8.142169 -339.113232) (xy 8.206428 -339.082287)
			(xy 8.273748 -339.05873) (xy 8.343283 -339.04286) (xy 8.414157 -339.034874) (xy 8.485479 -339.034874)
			(xy 8.556353 -339.04286) (xy 8.625888 -339.05873) (xy 8.693208 -339.082287) (xy 8.757467 -339.113232)
			(xy 8.817858 -339.151178) (xy 8.87362 -339.195647) (xy 8.924053 -339.24608) (xy 8.968522 -339.301842)
			(xy 8.969955 -339.304122) (xy 11.550902 -339.304122) (xy 11.554973 -339.2485) (xy 11.567099 -339.194063)
			(xy 11.587022 -339.141972) (xy 11.614318 -339.093337) (xy 11.648404 -339.049194) (xy 11.688553 -339.010485)
			(xy 11.733911 -338.978034) (xy 11.783511 -338.952533) (xy 11.836295 -338.934526) (xy 11.891138 -338.924396)
			(xy 11.946872 -338.922359) (xy 12.002309 -338.928459) (xy 12.056266 -338.942565) (xy 12.107595 -338.964377)
			(xy 12.155201 -338.993431) (xy 12.198069 -339.029106) (xy 12.235286 -339.070643) (xy 12.266059 -339.117156)
			(xy 12.289731 -339.167653) (xy 12.305799 -339.22106) (xy 12.313919 -339.276236) (xy 12.314428 -339.304122)
			(xy 12.313919 -339.332008) (xy 12.305799 -339.387184) (xy 12.289731 -339.440591) (xy 12.266059 -339.491088)
			(xy 12.235286 -339.537601) (xy 12.198069 -339.579138) (xy 12.155201 -339.614813) (xy 12.107595 -339.643867)
			(xy 12.056266 -339.665679) (xy 12.002309 -339.679785) (xy 11.946872 -339.685885) (xy 11.891138 -339.683848)
			(xy 11.836295 -339.673718) (xy 11.783511 -339.655711) (xy 11.733911 -339.63021) (xy 11.688553 -339.597759)
			(xy 11.648404 -339.55905) (xy 11.614318 -339.514907) (xy 11.587022 -339.466272) (xy 11.567099 -339.414181)
			(xy 11.554973 -339.359744) (xy 11.550902 -339.304122) (xy 8.969955 -339.304122) (xy 9.006468 -339.362233)
			(xy 9.037413 -339.426492) (xy 9.06097 -339.493812) (xy 9.07684 -339.563347) (xy 9.084826 -339.634221)
			(xy 9.085326 -339.669882) (xy 9.084826 -339.705543) (xy 9.07684 -339.776417) (xy 9.06097 -339.845952)
			(xy 9.037413 -339.913272) (xy 9.006468 -339.977531) (xy 8.968522 -340.037922) (xy 8.924053 -340.093684)
			(xy 8.87362 -340.144117) (xy 8.817858 -340.188586) (xy 8.757467 -340.226532) (xy 8.693208 -340.257477)
			(xy 8.625888 -340.281034) (xy 8.556353 -340.296904) (xy 8.485479 -340.30489) (xy 8.414157 -340.30489)
			(xy 8.343283 -340.296904) (xy 8.273748 -340.281034) (xy 8.206428 -340.257477) (xy 8.142169 -340.226532)
			(xy 8.081778 -340.188586) (xy 8.026016 -340.144117) (xy 7.975583 -340.093684) (xy 7.931114 -340.037922)
			(xy 7.893168 -339.977531) (xy 7.862223 -339.913272) (xy 7.838666 -339.845952) (xy 7.822796 -339.776417)
			(xy 7.81481 -339.705543) (xy 6.140061 -339.705543) (xy 6.197545 -339.747409) (xy 6.285277 -339.821373)
			(xy 6.367542 -339.901371) (xy 6.443927 -339.987003) (xy 6.514047 -340.077835) (xy 6.577549 -340.173412)
			(xy 6.634114 -340.273251) (xy 6.683456 -340.37685) (xy 6.725326 -340.483687) (xy 6.753553 -340.574122)
			(xy 11.550902 -340.574122) (xy 11.554973 -340.5185) (xy 11.567099 -340.464063) (xy 11.587022 -340.411972)
			(xy 11.614318 -340.363337) (xy 11.648404 -340.319194) (xy 11.688553 -340.280485) (xy 11.733911 -340.248034)
			(xy 11.783511 -340.222533) (xy 11.836295 -340.204526) (xy 11.891138 -340.194396) (xy 11.946872 -340.192359)
			(xy 12.002309 -340.198459) (xy 12.056266 -340.212565) (xy 12.107595 -340.234377) (xy 12.155201 -340.263431)
			(xy 12.198069 -340.299106) (xy 12.235286 -340.340643) (xy 12.266059 -340.387156) (xy 12.289731 -340.437653)
			(xy 12.305799 -340.49106) (xy 12.313919 -340.546236) (xy 12.314428 -340.574122) (xy 12.313919 -340.602008)
			(xy 12.305799 -340.657184) (xy 12.289731 -340.710591) (xy 12.266059 -340.761088) (xy 12.235286 -340.807601)
			(xy 12.198069 -340.849138) (xy 12.155201 -340.884813) (xy 12.107595 -340.913867) (xy 12.056266 -340.935679)
			(xy 12.002309 -340.949785) (xy 11.946872 -340.955885) (xy 11.891138 -340.953848) (xy 11.836295 -340.943718)
			(xy 11.783511 -340.925711) (xy 11.733911 -340.90021) (xy 11.688553 -340.867759) (xy 11.648404 -340.82905)
			(xy 11.614318 -340.784907) (xy 11.587022 -340.736272) (xy 11.567099 -340.684181) (xy 11.554973 -340.629744)
			(xy 11.550902 -340.574122) (xy 6.753553 -340.574122) (xy 6.759515 -340.593225) (xy 6.78585 -340.704911)
			(xy 6.804198 -340.818184) (xy 6.814468 -340.932473) (xy 6.816606 -341.047202) (xy 6.810603 -341.161795)
			(xy 6.796489 -341.275672) (xy 6.774334 -341.388263) (xy 6.744251 -341.498998) (xy 6.706391 -341.607322)
			(xy 6.660944 -341.712688) (xy 6.634988 -341.763858) (xy 6.625193 -341.783747) (xy 6.611932 -341.826049)
			(xy 6.609578 -341.844122) (xy 11.550902 -341.844122) (xy 11.554973 -341.7885) (xy 11.567099 -341.734063)
			(xy 11.587022 -341.681972) (xy 11.614318 -341.633337) (xy 11.648404 -341.589194) (xy 11.688553 -341.550485)
			(xy 11.733911 -341.518034) (xy 11.783511 -341.492533) (xy 11.836295 -341.474526) (xy 11.891138 -341.464396)
			(xy 11.946872 -341.462359) (xy 12.002309 -341.468459) (xy 12.056266 -341.482565) (xy 12.107595 -341.504377)
			(xy 12.155201 -341.533431) (xy 12.198069 -341.569106) (xy 12.235286 -341.610643) (xy 12.266059 -341.657156)
			(xy 12.289731 -341.707653) (xy 12.305799 -341.76106) (xy 12.313919 -341.816236) (xy 12.314428 -341.844122)
			(xy 12.313919 -341.872008) (xy 12.305799 -341.927184) (xy 12.289731 -341.980591) (xy 12.266059 -342.031088)
			(xy 12.235286 -342.077601) (xy 12.198069 -342.119138) (xy 12.155201 -342.154813) (xy 12.107595 -342.183867)
			(xy 12.056266 -342.205679) (xy 12.002309 -342.219785) (xy 11.946872 -342.225885) (xy 11.891138 -342.223848)
			(xy 11.836295 -342.213718) (xy 11.783511 -342.195711) (xy 11.733911 -342.17021) (xy 11.688553 -342.137759)
			(xy 11.648404 -342.09905) (xy 11.614318 -342.054907) (xy 11.587022 -342.006272) (xy 11.567099 -341.954181)
			(xy 11.554973 -341.899744) (xy 11.550902 -341.844122) (xy 6.609578 -341.844122) (xy 6.606207 -341.87001)
			(xy 6.608191 -341.914297) (xy 6.617823 -341.95757) (xy 6.634812 -341.998517) (xy 6.658643 -342.035899)
			(xy 6.688594 -342.068583) (xy 6.723758 -342.095579) (xy 6.743192 -342.10625) (xy 6.774485 -342.123119)
			(xy 6.833489 -342.162778) (xy 6.887697 -342.208775) (xy 6.936433 -342.260536) (xy 6.979086 -342.317413)
			(xy 7.015123 -342.378696) (xy 7.044095 -342.443618) (xy 7.065639 -342.511368) (xy 7.079486 -342.5811)
			(xy 7.085463 -342.651942) (xy 7.083495 -342.723008) (xy 7.073607 -342.793411) (xy 7.055922 -342.86227)
			(xy 7.030662 -342.928724) (xy 6.998141 -342.991944) (xy 6.958768 -343.051138) (xy 6.913032 -343.105568)
			(xy 6.861507 -343.154552) (xy 6.804837 -343.197479) (xy 6.743729 -343.233812) (xy 6.678947 -343.263097)
			(xy 6.611301 -343.284967) (xy 6.541637 -343.299151) (xy 6.470825 -343.305469) (xy 6.39975 -343.303844)
			(xy 6.3293 -343.294296) (xy 6.260357 -343.276943) (xy 6.193781 -343.252004) (xy 6.130406 -343.219789)
			(xy 6.071022 -343.180701) (xy 6.016373 -343.135229) (xy 5.96714 -343.083941) (xy 5.92394 -343.027478)
			(xy 5.887313 -342.966546) (xy 5.857716 -342.901906) (xy 5.835519 -342.834367) (xy 5.827776 -342.79967)
			(xy 5.822798 -342.778068) (xy 5.806347 -342.736906) (xy 5.783004 -342.699222) (xy 5.753478 -342.66616)
			(xy 5.718664 -342.63872) (xy 5.679617 -342.617737) (xy 5.637523 -342.603845) (xy 5.593656 -342.597466)
			(xy 5.549349 -342.598794) (xy 5.527548 -342.60282) (xy 5.473606 -342.613548) (xy 5.364635 -342.628518)
			(xy 5.254898 -342.636041) (xy 5.144904 -342.636082) (xy 5.035162 -342.628641) (xy 4.92618 -342.613752)
			(xy 4.872228 -342.603074) (xy 4.850439 -342.599028) (xy 4.806148 -342.597667) (xy 4.762293 -342.604013)
			(xy 4.720204 -342.617873) (xy 4.681159 -342.638827) (xy 4.646344 -342.666239) (xy 4.616813 -342.699278)
			(xy 4.593465 -342.736939) (xy 4.577006 -342.778082) (xy 4.572 -342.79967) (xy 4.564252 -342.834367)
			(xy 4.542053 -342.90191) (xy 4.512454 -342.966552) (xy 4.475825 -343.027487) (xy 4.432624 -343.083953)
			(xy 4.38339 -343.135245) (xy 4.328739 -343.18072) (xy 4.269354 -343.219812) (xy 4.205977 -343.252031)
			(xy 4.139399 -343.276976) (xy 4.070454 -343.294333) (xy 4.000002 -343.303887) (xy 3.928924 -343.305517)
			(xy 3.858108 -343.299204) (xy 3.788439 -343.285026) (xy 3.720787 -343.263161) (xy 3.655999 -343.233882)
			(xy 3.594884 -343.197555) (xy 3.538206 -343.154633) (xy 3.486672 -343.105653) (xy 3.440927 -343.051227)
			(xy 3.401542 -342.992036) (xy 3.36901 -342.928818) (xy 3.343738 -342.862365) (xy 3.32604 -342.793506)
			(xy 3.316139 -342.723102) (xy 3.314157 -342.652033) (xy 1.525016 -342.652033) (xy 1.525016 -342.796876)
			(xy 1.525462 -342.818893) (xy 1.533007 -342.862275) (xy 1.547918 -342.903707) (xy 1.56975 -342.941948)
			(xy 1.597848 -342.975851) (xy 1.63137 -343.004403) (xy 1.669314 -343.026747) (xy 1.710541 -343.042215)
			(xy 1.753818 -343.050343) (xy 1.797848 -343.050888) (xy 1.819656 -343.047828) (xy 1.854312 -343.041059)
			(xy 1.924607 -343.034332) (xy 1.995215 -343.035439) (xy 2.065264 -343.044366) (xy 2.133892 -343.061003)
			(xy 2.200253 -343.085145) (xy 2.263529 -343.116494) (xy 2.32294 -343.154664) (xy 2.377753 -343.199185)
			(xy 2.427293 -343.249508) (xy 2.47095 -343.305013) (xy 2.508184 -343.365014) (xy 2.538538 -343.428774)
			(xy 2.561637 -343.495505) (xy 2.577197 -343.564385) (xy 2.585025 -343.634566) (xy 2.585025 -343.705182)
			(xy 2.584986 -343.705535) (xy 7.81481 -343.705535) (xy 7.81481 -343.634213) (xy 7.822796 -343.563339)
			(xy 7.838666 -343.493804) (xy 7.862223 -343.426484) (xy 7.893168 -343.362225) (xy 7.931114 -343.301834)
			(xy 7.975583 -343.246072) (xy 8.026016 -343.195639) (xy 8.081778 -343.15117) (xy 8.142169 -343.113224)
			(xy 8.206428 -343.082279) (xy 8.273748 -343.058722) (xy 8.343283 -343.042852) (xy 8.414157 -343.034866)
			(xy 8.485479 -343.034866) (xy 8.556353 -343.042852) (xy 8.625888 -343.058722) (xy 8.693208 -343.082279)
			(xy 8.757467 -343.113224) (xy 8.817858 -343.15117) (xy 8.87362 -343.195639) (xy 8.924053 -343.246072)
			(xy 8.968522 -343.301834) (xy 9.006468 -343.362225) (xy 9.037413 -343.426484) (xy 9.06097 -343.493804)
			(xy 9.07684 -343.563339) (xy 9.084826 -343.634213) (xy 9.085326 -343.669874) (xy 9.084826 -343.705535)
			(xy 9.07684 -343.776409) (xy 9.06097 -343.845944) (xy 9.037413 -343.913264) (xy 9.006468 -343.977523)
			(xy 8.968522 -344.037914) (xy 8.924053 -344.093676) (xy 8.87362 -344.144109) (xy 8.817858 -344.188578)
			(xy 8.757467 -344.226524) (xy 8.693208 -344.257469) (xy 8.625888 -344.281026) (xy 8.556353 -344.296896)
			(xy 8.485479 -344.304882) (xy 8.414157 -344.304882) (xy 8.343283 -344.296896) (xy 8.273748 -344.281026)
			(xy 8.206428 -344.257469) (xy 8.142169 -344.226524) (xy 8.081778 -344.188578) (xy 8.026016 -344.144109)
			(xy 7.975583 -344.093676) (xy 7.931114 -344.037914) (xy 7.893168 -343.977523) (xy 7.862223 -343.913264)
			(xy 7.838666 -343.845944) (xy 7.822796 -343.776409) (xy 7.81481 -343.705535) (xy 2.584986 -343.705535)
			(xy 2.577197 -343.775363) (xy 2.561637 -343.844243) (xy 2.538538 -343.910974) (xy 2.508184 -343.974734)
			(xy 2.47095 -344.034735) (xy 2.427293 -344.09024) (xy 2.377753 -344.140563) (xy 2.32294 -344.185084)
			(xy 2.263529 -344.223254) (xy 2.200253 -344.254603) (xy 2.133892 -344.278745) (xy 2.065264 -344.295382)
			(xy 1.995215 -344.304309) (xy 1.924607 -344.305416) (xy 1.854312 -344.298689) (xy 1.819656 -344.29192)
			(xy 1.797849 -344.288862) (xy 1.753823 -344.289417) (xy 1.710551 -344.297551) (xy 1.669329 -344.313023)
			(xy 1.63139 -344.335368) (xy 1.59787 -344.363918) (xy 1.569773 -344.397817) (xy 1.54794 -344.436053)
			(xy 1.533024 -344.477479) (xy 1.525471 -344.520857) (xy 1.525016 -344.542872) (xy 1.525016 -344.705533)
			(xy 5.814814 -344.705533) (xy 5.814814 -344.634211) (xy 5.8228 -344.563337) (xy 5.83867 -344.493802)
			(xy 5.862227 -344.426482) (xy 5.893172 -344.362223) (xy 5.931118 -344.301832) (xy 5.975587 -344.24607)
			(xy 6.02602 -344.195637) (xy 6.081782 -344.151168) (xy 6.142173 -344.113222) (xy 6.206432 -344.082277)
			(xy 6.273752 -344.05872) (xy 6.343287 -344.04285) (xy 6.414161 -344.034864) (xy 6.485483 -344.034864)
			(xy 6.556357 -344.04285) (xy 6.625892 -344.05872) (xy 6.693212 -344.082277) (xy 6.757471 -344.113222)
			(xy 6.817862 -344.151168) (xy 6.873624 -344.195637) (xy 6.924057 -344.24607) (xy 6.968526 -344.301832)
			(xy 7.006472 -344.362223) (xy 7.037417 -344.426482) (xy 7.060974 -344.493802) (xy 7.076844 -344.563337)
			(xy 7.08483 -344.634211) (xy 7.08533 -344.669872) (xy 7.08483 -344.705533) (xy 7.076844 -344.776407)
			(xy 7.060974 -344.845942) (xy 7.037417 -344.913262) (xy 7.006472 -344.977521) (xy 6.968526 -345.037912)
			(xy 6.924057 -345.093674) (xy 6.873624 -345.144107) (xy 6.817862 -345.188576) (xy 6.757471 -345.226522)
			(xy 6.693212 -345.257467) (xy 6.625892 -345.281024) (xy 6.556357 -345.296894) (xy 6.485483 -345.30488)
			(xy 6.414161 -345.30488) (xy 6.343287 -345.296894) (xy 6.273752 -345.281024) (xy 6.206432 -345.257467)
			(xy 6.142173 -345.226522) (xy 6.081782 -345.188576) (xy 6.02602 -345.144107) (xy 5.975587 -345.093674)
			(xy 5.931118 -345.037912) (xy 5.893172 -344.977521) (xy 5.862227 -344.913262) (xy 5.83867 -344.845942)
			(xy 5.8228 -344.776407) (xy 5.814814 -344.705533) (xy 1.525016 -344.705533) (xy 1.525016 -346.705529)
			(xy 5.814814 -346.705529) (xy 5.814814 -346.634207) (xy 5.8228 -346.563333) (xy 5.83867 -346.493798)
			(xy 5.862227 -346.426478) (xy 5.893172 -346.362219) (xy 5.931118 -346.301828) (xy 5.975587 -346.246066)
			(xy 6.02602 -346.195633) (xy 6.081782 -346.151164) (xy 6.142173 -346.113218) (xy 6.206432 -346.082273)
			(xy 6.273752 -346.058716) (xy 6.343287 -346.042846) (xy 6.414161 -346.03486) (xy 6.485483 -346.03486)
			(xy 6.556357 -346.042846) (xy 6.625892 -346.058716) (xy 6.693212 -346.082273) (xy 6.757471 -346.113218)
			(xy 6.817862 -346.151164) (xy 6.873624 -346.195633) (xy 6.924057 -346.246066) (xy 6.968526 -346.301828)
			(xy 7.006472 -346.362219) (xy 7.037417 -346.426478) (xy 7.060974 -346.493798) (xy 7.076844 -346.563333)
			(xy 7.08483 -346.634207) (xy 7.08533 -346.669868) (xy 7.08483 -346.705529) (xy 7.076844 -346.776403)
			(xy 7.060974 -346.845938) (xy 7.037417 -346.913258) (xy 7.006472 -346.977517) (xy 6.968526 -347.037908)
			(xy 6.924057 -347.09367) (xy 6.873624 -347.144103) (xy 6.817862 -347.188572) (xy 6.757471 -347.226518)
			(xy 6.693212 -347.257463) (xy 6.625892 -347.28102) (xy 6.556357 -347.29689) (xy 6.485483 -347.304876)
			(xy 6.414161 -347.304876) (xy 6.343287 -347.29689) (xy 6.273752 -347.28102) (xy 6.206432 -347.257463)
			(xy 6.142173 -347.226518) (xy 6.081782 -347.188572) (xy 6.02602 -347.144103) (xy 5.975587 -347.09367)
			(xy 5.931118 -347.037908) (xy 5.893172 -346.977517) (xy 5.862227 -346.913258) (xy 5.83867 -346.845938)
			(xy 5.8228 -346.776403) (xy 5.814814 -346.705529) (xy 1.525016 -346.705529) (xy 1.525016 -346.796868)
			(xy 1.525462 -346.818885) (xy 1.533007 -346.862267) (xy 1.547919 -346.903698) (xy 1.569751 -346.941938)
			(xy 1.597849 -346.975842) (xy 1.631371 -347.004393) (xy 1.669314 -347.026737) (xy 1.710541 -347.042205)
			(xy 1.753818 -347.050333) (xy 1.797848 -347.050878) (xy 1.819656 -347.04782) (xy 1.854312 -347.041051)
			(xy 1.924607 -347.034324) (xy 1.995215 -347.035431) (xy 2.065264 -347.044358) (xy 2.133892 -347.060995)
			(xy 2.200253 -347.085137) (xy 2.263529 -347.116486) (xy 2.32294 -347.154656) (xy 2.377753 -347.199177)
			(xy 2.427293 -347.2495) (xy 2.47095 -347.305005) (xy 2.508184 -347.365006) (xy 2.538538 -347.428766)
			(xy 2.561637 -347.495497) (xy 2.577197 -347.564377) (xy 2.585025 -347.634558) (xy 2.585025 -347.705174)
			(xy 2.584986 -347.705527) (xy 7.81481 -347.705527) (xy 7.81481 -347.634205) (xy 7.822796 -347.563331)
			(xy 7.838666 -347.493796) (xy 7.862223 -347.426476) (xy 7.893168 -347.362217) (xy 7.931114 -347.301826)
			(xy 7.975583 -347.246064) (xy 8.026016 -347.195631) (xy 8.081778 -347.151162) (xy 8.142169 -347.113216)
			(xy 8.206428 -347.082271) (xy 8.273748 -347.058714) (xy 8.343283 -347.042844) (xy 8.414157 -347.034858)
			(xy 8.485479 -347.034858) (xy 8.556353 -347.042844) (xy 8.625888 -347.058714) (xy 8.693208 -347.082271)
			(xy 8.757467 -347.113216) (xy 8.817858 -347.151162) (xy 8.87362 -347.195631) (xy 8.924053 -347.246064)
			(xy 8.968522 -347.301826) (xy 9.006468 -347.362217) (xy 9.037413 -347.426476) (xy 9.06097 -347.493796)
			(xy 9.07684 -347.563331) (xy 9.084826 -347.634205) (xy 9.085326 -347.669866) (xy 9.084826 -347.705527)
			(xy 9.07684 -347.776401) (xy 9.06097 -347.845936) (xy 9.037413 -347.913256) (xy 9.006468 -347.977515)
			(xy 8.968522 -348.037906) (xy 8.924053 -348.093668) (xy 8.87362 -348.144101) (xy 8.817858 -348.18857)
			(xy 8.757467 -348.226516) (xy 8.693208 -348.257461) (xy 8.625888 -348.281018) (xy 8.556353 -348.296888)
			(xy 8.485479 -348.304874) (xy 8.414157 -348.304874) (xy 8.343283 -348.296888) (xy 8.273748 -348.281018)
			(xy 8.206428 -348.257461) (xy 8.142169 -348.226516) (xy 8.081778 -348.18857) (xy 8.026016 -348.144101)
			(xy 7.975583 -348.093668) (xy 7.931114 -348.037906) (xy 7.893168 -347.977515) (xy 7.862223 -347.913256)
			(xy 7.838666 -347.845936) (xy 7.822796 -347.776401) (xy 7.81481 -347.705527) (xy 2.584986 -347.705527)
			(xy 2.577197 -347.775355) (xy 2.561637 -347.844235) (xy 2.538538 -347.910966) (xy 2.508184 -347.974726)
			(xy 2.47095 -348.034727) (xy 2.427293 -348.090232) (xy 2.377753 -348.140555) (xy 2.32294 -348.185076)
			(xy 2.263529 -348.223246) (xy 2.200253 -348.254595) (xy 2.133892 -348.278737) (xy 2.065264 -348.295374)
			(xy 1.995215 -348.304301) (xy 1.924607 -348.305408) (xy 1.854312 -348.298681) (xy 1.819656 -348.291912)
			(xy 1.797849 -348.288854) (xy 1.753823 -348.289409) (xy 1.710551 -348.297543) (xy 1.669329 -348.313015)
			(xy 1.63139 -348.33536) (xy 1.597871 -348.36391) (xy 1.569774 -348.39781) (xy 1.547941 -348.436045)
			(xy 1.533025 -348.477471) (xy 1.525473 -348.520849) (xy 1.525016 -348.542864) (xy 1.525016 -348.705525)
			(xy 3.314946 -348.705525) (xy 3.314946 -348.634203) (xy 3.322932 -348.563329) (xy 3.338802 -348.493794)
			(xy 3.362359 -348.426474) (xy 3.393304 -348.362215) (xy 3.43125 -348.301824) (xy 3.475719 -348.246062)
			(xy 3.526152 -348.195629) (xy 3.581914 -348.15116) (xy 3.642305 -348.113214) (xy 3.706564 -348.082269)
			(xy 3.773884 -348.058712) (xy 3.843419 -348.042842) (xy 3.914293 -348.034856) (xy 3.985615 -348.034856)
			(xy 4.056489 -348.042842) (xy 4.126024 -348.058712) (xy 4.193344 -348.082269) (xy 4.257603 -348.113214)
			(xy 4.317994 -348.15116) (xy 4.373756 -348.195629) (xy 4.424189 -348.246062) (xy 4.468658 -348.301824)
			(xy 4.506604 -348.362215) (xy 4.537549 -348.426474) (xy 4.561106 -348.493794) (xy 4.576976 -348.563329)
			(xy 4.584962 -348.634203) (xy 4.585462 -348.669864) (xy 4.584962 -348.705525) (xy 4.576976 -348.776399)
			(xy 4.561106 -348.845934) (xy 4.537549 -348.913254) (xy 4.506604 -348.977513) (xy 4.468658 -349.037904)
			(xy 4.424189 -349.093666) (xy 4.373756 -349.144099) (xy 4.317994 -349.188568) (xy 4.257603 -349.226514)
			(xy 4.193344 -349.257459) (xy 4.126024 -349.281016) (xy 4.056489 -349.296886) (xy 3.985615 -349.304872)
			(xy 3.914293 -349.304872) (xy 3.843419 -349.296886) (xy 3.773884 -349.281016) (xy 3.706564 -349.257459)
			(xy 3.642305 -349.226514) (xy 3.581914 -349.188568) (xy 3.526152 -349.144099) (xy 3.475719 -349.093666)
			(xy 3.43125 -349.037904) (xy 3.393304 -348.977513) (xy 3.362359 -348.913254) (xy 3.338802 -348.845934)
			(xy 3.322932 -348.776399) (xy 3.314946 -348.705525) (xy 1.525016 -348.705525) (xy 1.525016 -349.705523)
			(xy 7.81481 -349.705523) (xy 7.81481 -349.634201) (xy 7.822796 -349.563327) (xy 7.838666 -349.493792)
			(xy 7.862223 -349.426472) (xy 7.893168 -349.362213) (xy 7.931114 -349.301822) (xy 7.975583 -349.24606)
			(xy 8.026016 -349.195627) (xy 8.081778 -349.151158) (xy 8.142169 -349.113212) (xy 8.206428 -349.082267)
			(xy 8.273748 -349.05871) (xy 8.343283 -349.04284) (xy 8.414157 -349.034854) (xy 8.485479 -349.034854)
			(xy 8.556353 -349.04284) (xy 8.625888 -349.05871) (xy 8.693208 -349.082267) (xy 8.757467 -349.113212)
			(xy 8.817858 -349.151158) (xy 8.87362 -349.195627) (xy 8.924053 -349.24606) (xy 8.968522 -349.301822)
			(xy 9.006468 -349.362213) (xy 9.037413 -349.426472) (xy 9.06097 -349.493792) (xy 9.07684 -349.563327)
			(xy 9.084826 -349.634201) (xy 9.085326 -349.669862) (xy 9.084826 -349.705523) (xy 9.07684 -349.776397)
			(xy 9.06097 -349.845932) (xy 9.037413 -349.913252) (xy 9.006468 -349.977511) (xy 8.968522 -350.037902)
			(xy 8.924053 -350.093664) (xy 8.87362 -350.144097) (xy 8.817858 -350.188566) (xy 8.757467 -350.226512)
			(xy 8.693208 -350.257457) (xy 8.625888 -350.281014) (xy 8.556353 -350.296884) (xy 8.485479 -350.30487)
			(xy 8.414157 -350.30487) (xy 8.343283 -350.296884) (xy 8.273748 -350.281014) (xy 8.206428 -350.257457)
			(xy 8.142169 -350.226512) (xy 8.081778 -350.188566) (xy 8.026016 -350.144097) (xy 7.975583 -350.093664)
			(xy 7.931114 -350.037902) (xy 7.893168 -349.977511) (xy 7.862223 -349.913252) (xy 7.838666 -349.845932)
			(xy 7.822796 -349.776397) (xy 7.81481 -349.705523) (xy 1.525016 -349.705523) (xy 1.525016 -350.705521)
			(xy 3.314946 -350.705521) (xy 3.314946 -350.634199) (xy 3.322932 -350.563325) (xy 3.338802 -350.49379)
			(xy 3.362359 -350.42647) (xy 3.393304 -350.362211) (xy 3.43125 -350.30182) (xy 3.475719 -350.246058)
			(xy 3.526152 -350.195625) (xy 3.581914 -350.151156) (xy 3.642305 -350.11321) (xy 3.706564 -350.082265)
			(xy 3.773884 -350.058708) (xy 3.843419 -350.042838) (xy 3.914293 -350.034852) (xy 3.985615 -350.034852)
			(xy 4.056489 -350.042838) (xy 4.126024 -350.058708) (xy 4.193344 -350.082265) (xy 4.257603 -350.11321)
			(xy 4.317994 -350.151156) (xy 4.373756 -350.195625) (xy 4.424189 -350.246058) (xy 4.468658 -350.30182)
			(xy 4.506604 -350.362211) (xy 4.537549 -350.42647) (xy 4.561106 -350.49379) (xy 4.576976 -350.563325)
			(xy 4.584962 -350.634199) (xy 4.585462 -350.66986) (xy 4.584962 -350.705521) (xy 5.814814 -350.705521)
			(xy 5.814814 -350.634199) (xy 5.8228 -350.563325) (xy 5.83867 -350.49379) (xy 5.862227 -350.42647)
			(xy 5.893172 -350.362211) (xy 5.931118 -350.30182) (xy 5.975587 -350.246058) (xy 6.02602 -350.195625)
			(xy 6.081782 -350.151156) (xy 6.142173 -350.11321) (xy 6.206432 -350.082265) (xy 6.273752 -350.058708)
			(xy 6.343287 -350.042838) (xy 6.414161 -350.034852) (xy 6.485483 -350.034852) (xy 6.556357 -350.042838)
			(xy 6.625892 -350.058708) (xy 6.693212 -350.082265) (xy 6.757471 -350.11321) (xy 6.817862 -350.151156)
			(xy 6.873624 -350.195625) (xy 6.924057 -350.246058) (xy 6.968526 -350.30182) (xy 7.006472 -350.362211)
			(xy 7.037417 -350.42647) (xy 7.060974 -350.49379) (xy 7.076844 -350.563325) (xy 7.08483 -350.634199)
			(xy 7.08533 -350.66986) (xy 7.08483 -350.705521) (xy 7.076844 -350.776395) (xy 7.060974 -350.84593)
			(xy 7.037417 -350.91325) (xy 7.006472 -350.977509) (xy 6.968526 -351.0379) (xy 6.924057 -351.093662)
			(xy 6.873624 -351.144095) (xy 6.817862 -351.188564) (xy 6.757471 -351.22651) (xy 6.693212 -351.257455)
			(xy 6.625892 -351.281012) (xy 6.556357 -351.296882) (xy 6.485483 -351.304868) (xy 6.414161 -351.304868)
			(xy 6.343287 -351.296882) (xy 6.273752 -351.281012) (xy 6.206432 -351.257455) (xy 6.142173 -351.22651)
			(xy 6.081782 -351.188564) (xy 6.02602 -351.144095) (xy 5.975587 -351.093662) (xy 5.931118 -351.0379)
			(xy 5.893172 -350.977509) (xy 5.862227 -350.91325) (xy 5.83867 -350.84593) (xy 5.8228 -350.776395)
			(xy 5.814814 -350.705521) (xy 4.584962 -350.705521) (xy 4.576976 -350.776395) (xy 4.561106 -350.84593)
			(xy 4.537549 -350.91325) (xy 4.506604 -350.977509) (xy 4.468658 -351.0379) (xy 4.424189 -351.093662)
			(xy 4.373756 -351.144095) (xy 4.317994 -351.188564) (xy 4.257603 -351.22651) (xy 4.193344 -351.257455)
			(xy 4.126024 -351.281012) (xy 4.056489 -351.296882) (xy 3.985615 -351.304868) (xy 3.914293 -351.304868)
			(xy 3.843419 -351.296882) (xy 3.773884 -351.281012) (xy 3.706564 -351.257455) (xy 3.642305 -351.22651)
			(xy 3.581914 -351.188564) (xy 3.526152 -351.144095) (xy 3.475719 -351.093662) (xy 3.43125 -351.0379)
			(xy 3.393304 -350.977509) (xy 3.362359 -350.91325) (xy 3.338802 -350.84593) (xy 3.322932 -350.776395)
			(xy 3.314946 -350.705521) (xy 1.525016 -350.705521) (xy 1.525016 -350.79686) (xy 1.525462 -350.818877)
			(xy 1.533008 -350.862259) (xy 1.54792 -350.90369) (xy 1.569751 -350.941929) (xy 1.597849 -350.975832)
			(xy 1.631372 -351.004383) (xy 1.669314 -351.026727) (xy 1.710541 -351.042195) (xy 1.753818 -351.050323)
			(xy 1.797847 -351.050868) (xy 1.819656 -351.047812) (xy 1.854313 -351.041043) (xy 1.924608 -351.034316)
			(xy 1.995215 -351.035422) (xy 2.065265 -351.044349) (xy 2.133894 -351.060986) (xy 2.200255 -351.085128)
			(xy 2.263532 -351.116478) (xy 2.322943 -351.154648) (xy 2.377756 -351.199169) (xy 2.427297 -351.249492)
			(xy 2.470954 -351.304997) (xy 2.508188 -351.364999) (xy 2.538543 -351.428759) (xy 2.561642 -351.49549)
			(xy 2.577201 -351.564371) (xy 2.585029 -351.634552) (xy 2.585029 -351.705169) (xy 2.577201 -351.77535)
			(xy 2.561641 -351.844231) (xy 2.538542 -351.910962) (xy 2.508188 -351.974722) (xy 2.470953 -352.034724)
			(xy 2.427296 -352.090228) (xy 2.377756 -352.140551) (xy 2.322942 -352.185072) (xy 2.263531 -352.223243)
			(xy 2.200255 -352.254592) (xy 2.133893 -352.278734) (xy 2.065265 -352.295371) (xy 1.995215 -352.304298)
			(xy 1.924607 -352.305404) (xy 1.854312 -352.298677) (xy 1.819656 -352.291904) (xy 1.797849 -352.288846)
			(xy 1.753822 -352.289401) (xy 1.71055 -352.297535) (xy 1.669327 -352.313007) (xy 1.631388 -352.335352)
			(xy 1.597868 -352.363901) (xy 1.569771 -352.397801) (xy 1.547936 -352.436037) (xy 1.533019 -352.477463)
			(xy 1.525465 -352.52084) (xy 1.525016 -352.542856) (xy 1.525016 -352.705517) (xy 5.814814 -352.705517)
			(xy 5.814814 -352.634195) (xy 5.8228 -352.563321) (xy 5.83867 -352.493786) (xy 5.862227 -352.426466)
			(xy 5.893172 -352.362207) (xy 5.931118 -352.301816) (xy 5.975587 -352.246054) (xy 6.02602 -352.195621)
			(xy 6.081782 -352.151152) (xy 6.142173 -352.113206) (xy 6.206432 -352.082261) (xy 6.273752 -352.058704)
			(xy 6.343287 -352.042834) (xy 6.414161 -352.034848) (xy 6.485483 -352.034848) (xy 6.556357 -352.042834)
			(xy 6.625892 -352.058704) (xy 6.693212 -352.082261) (xy 6.757471 -352.113206) (xy 6.817862 -352.151152)
			(xy 6.873624 -352.195621) (xy 6.924057 -352.246054) (xy 6.968526 -352.301816) (xy 7.006472 -352.362207)
			(xy 7.037417 -352.426466) (xy 7.060974 -352.493786) (xy 7.076844 -352.563321) (xy 7.08483 -352.634195)
			(xy 7.08533 -352.669856) (xy 7.08483 -352.705517) (xy 7.076844 -352.776391) (xy 7.060974 -352.845926)
			(xy 7.037417 -352.913246) (xy 7.006472 -352.977505) (xy 6.968526 -353.037896) (xy 6.924057 -353.093658)
			(xy 6.873624 -353.144091) (xy 6.817862 -353.18856) (xy 6.757471 -353.226506) (xy 6.693212 -353.257451)
			(xy 6.625892 -353.281008) (xy 6.556357 -353.296878) (xy 6.485483 -353.304864) (xy 6.414161 -353.304864)
			(xy 6.343287 -353.296878) (xy 6.273752 -353.281008) (xy 6.206432 -353.257451) (xy 6.142173 -353.226506)
			(xy 6.081782 -353.18856) (xy 6.02602 -353.144091) (xy 5.975587 -353.093658) (xy 5.931118 -353.037896)
			(xy 5.893172 -352.977505) (xy 5.862227 -352.913246) (xy 5.83867 -352.845926) (xy 5.8228 -352.776391)
			(xy 5.814814 -352.705517) (xy 1.525016 -352.705517) (xy 1.525016 -384.79984) (xy 11.345672 -384.79984)
			(xy 11.346163 -384.696662) (xy 11.354255 -384.490463) (xy 11.370436 -384.284742) (xy 11.394682 -384.079814)
			(xy 11.426955 -383.875996) (xy 11.467204 -383.673603) (xy 11.515369 -383.472946) (xy 11.571375 -383.274334)
			(xy 11.635136 -383.078075) (xy 11.706552 -382.88447) (xy 11.785515 -382.693818) (xy 11.871902 -382.506413)
			(xy 11.96558 -382.322545) (xy 12.066404 -382.142496) (xy 12.17422 -381.966544) (xy 12.288861 -381.794961)
			(xy 12.410149 -381.628012) (xy 12.537899 -381.465952) (xy 12.671913 -381.309034) (xy 12.811985 -381.157498)
			(xy 12.957898 -381.011578) (xy 13.109427 -380.871499) (xy 13.266339 -380.737478) (xy 13.428392 -380.60972)
			(xy 13.595336 -380.488424) (xy 13.766914 -380.373775) (xy 13.94286 -380.265951) (xy 14.122904 -380.165117)
			(xy 14.306768 -380.071431) (xy 14.494169 -379.985035) (xy 14.684817 -379.906063) (xy 14.878418 -379.834637)
			(xy 15.074675 -379.770868) (xy 15.273284 -379.714853) (xy 15.473939 -379.666678) (xy 15.67633 -379.626419)
			(xy 15.880146 -379.594136) (xy 16.085073 -379.569881) (xy 16.290794 -379.55369) (xy 16.496992 -379.545588)
			(xy 16.60017 -379.545088) (xy 16.703348 -379.545592) (xy 16.909546 -379.553694) (xy 17.115267 -379.569885)
			(xy 17.320193 -379.59414) (xy 17.524009 -379.626422) (xy 17.726401 -379.666682) (xy 17.927055 -379.714856)
			(xy 18.125664 -379.770872) (xy 18.32192 -379.834641) (xy 18.515522 -379.906067) (xy 18.70617 -379.985039)
			(xy 18.89357 -380.071434) (xy 19.077434 -380.165121) (xy 19.257478 -380.265954) (xy 19.433424 -380.373778)
			(xy 19.605002 -380.488427) (xy 19.771945 -380.609723) (xy 19.933998 -380.737481) (xy 20.09091 -380.871502)
			(xy 20.24244 -381.011581) (xy 20.388352 -381.157501) (xy 20.528424 -381.309037) (xy 20.662438 -381.465955)
			(xy 20.790187 -381.628014) (xy 20.911476 -381.794964) (xy 21.026117 -381.966546) (xy 21.133932 -382.142498)
			(xy 21.234757 -382.322547) (xy 21.328435 -382.506415) (xy 21.414822 -382.693819) (xy 21.493784 -382.884471)
			(xy 21.565201 -383.078076) (xy 21.628961 -383.274335) (xy 21.684967 -383.472947) (xy 21.733132 -383.673604)
			(xy 21.773381 -383.875997) (xy 21.805654 -384.079815) (xy 21.8299 -384.284742) (xy 21.846081 -384.490464)
			(xy 21.854173 -384.696662) (xy 21.854668 -384.79984) (xy 21.854174 -384.901741) (xy 21.846271 -385.105391)
			(xy 21.830478 -385.30858) (xy 21.806818 -385.511005) (xy 21.775327 -385.71236) (xy 21.736052 -385.912342)
			(xy 21.689051 -386.110651) (xy 21.634397 -386.306989) (xy 21.572171 -386.501059) (xy 21.502466 -386.692571)
			(xy 21.425388 -386.881236) (xy 21.341053 -387.06677) (xy 21.249586 -387.248895) (xy 21.151127 -387.427336)
			(xy 21.045822 -387.601825) (xy 20.933831 -387.7721) (xy 20.815321 -387.937904) (xy 20.690471 -388.098988)
			(xy 20.55947 -388.25511) (xy 20.422513 -388.406034) (xy 20.279807 -388.551535) (xy 20.131566 -388.691393)
			(xy 19.978014 -388.825397) (xy 19.819381 -388.953347) (xy 19.655906 -389.07505) (xy 19.487835 -389.190322)
			(xy 19.315421 -389.29899) (xy 19.138923 -389.400892) (xy 18.958606 -389.495872) (xy 18.774742 -389.58379)
			(xy 18.587607 -389.664512) (xy 18.397483 -389.737917) (xy 18.204656 -389.803895) (xy 18.009415 -389.862346)
			(xy 17.812055 -389.913183) (xy 17.612871 -389.956329) (xy 17.412165 -389.991719) (xy 17.210237 -390.0193)
			(xy 17.007392 -390.03903) (xy 16.803934 -390.05088) (xy 16.60017 -390.054832) (xy 16.396406 -390.05088)
			(xy 16.192948 -390.03903) (xy 15.990103 -390.0193) (xy 15.788175 -389.991719) (xy 15.587469 -389.956329)
			(xy 15.388285 -389.913183) (xy 15.190925 -389.862346) (xy 14.995684 -389.803895) (xy 14.802857 -389.737917)
			(xy 14.612733 -389.664512) (xy 14.425598 -389.58379) (xy 14.241734 -389.495872) (xy 14.061417 -389.400892)
			(xy 13.884919 -389.29899) (xy 13.712505 -389.190322) (xy 13.544434 -389.07505) (xy 13.380959 -388.953347)
			(xy 13.222326 -388.825397) (xy 13.068774 -388.691393) (xy 12.920533 -388.551535) (xy 12.777827 -388.406034)
			(xy 12.64087 -388.25511) (xy 12.509869 -388.098988) (xy 12.385019 -387.937904) (xy 12.266509 -387.7721)
			(xy 12.154518 -387.601825) (xy 12.049213 -387.427336) (xy 11.950754 -387.248895) (xy 11.859287 -387.06677)
			(xy 11.774952 -386.881236) (xy 11.697874 -386.692571) (xy 11.628169 -386.501059) (xy 11.565943 -386.306989)
			(xy 11.511289 -386.110651) (xy 11.464288 -385.912342) (xy 11.425013 -385.71236) (xy 11.393522 -385.511005)
			(xy 11.369862 -385.30858) (xy 11.354069 -385.105391) (xy 11.346166 -384.901741) (xy 11.345672 -384.79984)
			(xy 1.525016 -384.79984) (xy 1.525016 -398.870987) (xy 2.787139 -398.870987) (xy 2.787139 -398.791121)
			(xy 2.795219 -398.711666) (xy 2.811296 -398.633436) (xy 2.835205 -398.557234) (xy 2.8667 -398.483841)
			(xy 2.905459 -398.414011) (xy 2.951083 -398.348461) (xy 3.003105 -398.287862) (xy 3.06099 -398.232838)
			(xy 3.124146 -398.183952) (xy 3.191923 -398.141706) (xy 3.263626 -398.106534) (xy 3.33852 -398.078797)
			(xy 3.415835 -398.058778) (xy 3.494779 -398.046685) (xy 3.574542 -398.04264) (xy 3.654305 -398.046685)
			(xy 3.733249 -398.058778) (xy 3.810564 -398.078797) (xy 3.885458 -398.106534) (xy 3.957161 -398.141706)
			(xy 4.024938 -398.183952) (xy 4.088094 -398.232838) (xy 4.145979 -398.287862) (xy 4.198001 -398.348461)
			(xy 4.243625 -398.414011) (xy 4.282384 -398.483841) (xy 4.313879 -398.557234) (xy 4.337788 -398.633436)
			(xy 4.353865 -398.711666) (xy 4.361945 -398.791121) (xy 4.36245 -398.831054) (xy 4.361945 -398.870987)
			(xy 4.353865 -398.950442) (xy 4.337788 -399.028672) (xy 4.313879 -399.104874) (xy 4.282384 -399.178267)
			(xy 4.243625 -399.248097) (xy 4.198001 -399.313647) (xy 4.145979 -399.374246) (xy 4.088094 -399.42927)
			(xy 4.024938 -399.478156) (xy 4.023449 -399.479084) (xy 5.677649 -399.479084) (xy 5.677649 -399.352948)
			(xy 5.685569 -399.22706) (xy 5.701379 -399.101918) (xy 5.725014 -398.978015) (xy 5.756383 -398.855842)
			(xy 5.795361 -398.735879) (xy 5.841795 -398.6186) (xy 5.895502 -398.504468) (xy 5.956269 -398.393933)
			(xy 6.023856 -398.287433) (xy 6.097997 -398.185386) (xy 6.1784 -398.088196) (xy 6.264746 -397.996246)
			(xy 6.356696 -397.9099) (xy 6.453886 -397.829497) (xy 6.555933 -397.755356) (xy 6.662433 -397.687769)
			(xy 6.772968 -397.627002) (xy 6.8871 -397.573295) (xy 7.004379 -397.526861) (xy 7.124342 -397.487883)
			(xy 7.246515 -397.456514) (xy 7.370418 -397.432879) (xy 7.49556 -397.417069) (xy 7.621448 -397.409149)
			(xy 7.747584 -397.409149) (xy 7.873472 -397.417069) (xy 7.998614 -397.432879) (xy 8.122517 -397.456514)
			(xy 8.24469 -397.487883) (xy 8.364653 -397.526861) (xy 8.481932 -397.573295) (xy 8.596064 -397.627002)
			(xy 8.706599 -397.687769) (xy 8.813099 -397.755356) (xy 8.915146 -397.829497) (xy 9.012336 -397.9099)
			(xy 9.104286 -397.996246) (xy 9.190632 -398.088196) (xy 9.271035 -398.185386) (xy 9.345176 -398.287433)
			(xy 9.412763 -398.393933) (xy 9.47353 -398.504468) (xy 9.527237 -398.6186) (xy 9.573671 -398.735879)
			(xy 9.612649 -398.855842) (xy 9.644018 -398.978015) (xy 9.667653 -399.101918) (xy 9.683463 -399.22706)
			(xy 9.691383 -399.352948) (xy 9.691878 -399.416016) (xy 9.691383 -399.479084) (xy 9.683463 -399.604972)
			(xy 9.667653 -399.730114) (xy 9.644018 -399.854017) (xy 9.612649 -399.97619) (xy 9.573671 -400.096153)
			(xy 9.527237 -400.213432) (xy 9.47353 -400.327564) (xy 9.412763 -400.438099) (xy 9.345176 -400.544599)
			(xy 9.271035 -400.646646) (xy 9.205429 -400.725949) (xy 15.787113 -400.725949) (xy 15.787113 -400.646083)
			(xy 15.795193 -400.566628) (xy 15.81127 -400.488398) (xy 15.835179 -400.412196) (xy 15.866674 -400.338803)
			(xy 15.905433 -400.268973) (xy 15.951057 -400.203423) (xy 16.003079 -400.142824) (xy 16.060964 -400.0878)
			(xy 16.12412 -400.038914) (xy 16.191897 -399.996668) (xy 16.2636 -399.961496) (xy 16.338494 -399.933759)
			(xy 16.415809 -399.91374) (xy 16.494753 -399.901647) (xy 16.574516 -399.897602) (xy 16.654279 -399.901647)
			(xy 16.733223 -399.91374) (xy 16.810538 -399.933759) (xy 16.885432 -399.961496) (xy 16.957135 -399.996668)
			(xy 17.024912 -400.038914) (xy 17.088068 -400.0878) (xy 17.145953 -400.142824) (xy 17.197975 -400.203423)
			(xy 17.243599 -400.268973) (xy 17.282358 -400.338803) (xy 17.313853 -400.412196) (xy 17.337762 -400.488398)
			(xy 17.353839 -400.566628) (xy 17.361919 -400.646083) (xy 17.362424 -400.686016) (xy 17.361919 -400.725949)
			(xy 17.353839 -400.805404) (xy 17.337762 -400.883634) (xy 17.313853 -400.959836) (xy 17.282358 -401.033229)
			(xy 17.243599 -401.103059) (xy 17.197975 -401.168609) (xy 17.145953 -401.229208) (xy 17.088068 -401.284232)
			(xy 17.024912 -401.333118) (xy 16.957135 -401.375364) (xy 16.885432 -401.410536) (xy 16.810538 -401.438273)
			(xy 16.733223 -401.458292) (xy 16.654279 -401.470385) (xy 16.574516 -401.474431) (xy 16.494753 -401.470385)
			(xy 16.415809 -401.458292) (xy 16.338494 -401.438273) (xy 16.2636 -401.410536) (xy 16.191897 -401.375364)
			(xy 16.12412 -401.333118) (xy 16.060964 -401.284232) (xy 16.003079 -401.229208) (xy 15.951057 -401.168609)
			(xy 15.905433 -401.103059) (xy 15.866674 -401.033229) (xy 15.835179 -400.959836) (xy 15.81127 -400.883634)
			(xy 15.795193 -400.805404) (xy 15.787113 -400.725949) (xy 9.205429 -400.725949) (xy 9.190632 -400.743836)
			(xy 9.104286 -400.835786) (xy 9.012336 -400.922132) (xy 8.915146 -401.002535) (xy 8.813099 -401.076676)
			(xy 8.706599 -401.144263) (xy 8.596064 -401.20503) (xy 8.481932 -401.258737) (xy 8.364653 -401.305171)
			(xy 8.24469 -401.344149) (xy 8.122517 -401.375518) (xy 7.998614 -401.399153) (xy 7.873472 -401.414963)
			(xy 7.747584 -401.422883) (xy 7.621448 -401.422883) (xy 7.49556 -401.414963) (xy 7.370418 -401.399153)
			(xy 7.246515 -401.375518) (xy 7.124342 -401.344149) (xy 7.004379 -401.305171) (xy 6.8871 -401.258737)
			(xy 6.772968 -401.20503) (xy 6.662433 -401.144263) (xy 6.555933 -401.076676) (xy 6.453886 -401.002535)
			(xy 6.356696 -400.922132) (xy 6.264746 -400.835786) (xy 6.1784 -400.743836) (xy 6.097997 -400.646646)
			(xy 6.023856 -400.544599) (xy 5.956269 -400.438099) (xy 5.895502 -400.327564) (xy 5.841795 -400.213432)
			(xy 5.795361 -400.096153) (xy 5.756383 -399.97619) (xy 5.725014 -399.854017) (xy 5.701379 -399.730114)
			(xy 5.685569 -399.604972) (xy 5.677649 -399.479084) (xy 4.023449 -399.479084) (xy 3.957161 -399.520402)
			(xy 3.885458 -399.555574) (xy 3.810564 -399.583311) (xy 3.733249 -399.60333) (xy 3.654305 -399.615423)
			(xy 3.574542 -399.619469) (xy 3.494779 -399.615423) (xy 3.415835 -399.60333) (xy 3.33852 -399.583311)
			(xy 3.263626 -399.555574) (xy 3.191923 -399.520402) (xy 3.124146 -399.478156) (xy 3.06099 -399.42927)
			(xy 3.003105 -399.374246) (xy 2.951083 -399.313647) (xy 2.905459 -399.248097) (xy 2.8667 -399.178267)
			(xy 2.835205 -399.104874) (xy 2.811296 -399.028672) (xy 2.795219 -398.950442) (xy 2.787139 -398.870987)
			(xy 1.525016 -398.870987) (xy 1.525016 -401.360949) (xy 2.787139 -401.360949) (xy 2.787139 -401.281083)
			(xy 2.795219 -401.201628) (xy 2.811296 -401.123398) (xy 2.835205 -401.047196) (xy 2.8667 -400.973803)
			(xy 2.905459 -400.903973) (xy 2.951083 -400.838423) (xy 3.003105 -400.777824) (xy 3.06099 -400.7228)
			(xy 3.124146 -400.673914) (xy 3.191923 -400.631668) (xy 3.263626 -400.596496) (xy 3.33852 -400.568759)
			(xy 3.415835 -400.54874) (xy 3.494779 -400.536647) (xy 3.574542 -400.532602) (xy 3.654305 -400.536647)
			(xy 3.733249 -400.54874) (xy 3.810564 -400.568759) (xy 3.885458 -400.596496) (xy 3.957161 -400.631668)
			(xy 4.024938 -400.673914) (xy 4.088094 -400.7228) (xy 4.145979 -400.777824) (xy 4.198001 -400.838423)
			(xy 4.243625 -400.903973) (xy 4.282384 -400.973803) (xy 4.313879 -401.047196) (xy 4.337788 -401.123398)
			(xy 4.353865 -401.201628) (xy 4.361945 -401.281083) (xy 4.36245 -401.321016) (xy 4.361945 -401.360949)
			(xy 4.353865 -401.440404) (xy 4.337788 -401.518634) (xy 4.313879 -401.594836) (xy 4.282384 -401.668229)
			(xy 4.243625 -401.738059) (xy 4.198001 -401.803609) (xy 4.145979 -401.864208) (xy 4.088094 -401.919232)
			(xy 4.024938 -401.968118) (xy 3.980288 -401.995949) (xy 13.247113 -401.995949) (xy 13.247113 -401.916083)
			(xy 13.255193 -401.836628) (xy 13.27127 -401.758398) (xy 13.295179 -401.682196) (xy 13.326674 -401.608803)
			(xy 13.365433 -401.538973) (xy 13.411057 -401.473423) (xy 13.463079 -401.412824) (xy 13.520964 -401.3578)
			(xy 13.58412 -401.308914) (xy 13.651897 -401.266668) (xy 13.7236 -401.231496) (xy 13.798494 -401.203759)
			(xy 13.875809 -401.18374) (xy 13.954753 -401.171647) (xy 14.034516 -401.167602) (xy 14.114279 -401.171647)
			(xy 14.193223 -401.18374) (xy 14.270538 -401.203759) (xy 14.345432 -401.231496) (xy 14.417135 -401.266668)
			(xy 14.484912 -401.308914) (xy 14.548068 -401.3578) (xy 14.605953 -401.412824) (xy 14.657975 -401.473423)
			(xy 14.703599 -401.538973) (xy 14.742358 -401.608803) (xy 14.773853 -401.682196) (xy 14.797762 -401.758398)
			(xy 14.813839 -401.836628) (xy 14.821919 -401.916083) (xy 14.822424 -401.956016) (xy 14.821919 -401.995949)
			(xy 14.813839 -402.075404) (xy 14.797762 -402.153634) (xy 14.773853 -402.229836) (xy 14.742358 -402.303229)
			(xy 14.703599 -402.373059) (xy 14.657975 -402.438609) (xy 14.605953 -402.499208) (xy 14.548068 -402.554232)
			(xy 14.484912 -402.603118) (xy 14.417135 -402.645364) (xy 14.345432 -402.680536) (xy 14.270538 -402.708273)
			(xy 14.193223 -402.728292) (xy 14.114279 -402.740385) (xy 14.034516 -402.744431) (xy 13.954753 -402.740385)
			(xy 13.875809 -402.728292) (xy 13.798494 -402.708273) (xy 13.7236 -402.680536) (xy 13.651897 -402.645364)
			(xy 13.58412 -402.603118) (xy 13.520964 -402.554232) (xy 13.463079 -402.499208) (xy 13.411057 -402.438609)
			(xy 13.365433 -402.373059) (xy 13.326674 -402.303229) (xy 13.295179 -402.229836) (xy 13.27127 -402.153634)
			(xy 13.255193 -402.075404) (xy 13.247113 -401.995949) (xy 3.980288 -401.995949) (xy 3.957161 -402.010364)
			(xy 3.885458 -402.045536) (xy 3.810564 -402.073273) (xy 3.733249 -402.093292) (xy 3.654305 -402.105385)
			(xy 3.574542 -402.109431) (xy 3.494779 -402.105385) (xy 3.415835 -402.093292) (xy 3.33852 -402.073273)
			(xy 3.263626 -402.045536) (xy 3.191923 -402.010364) (xy 3.124146 -401.968118) (xy 3.06099 -401.919232)
			(xy 3.003105 -401.864208) (xy 2.951083 -401.803609) (xy 2.905459 -401.738059) (xy 2.8667 -401.668229)
			(xy 2.835205 -401.594836) (xy 2.811296 -401.518634) (xy 2.795219 -401.440404) (xy 2.787139 -401.360949)
			(xy 1.525016 -401.360949) (xy 1.525016 -403.265949) (xy 15.787113 -403.265949) (xy 15.787113 -403.186083)
			(xy 15.795193 -403.106628) (xy 15.81127 -403.028398) (xy 15.835179 -402.952196) (xy 15.866674 -402.878803)
			(xy 15.905433 -402.808973) (xy 15.951057 -402.743423) (xy 16.003079 -402.682824) (xy 16.060964 -402.6278)
			(xy 16.12412 -402.578914) (xy 16.191897 -402.536668) (xy 16.2636 -402.501496) (xy 16.338494 -402.473759)
			(xy 16.415809 -402.45374) (xy 16.494753 -402.441647) (xy 16.574516 -402.437602) (xy 16.654279 -402.441647)
			(xy 16.733223 -402.45374) (xy 16.810538 -402.473759) (xy 16.885432 -402.501496) (xy 16.957135 -402.536668)
			(xy 17.024912 -402.578914) (xy 17.088068 -402.6278) (xy 17.145953 -402.682824) (xy 17.197975 -402.743423)
			(xy 17.243599 -402.808973) (xy 17.282358 -402.878803) (xy 17.313853 -402.952196) (xy 17.337762 -403.028398)
			(xy 17.353839 -403.106628) (xy 17.361919 -403.186083) (xy 17.362424 -403.226016) (xy 17.361919 -403.265949)
			(xy 17.353839 -403.345404) (xy 17.337762 -403.423634) (xy 17.313853 -403.499836) (xy 17.282358 -403.573229)
			(xy 17.243599 -403.643059) (xy 17.197975 -403.708609) (xy 17.145953 -403.769208) (xy 17.088068 -403.824232)
			(xy 17.024912 -403.873118) (xy 16.957135 -403.915364) (xy 16.885432 -403.950536) (xy 16.810538 -403.978273)
			(xy 16.733223 -403.998292) (xy 16.654279 -404.010385) (xy 16.574516 -404.014431) (xy 16.494753 -404.010385)
			(xy 16.415809 -403.998292) (xy 16.338494 -403.978273) (xy 16.2636 -403.950536) (xy 16.191897 -403.915364)
			(xy 16.12412 -403.873118) (xy 16.060964 -403.824232) (xy 16.003079 -403.769208) (xy 15.951057 -403.708609)
			(xy 15.905433 -403.643059) (xy 15.866674 -403.573229) (xy 15.835179 -403.499836) (xy 15.81127 -403.423634)
			(xy 15.795193 -403.345404) (xy 15.787113 -403.265949) (xy 1.525016 -403.265949) (xy 1.525016 -404.535949)
			(xy 13.247113 -404.535949) (xy 13.247113 -404.456083) (xy 13.255193 -404.376628) (xy 13.27127 -404.298398)
			(xy 13.295179 -404.222196) (xy 13.326674 -404.148803) (xy 13.365433 -404.078973) (xy 13.411057 -404.013423)
			(xy 13.463079 -403.952824) (xy 13.520964 -403.8978) (xy 13.58412 -403.848914) (xy 13.651897 -403.806668)
			(xy 13.7236 -403.771496) (xy 13.798494 -403.743759) (xy 13.875809 -403.72374) (xy 13.954753 -403.711647)
			(xy 14.034516 -403.707602) (xy 14.114279 -403.711647) (xy 14.193223 -403.72374) (xy 14.270538 -403.743759)
			(xy 14.345432 -403.771496) (xy 14.417135 -403.806668) (xy 14.484912 -403.848914) (xy 14.548068 -403.8978)
			(xy 14.605953 -403.952824) (xy 14.657975 -404.013423) (xy 14.703599 -404.078973) (xy 14.742358 -404.148803)
			(xy 14.773853 -404.222196) (xy 14.797762 -404.298398) (xy 14.813839 -404.376628) (xy 14.821919 -404.456083)
			(xy 14.822424 -404.496016) (xy 14.821919 -404.535949) (xy 14.813839 -404.615404) (xy 14.797762 -404.693634)
			(xy 14.773853 -404.769836) (xy 14.742358 -404.843229) (xy 14.703599 -404.913059) (xy 14.657975 -404.978609)
			(xy 14.605953 -405.039208) (xy 14.548068 -405.094232) (xy 14.484912 -405.143118) (xy 14.417135 -405.185364)
			(xy 14.345432 -405.220536) (xy 14.270538 -405.248273) (xy 14.193223 -405.268292) (xy 14.114279 -405.280385)
			(xy 14.034516 -405.284431) (xy 13.954753 -405.280385) (xy 13.875809 -405.268292) (xy 13.798494 -405.248273)
			(xy 13.7236 -405.220536) (xy 13.651897 -405.185364) (xy 13.58412 -405.143118) (xy 13.520964 -405.094232)
			(xy 13.463079 -405.039208) (xy 13.411057 -404.978609) (xy 13.365433 -404.913059) (xy 13.326674 -404.843229)
			(xy 13.295179 -404.769836) (xy 13.27127 -404.693634) (xy 13.255193 -404.615404) (xy 13.247113 -404.535949)
			(xy 1.525016 -404.535949) (xy 1.525016 -405.805949) (xy 15.787113 -405.805949) (xy 15.787113 -405.726083)
			(xy 15.795193 -405.646628) (xy 15.81127 -405.568398) (xy 15.835179 -405.492196) (xy 15.866674 -405.418803)
			(xy 15.905433 -405.348973) (xy 15.951057 -405.283423) (xy 16.003079 -405.222824) (xy 16.060964 -405.1678)
			(xy 16.12412 -405.118914) (xy 16.191897 -405.076668) (xy 16.2636 -405.041496) (xy 16.338494 -405.013759)
			(xy 16.415809 -404.99374) (xy 16.494753 -404.981647) (xy 16.574516 -404.977602) (xy 16.654279 -404.981647)
			(xy 16.733223 -404.99374) (xy 16.810538 -405.013759) (xy 16.885432 -405.041496) (xy 16.957135 -405.076668)
			(xy 17.024912 -405.118914) (xy 17.088068 -405.1678) (xy 17.145953 -405.222824) (xy 17.197975 -405.283423)
			(xy 17.243599 -405.348973) (xy 17.282358 -405.418803) (xy 17.313853 -405.492196) (xy 17.337762 -405.568398)
			(xy 17.353839 -405.646628) (xy 17.361919 -405.726083) (xy 17.362424 -405.766016) (xy 17.361919 -405.805949)
			(xy 17.353839 -405.885404) (xy 17.337762 -405.963634) (xy 17.313853 -406.039836) (xy 17.282358 -406.113229)
			(xy 17.243599 -406.183059) (xy 17.197975 -406.248609) (xy 17.145953 -406.309208) (xy 17.088068 -406.364232)
			(xy 17.024912 -406.413118) (xy 16.957135 -406.455364) (xy 16.885432 -406.490536) (xy 16.810538 -406.518273)
			(xy 16.733223 -406.538292) (xy 16.654279 -406.550385) (xy 16.574516 -406.554431) (xy 16.494753 -406.550385)
			(xy 16.415809 -406.538292) (xy 16.338494 -406.518273) (xy 16.2636 -406.490536) (xy 16.191897 -406.455364)
			(xy 16.12412 -406.413118) (xy 16.060964 -406.364232) (xy 16.003079 -406.309208) (xy 15.951057 -406.248609)
			(xy 15.905433 -406.183059) (xy 15.866674 -406.113229) (xy 15.835179 -406.039836) (xy 15.81127 -405.963634)
			(xy 15.795193 -405.885404) (xy 15.787113 -405.805949) (xy 1.525016 -405.805949) (xy 1.525016 -407.075949)
			(xy 13.247113 -407.075949) (xy 13.247113 -406.996083) (xy 13.255193 -406.916628) (xy 13.27127 -406.838398)
			(xy 13.295179 -406.762196) (xy 13.326674 -406.688803) (xy 13.365433 -406.618973) (xy 13.411057 -406.553423)
			(xy 13.463079 -406.492824) (xy 13.520964 -406.4378) (xy 13.58412 -406.388914) (xy 13.651897 -406.346668)
			(xy 13.7236 -406.311496) (xy 13.798494 -406.283759) (xy 13.875809 -406.26374) (xy 13.954753 -406.251647)
			(xy 14.034516 -406.247602) (xy 14.114279 -406.251647) (xy 14.193223 -406.26374) (xy 14.270538 -406.283759)
			(xy 14.345432 -406.311496) (xy 14.417135 -406.346668) (xy 14.484912 -406.388914) (xy 14.548068 -406.4378)
			(xy 14.605953 -406.492824) (xy 14.657975 -406.553423) (xy 14.703599 -406.618973) (xy 14.742358 -406.688803)
			(xy 14.773853 -406.762196) (xy 14.797762 -406.838398) (xy 14.813839 -406.916628) (xy 14.821919 -406.996083)
			(xy 14.822424 -407.036016) (xy 14.821919 -407.075949) (xy 14.813839 -407.155404) (xy 14.797762 -407.233634)
			(xy 14.773853 -407.309836) (xy 14.742358 -407.383229) (xy 14.703599 -407.453059) (xy 14.657975 -407.518609)
			(xy 14.605953 -407.579208) (xy 14.548068 -407.634232) (xy 14.484912 -407.683118) (xy 14.417135 -407.725364)
			(xy 14.345432 -407.760536) (xy 14.270538 -407.788273) (xy 14.193223 -407.808292) (xy 14.114279 -407.820385)
			(xy 14.034516 -407.824431) (xy 13.954753 -407.820385) (xy 13.875809 -407.808292) (xy 13.798494 -407.788273)
			(xy 13.7236 -407.760536) (xy 13.651897 -407.725364) (xy 13.58412 -407.683118) (xy 13.520964 -407.634232)
			(xy 13.463079 -407.579208) (xy 13.411057 -407.518609) (xy 13.365433 -407.453059) (xy 13.326674 -407.383229)
			(xy 13.295179 -407.309836) (xy 13.27127 -407.233634) (xy 13.255193 -407.155404) (xy 13.247113 -407.075949)
			(xy 1.525016 -407.075949) (xy 1.525016 -408.980949) (xy 2.787139 -408.980949) (xy 2.787139 -408.901083)
			(xy 2.795219 -408.821628) (xy 2.811296 -408.743398) (xy 2.835205 -408.667196) (xy 2.8667 -408.593803)
			(xy 2.905459 -408.523973) (xy 2.951083 -408.458423) (xy 3.003105 -408.397824) (xy 3.06099 -408.3428)
			(xy 3.124146 -408.293914) (xy 3.191923 -408.251668) (xy 3.263626 -408.216496) (xy 3.33852 -408.188759)
			(xy 3.415835 -408.16874) (xy 3.494779 -408.156647) (xy 3.574542 -408.152602) (xy 3.654305 -408.156647)
			(xy 3.733249 -408.16874) (xy 3.810564 -408.188759) (xy 3.885458 -408.216496) (xy 3.957161 -408.251668)
			(xy 4.024938 -408.293914) (xy 4.088094 -408.3428) (xy 4.091407 -408.345949) (xy 15.787113 -408.345949)
			(xy 15.787113 -408.266083) (xy 15.795193 -408.186628) (xy 15.81127 -408.108398) (xy 15.835179 -408.032196)
			(xy 15.866674 -407.958803) (xy 15.905433 -407.888973) (xy 15.951057 -407.823423) (xy 16.003079 -407.762824)
			(xy 16.060964 -407.7078) (xy 16.12412 -407.658914) (xy 16.191897 -407.616668) (xy 16.2636 -407.581496)
			(xy 16.338494 -407.553759) (xy 16.415809 -407.53374) (xy 16.494753 -407.521647) (xy 16.574516 -407.517602)
			(xy 16.654279 -407.521647) (xy 16.733223 -407.53374) (xy 16.810538 -407.553759) (xy 16.885432 -407.581496)
			(xy 16.957135 -407.616668) (xy 17.024912 -407.658914) (xy 17.088068 -407.7078) (xy 17.145953 -407.762824)
			(xy 17.197975 -407.823423) (xy 17.243599 -407.888973) (xy 17.282358 -407.958803) (xy 17.313853 -408.032196)
			(xy 17.337762 -408.108398) (xy 17.353839 -408.186628) (xy 17.361919 -408.266083) (xy 17.362424 -408.306016)
			(xy 17.361919 -408.345949) (xy 17.353839 -408.425404) (xy 17.337762 -408.503634) (xy 17.313853 -408.579836)
			(xy 17.282358 -408.653229) (xy 17.243599 -408.723059) (xy 17.197975 -408.788609) (xy 17.145953 -408.849208)
			(xy 17.088068 -408.904232) (xy 17.024912 -408.953118) (xy 16.957135 -408.995364) (xy 16.885432 -409.030536)
			(xy 16.810538 -409.058273) (xy 16.733223 -409.078292) (xy 16.654279 -409.090385) (xy 16.574516 -409.094431)
			(xy 16.494753 -409.090385) (xy 16.415809 -409.078292) (xy 16.338494 -409.058273) (xy 16.2636 -409.030536)
			(xy 16.191897 -408.995364) (xy 16.12412 -408.953118) (xy 16.060964 -408.904232) (xy 16.003079 -408.849208)
			(xy 15.951057 -408.788609) (xy 15.905433 -408.723059) (xy 15.866674 -408.653229) (xy 15.835179 -408.579836)
			(xy 15.81127 -408.503634) (xy 15.795193 -408.425404) (xy 15.787113 -408.345949) (xy 4.091407 -408.345949)
			(xy 4.145979 -408.397824) (xy 4.198001 -408.458423) (xy 4.243625 -408.523973) (xy 4.282384 -408.593803)
			(xy 4.313879 -408.667196) (xy 4.337788 -408.743398) (xy 4.353865 -408.821628) (xy 4.361945 -408.901083)
			(xy 4.36245 -408.941016) (xy 4.361945 -408.980949) (xy 4.353865 -409.060404) (xy 4.337788 -409.138634)
			(xy 4.313879 -409.214836) (xy 4.282384 -409.288229) (xy 4.243625 -409.358059) (xy 4.198001 -409.423609)
			(xy 4.145979 -409.484208) (xy 4.088094 -409.539232) (xy 4.024938 -409.588118) (xy 3.957161 -409.630364)
			(xy 3.885458 -409.665536) (xy 3.810564 -409.693273) (xy 3.733249 -409.713292) (xy 3.654305 -409.725385)
			(xy 3.574542 -409.729431) (xy 3.494779 -409.725385) (xy 3.415835 -409.713292) (xy 3.33852 -409.693273)
			(xy 3.263626 -409.665536) (xy 3.191923 -409.630364) (xy 3.124146 -409.588118) (xy 3.06099 -409.539232)
			(xy 3.003105 -409.484208) (xy 2.951083 -409.423609) (xy 2.905459 -409.358059) (xy 2.8667 -409.288229)
			(xy 2.835205 -409.214836) (xy 2.811296 -409.138634) (xy 2.795219 -409.060404) (xy 2.787139 -408.980949)
			(xy 1.525016 -408.980949) (xy 1.525016 -411.470911) (xy 2.787139 -411.470911) (xy 2.787139 -411.391045)
			(xy 2.795219 -411.31159) (xy 2.811296 -411.23336) (xy 2.835205 -411.157158) (xy 2.8667 -411.083765)
			(xy 2.905459 -411.013935) (xy 2.951083 -410.948385) (xy 3.003105 -410.887786) (xy 3.06099 -410.832762)
			(xy 3.124146 -410.783876) (xy 3.191923 -410.74163) (xy 3.263626 -410.706458) (xy 3.33852 -410.678721)
			(xy 3.415835 -410.658702) (xy 3.494779 -410.646609) (xy 3.574542 -410.642564) (xy 3.654305 -410.646609)
			(xy 3.733249 -410.658702) (xy 3.810564 -410.678721) (xy 3.885458 -410.706458) (xy 3.957161 -410.74163)
			(xy 4.024938 -410.783876) (xy 4.088094 -410.832762) (xy 4.145979 -410.887786) (xy 4.164263 -410.909084)
			(xy 5.677649 -410.909084) (xy 5.677649 -410.782948) (xy 5.685569 -410.65706) (xy 5.701379 -410.531918)
			(xy 5.725014 -410.408015) (xy 5.756383 -410.285842) (xy 5.795361 -410.165879) (xy 5.841795 -410.0486)
			(xy 5.895502 -409.934468) (xy 5.956269 -409.823933) (xy 6.023856 -409.717433) (xy 6.097997 -409.615386)
			(xy 6.1784 -409.518196) (xy 6.264746 -409.426246) (xy 6.356696 -409.3399) (xy 6.453886 -409.259497)
			(xy 6.555933 -409.185356) (xy 6.662433 -409.117769) (xy 6.772968 -409.057002) (xy 6.8871 -409.003295)
			(xy 7.004379 -408.956861) (xy 7.124342 -408.917883) (xy 7.246515 -408.886514) (xy 7.370418 -408.862879)
			(xy 7.49556 -408.847069) (xy 7.621448 -408.839149) (xy 7.747584 -408.839149) (xy 7.873472 -408.847069)
			(xy 7.998614 -408.862879) (xy 8.122517 -408.886514) (xy 8.24469 -408.917883) (xy 8.364653 -408.956861)
			(xy 8.481932 -409.003295) (xy 8.596064 -409.057002) (xy 8.706599 -409.117769) (xy 8.813099 -409.185356)
			(xy 8.915146 -409.259497) (xy 9.012336 -409.3399) (xy 9.104286 -409.426246) (xy 9.190632 -409.518196)
			(xy 9.271035 -409.615386) (xy 9.271444 -409.615949) (xy 13.247113 -409.615949) (xy 13.247113 -409.536083)
			(xy 13.255193 -409.456628) (xy 13.27127 -409.378398) (xy 13.295179 -409.302196) (xy 13.326674 -409.228803)
			(xy 13.365433 -409.158973) (xy 13.411057 -409.093423) (xy 13.463079 -409.032824) (xy 13.520964 -408.9778)
			(xy 13.58412 -408.928914) (xy 13.651897 -408.886668) (xy 13.7236 -408.851496) (xy 13.798494 -408.823759)
			(xy 13.875809 -408.80374) (xy 13.954753 -408.791647) (xy 14.034516 -408.787602) (xy 14.114279 -408.791647)
			(xy 14.193223 -408.80374) (xy 14.270538 -408.823759) (xy 14.345432 -408.851496) (xy 14.417135 -408.886668)
			(xy 14.484912 -408.928914) (xy 14.548068 -408.9778) (xy 14.605953 -409.032824) (xy 14.657975 -409.093423)
			(xy 14.703599 -409.158973) (xy 14.742358 -409.228803) (xy 14.773853 -409.302196) (xy 14.797762 -409.378398)
			(xy 14.813839 -409.456628) (xy 14.821919 -409.536083) (xy 14.822424 -409.576016) (xy 14.821919 -409.615949)
			(xy 14.813839 -409.695404) (xy 14.797762 -409.773634) (xy 14.773853 -409.849836) (xy 14.742358 -409.923229)
			(xy 14.703599 -409.993059) (xy 14.657975 -410.058609) (xy 14.605953 -410.119208) (xy 14.548068 -410.174232)
			(xy 14.484912 -410.223118) (xy 14.417135 -410.265364) (xy 14.345432 -410.300536) (xy 14.270538 -410.328273)
			(xy 14.193223 -410.348292) (xy 14.114279 -410.360385) (xy 14.034516 -410.364431) (xy 13.954753 -410.360385)
			(xy 13.875809 -410.348292) (xy 13.798494 -410.328273) (xy 13.7236 -410.300536) (xy 13.651897 -410.265364)
			(xy 13.58412 -410.223118) (xy 13.520964 -410.174232) (xy 13.463079 -410.119208) (xy 13.411057 -410.058609)
			(xy 13.365433 -409.993059) (xy 13.326674 -409.923229) (xy 13.295179 -409.849836) (xy 13.27127 -409.773634)
			(xy 13.255193 -409.695404) (xy 13.247113 -409.615949) (xy 9.271444 -409.615949) (xy 9.345176 -409.717433)
			(xy 9.412763 -409.823933) (xy 9.47353 -409.934468) (xy 9.527237 -410.0486) (xy 9.573671 -410.165879)
			(xy 9.612649 -410.285842) (xy 9.644018 -410.408015) (xy 9.667653 -410.531918) (xy 9.683463 -410.65706)
			(xy 9.691383 -410.782948) (xy 9.691878 -410.846016) (xy 9.691383 -410.909084) (xy 9.683463 -411.034972)
			(xy 9.667653 -411.160114) (xy 9.644018 -411.284017) (xy 9.612649 -411.40619) (xy 9.573671 -411.526153)
			(xy 9.527237 -411.643432) (xy 9.47353 -411.757564) (xy 9.412763 -411.868099) (xy 9.345176 -411.974599)
			(xy 9.271035 -412.076646) (xy 9.190632 -412.173836) (xy 9.104286 -412.265786) (xy 9.012336 -412.352132)
			(xy 8.915146 -412.432535) (xy 8.813099 -412.506676) (xy 8.706599 -412.574263) (xy 8.596064 -412.63503)
			(xy 8.481932 -412.688737) (xy 8.364653 -412.735171) (xy 8.24469 -412.774149) (xy 8.122517 -412.805518)
			(xy 7.998614 -412.829153) (xy 7.873472 -412.844963) (xy 7.747584 -412.852883) (xy 7.621448 -412.852883)
			(xy 7.49556 -412.844963) (xy 7.370418 -412.829153) (xy 7.246515 -412.805518) (xy 7.124342 -412.774149)
			(xy 7.004379 -412.735171) (xy 6.8871 -412.688737) (xy 6.772968 -412.63503) (xy 6.662433 -412.574263)
			(xy 6.555933 -412.506676) (xy 6.453886 -412.432535) (xy 6.356696 -412.352132) (xy 6.264746 -412.265786)
			(xy 6.1784 -412.173836) (xy 6.097997 -412.076646) (xy 6.023856 -411.974599) (xy 5.956269 -411.868099)
			(xy 5.895502 -411.757564) (xy 5.841795 -411.643432) (xy 5.795361 -411.526153) (xy 5.756383 -411.40619)
			(xy 5.725014 -411.284017) (xy 5.701379 -411.160114) (xy 5.685569 -411.034972) (xy 5.677649 -410.909084)
			(xy 4.164263 -410.909084) (xy 4.198001 -410.948385) (xy 4.243625 -411.013935) (xy 4.282384 -411.083765)
			(xy 4.313879 -411.157158) (xy 4.337788 -411.23336) (xy 4.353865 -411.31159) (xy 4.361945 -411.391045)
			(xy 4.36245 -411.430978) (xy 4.361945 -411.470911) (xy 4.353865 -411.550366) (xy 4.337788 -411.628596)
			(xy 4.313879 -411.704798) (xy 4.282384 -411.778191) (xy 4.243625 -411.848021) (xy 4.198001 -411.913571)
			(xy 4.145979 -411.97417) (xy 4.088094 -412.029194) (xy 4.024938 -412.07808) (xy 3.957161 -412.120326)
			(xy 3.885458 -412.155498) (xy 3.810564 -412.183235) (xy 3.733249 -412.203254) (xy 3.654305 -412.215347)
			(xy 3.574542 -412.219393) (xy 3.494779 -412.215347) (xy 3.415835 -412.203254) (xy 3.33852 -412.183235)
			(xy 3.263626 -412.155498) (xy 3.191923 -412.120326) (xy 3.124146 -412.07808) (xy 3.06099 -412.029194)
			(xy 3.003105 -411.97417) (xy 2.951083 -411.913571) (xy 2.905459 -411.848021) (xy 2.8667 -411.778191)
			(xy 2.835205 -411.704798) (xy 2.811296 -411.628596) (xy 2.795219 -411.550366) (xy 2.787139 -411.470911)
			(xy 1.525016 -411.470911) (xy 1.525016 -423.940932) (xy 4.839198 -423.940932) (xy 4.839198 -423.84706)
			(xy 4.847159 -423.753526) (xy 4.863023 -423.661004) (xy 4.886677 -423.570161) (xy 4.917949 -423.481652)
			(xy 4.956615 -423.396113) (xy 5.002396 -423.314161) (xy 5.054962 -423.236387) (xy 5.113935 -423.163352)
			(xy 5.178888 -423.09558) (xy 5.249355 -423.033561) (xy 5.324828 -422.977742) (xy 5.404763 -422.928524)
			(xy 5.488584 -422.886262) (xy 5.575687 -422.851262) (xy 5.665444 -422.823774) (xy 5.757209 -422.803997)
			(xy 5.850321 -422.792074) (xy 5.944108 -422.78809) (xy 6.037895 -422.792074) (xy 6.131007 -422.803997)
			(xy 6.222772 -422.823774) (xy 6.312529 -422.851262) (xy 6.399632 -422.886262) (xy 6.483453 -422.928524)
			(xy 6.563388 -422.977742) (xy 6.638861 -423.033561) (xy 6.709328 -423.09558) (xy 6.774281 -423.163352)
			(xy 6.833254 -423.236387) (xy 6.88582 -423.314161) (xy 6.931601 -423.396113) (xy 6.970267 -423.481652)
			(xy 7.001539 -423.570161) (xy 7.025193 -423.661004) (xy 7.041057 -423.753526) (xy 7.049018 -423.84706)
			(xy 7.049516 -423.893996) (xy 7.049018 -423.940932) (xy 10.339314 -423.940932) (xy 10.339314 -423.84706)
			(xy 10.347275 -423.753526) (xy 10.363139 -423.661004) (xy 10.386793 -423.570161) (xy 10.418065 -423.481652)
			(xy 10.456731 -423.396113) (xy 10.502512 -423.314161) (xy 10.555078 -423.236387) (xy 10.614051 -423.163352)
			(xy 10.679004 -423.09558) (xy 10.749471 -423.033561) (xy 10.824944 -422.977742) (xy 10.904879 -422.928524)
			(xy 10.9887 -422.886262) (xy 11.075803 -422.851262) (xy 11.16556 -422.823774) (xy 11.257325 -422.803997)
			(xy 11.350437 -422.792074) (xy 11.444224 -422.78809) (xy 11.538011 -422.792074) (xy 11.631123 -422.803997)
			(xy 11.722888 -422.823774) (xy 11.812645 -422.851262) (xy 11.899748 -422.886262) (xy 11.983569 -422.928524)
			(xy 12.063504 -422.977742) (xy 12.138977 -423.033561) (xy 12.209444 -423.09558) (xy 12.274397 -423.163352)
			(xy 12.33337 -423.236387) (xy 12.385936 -423.314161) (xy 12.431717 -423.396113) (xy 12.470383 -423.481652)
			(xy 12.501655 -423.570161) (xy 12.525309 -423.661004) (xy 12.541173 -423.753526) (xy 12.549134 -423.84706)
			(xy 12.549632 -423.893996) (xy 12.549134 -423.940932) (xy 12.541173 -424.034466) (xy 12.525309 -424.126988)
			(xy 12.501655 -424.217831) (xy 12.470383 -424.30634) (xy 12.431717 -424.391879) (xy 12.385936 -424.473831)
			(xy 12.33337 -424.551605) (xy 12.274397 -424.62464) (xy 12.209444 -424.692412) (xy 12.138977 -424.754431)
			(xy 12.063504 -424.81025) (xy 11.983569 -424.859468) (xy 11.899748 -424.90173) (xy 11.812645 -424.93673)
			(xy 11.722888 -424.964218) (xy 11.631123 -424.983995) (xy 11.538011 -424.995918) (xy 11.444224 -424.999903)
			(xy 11.350437 -424.995918) (xy 11.257325 -424.983995) (xy 11.16556 -424.964218) (xy 11.075803 -424.93673)
			(xy 10.9887 -424.90173) (xy 10.904879 -424.859468) (xy 10.824944 -424.81025) (xy 10.749471 -424.754431)
			(xy 10.679004 -424.692412) (xy 10.614051 -424.62464) (xy 10.555078 -424.551605) (xy 10.502512 -424.473831)
			(xy 10.456731 -424.391879) (xy 10.418065 -424.30634) (xy 10.386793 -424.217831) (xy 10.363139 -424.126988)
			(xy 10.347275 -424.034466) (xy 10.339314 -423.940932) (xy 7.049018 -423.940932) (xy 7.041057 -424.034466)
			(xy 7.025193 -424.126988) (xy 7.001539 -424.217831) (xy 6.970267 -424.30634) (xy 6.931601 -424.391879)
			(xy 6.88582 -424.473831) (xy 6.833254 -424.551605) (xy 6.774281 -424.62464) (xy 6.709328 -424.692412)
			(xy 6.638861 -424.754431) (xy 6.563388 -424.81025) (xy 6.483453 -424.859468) (xy 6.399632 -424.90173)
			(xy 6.312529 -424.93673) (xy 6.222772 -424.964218) (xy 6.131007 -424.983995) (xy 6.037895 -424.995918)
			(xy 5.944108 -424.999903) (xy 5.850321 -424.995918) (xy 5.757209 -424.983995) (xy 5.665444 -424.964218)
			(xy 5.575687 -424.93673) (xy 5.488584 -424.90173) (xy 5.404763 -424.859468) (xy 5.324828 -424.81025)
			(xy 5.249355 -424.754431) (xy 5.178888 -424.692412) (xy 5.113935 -424.62464) (xy 5.054962 -424.551605)
			(xy 5.002396 -424.473831) (xy 4.956615 -424.391879) (xy 4.917949 -424.30634) (xy 4.886677 -424.217831)
			(xy 4.863023 -424.126988) (xy 4.847159 -424.034466) (xy 4.839198 -423.940932) (xy 1.525016 -423.940932)
			(xy 1.525016 -428.141076) (xy 10.339314 -428.141076) (xy 10.339314 -428.047204) (xy 10.347275 -427.95367)
			(xy 10.363139 -427.861148) (xy 10.386793 -427.770305) (xy 10.418065 -427.681796) (xy 10.456731 -427.596257)
			(xy 10.502512 -427.514305) (xy 10.555078 -427.436531) (xy 10.614051 -427.363496) (xy 10.679004 -427.295724)
			(xy 10.749471 -427.233705) (xy 10.824944 -427.177886) (xy 10.904879 -427.128668) (xy 10.9887 -427.086406)
			(xy 11.075803 -427.051406) (xy 11.16556 -427.023918) (xy 11.257325 -427.004141) (xy 11.350437 -426.992218)
			(xy 11.444224 -426.988234) (xy 11.538011 -426.992218) (xy 11.631123 -427.004141) (xy 11.722888 -427.023918)
			(xy 11.812645 -427.051406) (xy 11.899748 -427.086406) (xy 11.983569 -427.128668) (xy 12.063504 -427.177886)
			(xy 12.138977 -427.233705) (xy 12.209444 -427.295724) (xy 12.274397 -427.363496) (xy 12.33337 -427.436531)
			(xy 12.385936 -427.514305) (xy 12.431717 -427.596257) (xy 12.470383 -427.681796) (xy 12.501655 -427.770305)
			(xy 12.525309 -427.861148) (xy 12.541173 -427.95367) (xy 12.549134 -428.047204) (xy 12.549632 -428.09414)
			(xy 12.549134 -428.141076) (xy 12.541173 -428.23461) (xy 12.525309 -428.327132) (xy 12.501655 -428.417975)
			(xy 12.470383 -428.506484) (xy 12.431717 -428.592023) (xy 12.385936 -428.673975) (xy 12.33337 -428.751749)
			(xy 12.274397 -428.824784) (xy 12.209444 -428.892556) (xy 12.138977 -428.954575) (xy 12.063504 -429.010394)
			(xy 11.983569 -429.059612) (xy 11.899748 -429.101874) (xy 11.812645 -429.136874) (xy 11.722888 -429.164362)
			(xy 11.631123 -429.184139) (xy 11.538011 -429.196062) (xy 11.444224 -429.200047) (xy 11.350437 -429.196062)
			(xy 11.257325 -429.184139) (xy 11.16556 -429.164362) (xy 11.075803 -429.136874) (xy 10.9887 -429.101874)
			(xy 10.904879 -429.059612) (xy 10.824944 -429.010394) (xy 10.749471 -428.954575) (xy 10.679004 -428.892556)
			(xy 10.614051 -428.824784) (xy 10.555078 -428.751749) (xy 10.502512 -428.673975) (xy 10.456731 -428.592023)
			(xy 10.418065 -428.506484) (xy 10.386793 -428.417975) (xy 10.363139 -428.327132) (xy 10.347275 -428.23461)
			(xy 10.339314 -428.141076) (xy 1.525016 -428.141076) (xy 1.525016 -432.340966) (xy 10.339314 -432.340966)
			(xy 10.339314 -432.247094) (xy 10.347275 -432.15356) (xy 10.363139 -432.061038) (xy 10.386793 -431.970195)
			(xy 10.418065 -431.881686) (xy 10.456731 -431.796147) (xy 10.502512 -431.714195) (xy 10.555078 -431.636421)
			(xy 10.614051 -431.563386) (xy 10.679004 -431.495614) (xy 10.749471 -431.433595) (xy 10.824944 -431.377776)
			(xy 10.904879 -431.328558) (xy 10.9887 -431.286296) (xy 11.075803 -431.251296) (xy 11.16556 -431.223808)
			(xy 11.257325 -431.204031) (xy 11.350437 -431.192108) (xy 11.444224 -431.188124) (xy 11.538011 -431.192108)
			(xy 11.631123 -431.204031) (xy 11.722888 -431.223808) (xy 11.812645 -431.251296) (xy 11.899748 -431.286296)
			(xy 11.983569 -431.328558) (xy 12.063504 -431.377776) (xy 12.138977 -431.433595) (xy 12.209444 -431.495614)
			(xy 12.274397 -431.563386) (xy 12.33337 -431.636421) (xy 12.385936 -431.714195) (xy 12.431717 -431.796147)
			(xy 12.470383 -431.881686) (xy 12.501655 -431.970195) (xy 12.525309 -432.061038) (xy 12.541173 -432.15356)
			(xy 12.549134 -432.247094) (xy 12.549632 -432.29403) (xy 12.549134 -432.340966) (xy 12.541173 -432.4345)
			(xy 12.525309 -432.527022) (xy 12.501655 -432.617865) (xy 12.470383 -432.706374) (xy 12.431717 -432.791913)
			(xy 12.385936 -432.873865) (xy 12.33337 -432.951639) (xy 12.274397 -433.024674) (xy 12.209444 -433.092446)
			(xy 12.138977 -433.154465) (xy 12.063504 -433.210284) (xy 11.983569 -433.259502) (xy 11.899748 -433.301764)
			(xy 11.812645 -433.336764) (xy 11.722888 -433.364252) (xy 11.631123 -433.384029) (xy 11.538011 -433.395952)
			(xy 11.444224 -433.399937) (xy 11.350437 -433.395952) (xy 11.257325 -433.384029) (xy 11.16556 -433.364252)
			(xy 11.075803 -433.336764) (xy 10.9887 -433.301764) (xy 10.904879 -433.259502) (xy 10.824944 -433.210284)
			(xy 10.749471 -433.154465) (xy 10.679004 -433.092446) (xy 10.614051 -433.024674) (xy 10.555078 -432.951639)
			(xy 10.502512 -432.873865) (xy 10.456731 -432.791913) (xy 10.418065 -432.706374) (xy 10.386793 -432.617865)
			(xy 10.363139 -432.527022) (xy 10.347275 -432.4345) (xy 10.339314 -432.340966) (xy 1.525016 -432.340966)
			(xy 1.525016 -436.540856) (xy 4.839198 -436.540856) (xy 4.839198 -436.446984) (xy 4.847159 -436.35345)
			(xy 4.863023 -436.260928) (xy 4.886677 -436.170085) (xy 4.917949 -436.081576) (xy 4.956615 -435.996037)
			(xy 5.002396 -435.914085) (xy 5.054962 -435.836311) (xy 5.113935 -435.763276) (xy 5.178888 -435.695504)
			(xy 5.249355 -435.633485) (xy 5.324828 -435.577666) (xy 5.404763 -435.528448) (xy 5.488584 -435.486186)
			(xy 5.575687 -435.451186) (xy 5.665444 -435.423698) (xy 5.757209 -435.403921) (xy 5.850321 -435.391998)
			(xy 5.944108 -435.388014) (xy 6.037895 -435.391998) (xy 6.131007 -435.403921) (xy 6.222772 -435.423698)
			(xy 6.312529 -435.451186) (xy 6.399632 -435.486186) (xy 6.483453 -435.528448) (xy 6.563388 -435.577666)
			(xy 6.638861 -435.633485) (xy 6.709328 -435.695504) (xy 6.774281 -435.763276) (xy 6.833254 -435.836311)
			(xy 6.88582 -435.914085) (xy 6.931601 -435.996037) (xy 6.970267 -436.081576) (xy 7.001539 -436.170085)
			(xy 7.025193 -436.260928) (xy 7.041057 -436.35345) (xy 7.049018 -436.446984) (xy 7.049516 -436.49392)
			(xy 7.049018 -436.540856) (xy 10.339314 -436.540856) (xy 10.339314 -436.446984) (xy 10.347275 -436.35345)
			(xy 10.363139 -436.260928) (xy 10.386793 -436.170085) (xy 10.418065 -436.081576) (xy 10.456731 -435.996037)
			(xy 10.502512 -435.914085) (xy 10.555078 -435.836311) (xy 10.614051 -435.763276) (xy 10.679004 -435.695504)
			(xy 10.749471 -435.633485) (xy 10.824944 -435.577666) (xy 10.904879 -435.528448) (xy 10.9887 -435.486186)
			(xy 11.075803 -435.451186) (xy 11.16556 -435.423698) (xy 11.257325 -435.403921) (xy 11.350437 -435.391998)
			(xy 11.444224 -435.388014) (xy 11.538011 -435.391998) (xy 11.631123 -435.403921) (xy 11.722888 -435.423698)
			(xy 11.812645 -435.451186) (xy 11.899748 -435.486186) (xy 11.983569 -435.528448) (xy 12.063504 -435.577666)
			(xy 12.138977 -435.633485) (xy 12.209444 -435.695504) (xy 12.274397 -435.763276) (xy 12.33337 -435.836311)
			(xy 12.385936 -435.914085) (xy 12.431717 -435.996037) (xy 12.470383 -436.081576) (xy 12.501655 -436.170085)
			(xy 12.525309 -436.260928) (xy 12.541173 -436.35345) (xy 12.549134 -436.446984) (xy 12.549632 -436.49392)
			(xy 12.549134 -436.540856) (xy 12.541173 -436.63439) (xy 12.525309 -436.726912) (xy 12.501655 -436.817755)
			(xy 12.470383 -436.906264) (xy 12.431717 -436.991803) (xy 12.385936 -437.073755) (xy 12.33337 -437.151529)
			(xy 12.274397 -437.224564) (xy 12.209444 -437.292336) (xy 12.138977 -437.354355) (xy 12.063504 -437.410174)
			(xy 11.983569 -437.459392) (xy 11.899748 -437.501654) (xy 11.812645 -437.536654) (xy 11.722888 -437.564142)
			(xy 11.631123 -437.583919) (xy 11.538011 -437.595842) (xy 11.444224 -437.599827) (xy 11.350437 -437.595842)
			(xy 11.257325 -437.583919) (xy 11.16556 -437.564142) (xy 11.075803 -437.536654) (xy 10.9887 -437.501654)
			(xy 10.904879 -437.459392) (xy 10.824944 -437.410174) (xy 10.749471 -437.354355) (xy 10.679004 -437.292336)
			(xy 10.614051 -437.224564) (xy 10.555078 -437.151529) (xy 10.502512 -437.073755) (xy 10.456731 -436.991803)
			(xy 10.418065 -436.906264) (xy 10.386793 -436.817755) (xy 10.363139 -436.726912) (xy 10.347275 -436.63439)
			(xy 10.339314 -436.540856) (xy 7.049018 -436.540856) (xy 7.041057 -436.63439) (xy 7.025193 -436.726912)
			(xy 7.001539 -436.817755) (xy 6.970267 -436.906264) (xy 6.931601 -436.991803) (xy 6.88582 -437.073755)
			(xy 6.833254 -437.151529) (xy 6.774281 -437.224564) (xy 6.709328 -437.292336) (xy 6.638861 -437.354355)
			(xy 6.563388 -437.410174) (xy 6.483453 -437.459392) (xy 6.399632 -437.501654) (xy 6.312529 -437.536654)
			(xy 6.222772 -437.564142) (xy 6.131007 -437.583919) (xy 6.037895 -437.595842) (xy 5.944108 -437.599827)
			(xy 5.850321 -437.595842) (xy 5.757209 -437.583919) (xy 5.665444 -437.564142) (xy 5.575687 -437.536654)
			(xy 5.488584 -437.501654) (xy 5.404763 -437.459392) (xy 5.324828 -437.410174) (xy 5.249355 -437.354355)
			(xy 5.178888 -437.292336) (xy 5.113935 -437.224564) (xy 5.054962 -437.151529) (xy 5.002396 -437.073755)
			(xy 4.956615 -436.991803) (xy 4.917949 -436.906264) (xy 4.886677 -436.817755) (xy 4.863023 -436.726912)
			(xy 4.847159 -436.63439) (xy 4.839198 -436.540856) (xy 1.525016 -436.540856) (xy 1.525016 -440.741)
			(xy 10.339314 -440.741) (xy 10.339314 -440.647128) (xy 10.347275 -440.553594) (xy 10.363139 -440.461072)
			(xy 10.386793 -440.370229) (xy 10.418065 -440.28172) (xy 10.456731 -440.196181) (xy 10.502512 -440.114229)
			(xy 10.555078 -440.036455) (xy 10.614051 -439.96342) (xy 10.679004 -439.895648) (xy 10.749471 -439.833629)
			(xy 10.824944 -439.77781) (xy 10.904879 -439.728592) (xy 10.9887 -439.68633) (xy 11.075803 -439.65133)
			(xy 11.16556 -439.623842) (xy 11.257325 -439.604065) (xy 11.350437 -439.592142) (xy 11.444224 -439.588158)
			(xy 11.538011 -439.592142) (xy 11.631123 -439.604065) (xy 11.722888 -439.623842) (xy 11.812645 -439.65133)
			(xy 11.899748 -439.68633) (xy 11.983569 -439.728592) (xy 12.063504 -439.77781) (xy 12.138977 -439.833629)
			(xy 12.209444 -439.895648) (xy 12.274397 -439.96342) (xy 12.33337 -440.036455) (xy 12.385936 -440.114229)
			(xy 12.431717 -440.196181) (xy 12.470383 -440.28172) (xy 12.501655 -440.370229) (xy 12.525309 -440.461072)
			(xy 12.541173 -440.553594) (xy 12.549134 -440.647128) (xy 12.549632 -440.694064) (xy 12.549134 -440.741)
			(xy 12.541173 -440.834534) (xy 12.525309 -440.927056) (xy 12.501655 -441.017899) (xy 12.470383 -441.106408)
			(xy 12.431717 -441.191947) (xy 12.385936 -441.273899) (xy 12.33337 -441.351673) (xy 12.274397 -441.424708)
			(xy 12.209444 -441.49248) (xy 12.138977 -441.554499) (xy 12.063504 -441.610318) (xy 11.983569 -441.659536)
			(xy 11.899748 -441.701798) (xy 11.812645 -441.736798) (xy 11.722888 -441.764286) (xy 11.631123 -441.784063)
			(xy 11.538011 -441.795986) (xy 11.444224 -441.799971) (xy 11.350437 -441.795986) (xy 11.257325 -441.784063)
			(xy 11.16556 -441.764286) (xy 11.075803 -441.736798) (xy 10.9887 -441.701798) (xy 10.904879 -441.659536)
			(xy 10.824944 -441.610318) (xy 10.749471 -441.554499) (xy 10.679004 -441.49248) (xy 10.614051 -441.424708)
			(xy 10.555078 -441.351673) (xy 10.502512 -441.273899) (xy 10.456731 -441.191947) (xy 10.418065 -441.106408)
			(xy 10.386793 -441.017899) (xy 10.363139 -440.927056) (xy 10.347275 -440.834534) (xy 10.339314 -440.741)
			(xy 1.525016 -440.741) (xy 1.525016 -444.94089) (xy 10.339314 -444.94089) (xy 10.339314 -444.847018)
			(xy 10.347275 -444.753484) (xy 10.363139 -444.660962) (xy 10.386793 -444.570119) (xy 10.418065 -444.48161)
			(xy 10.456731 -444.396071) (xy 10.502512 -444.314119) (xy 10.555078 -444.236345) (xy 10.614051 -444.16331)
			(xy 10.679004 -444.095538) (xy 10.749471 -444.033519) (xy 10.824944 -443.9777) (xy 10.904879 -443.928482)
			(xy 10.9887 -443.88622) (xy 11.075803 -443.85122) (xy 11.16556 -443.823732) (xy 11.257325 -443.803955)
			(xy 11.350437 -443.792032) (xy 11.444224 -443.788048) (xy 11.538011 -443.792032) (xy 11.631123 -443.803955)
			(xy 11.722888 -443.823732) (xy 11.812645 -443.85122) (xy 11.899748 -443.88622) (xy 11.983569 -443.928482)
			(xy 12.063504 -443.9777) (xy 12.138977 -444.033519) (xy 12.209444 -444.095538) (xy 12.274397 -444.16331)
			(xy 12.33337 -444.236345) (xy 12.385936 -444.314119) (xy 12.431717 -444.396071) (xy 12.470383 -444.48161)
			(xy 12.501655 -444.570119) (xy 12.525309 -444.660962) (xy 12.541173 -444.753484) (xy 12.549134 -444.847018)
			(xy 12.549632 -444.893954) (xy 12.549134 -444.94089) (xy 12.541173 -445.034424) (xy 12.525309 -445.126946)
			(xy 12.501655 -445.217789) (xy 12.470383 -445.306298) (xy 12.431717 -445.391837) (xy 12.385936 -445.473789)
			(xy 12.33337 -445.551563) (xy 12.274397 -445.624598) (xy 12.209444 -445.69237) (xy 12.138977 -445.754389)
			(xy 12.063504 -445.810208) (xy 11.983569 -445.859426) (xy 11.899748 -445.901688) (xy 11.812645 -445.936688)
			(xy 11.722888 -445.964176) (xy 11.631123 -445.983953) (xy 11.538011 -445.995876) (xy 11.444224 -445.999861)
			(xy 11.350437 -445.995876) (xy 11.257325 -445.983953) (xy 11.16556 -445.964176) (xy 11.075803 -445.936688)
			(xy 10.9887 -445.901688) (xy 10.904879 -445.859426) (xy 10.824944 -445.810208) (xy 10.749471 -445.754389)
			(xy 10.679004 -445.69237) (xy 10.614051 -445.624598) (xy 10.555078 -445.551563) (xy 10.502512 -445.473789)
			(xy 10.456731 -445.391837) (xy 10.418065 -445.306298) (xy 10.386793 -445.217789) (xy 10.363139 -445.126946)
			(xy 10.347275 -445.034424) (xy 10.339314 -444.94089) (xy 1.525016 -444.94089) (xy 1.525016 -449.141034)
			(xy 4.839198 -449.141034) (xy 4.839198 -449.047162) (xy 4.847159 -448.953628) (xy 4.863023 -448.861106)
			(xy 4.886677 -448.770263) (xy 4.917949 -448.681754) (xy 4.956615 -448.596215) (xy 5.002396 -448.514263)
			(xy 5.054962 -448.436489) (xy 5.113935 -448.363454) (xy 5.178888 -448.295682) (xy 5.249355 -448.233663)
			(xy 5.324828 -448.177844) (xy 5.404763 -448.128626) (xy 5.488584 -448.086364) (xy 5.575687 -448.051364)
			(xy 5.665444 -448.023876) (xy 5.757209 -448.004099) (xy 5.850321 -447.992176) (xy 5.944108 -447.988192)
			(xy 6.037895 -447.992176) (xy 6.131007 -448.004099) (xy 6.222772 -448.023876) (xy 6.312529 -448.051364)
			(xy 6.399632 -448.086364) (xy 6.483453 -448.128626) (xy 6.563388 -448.177844) (xy 6.638861 -448.233663)
			(xy 6.709328 -448.295682) (xy 6.774281 -448.363454) (xy 6.833254 -448.436489) (xy 6.88582 -448.514263)
			(xy 6.931601 -448.596215) (xy 6.970267 -448.681754) (xy 7.001539 -448.770263) (xy 7.025193 -448.861106)
			(xy 7.041057 -448.953628) (xy 7.049018 -449.047162) (xy 7.049516 -449.094098) (xy 7.049018 -449.141034)
			(xy 10.339314 -449.141034) (xy 10.339314 -449.047162) (xy 10.347275 -448.953628) (xy 10.363139 -448.861106)
			(xy 10.386793 -448.770263) (xy 10.418065 -448.681754) (xy 10.456731 -448.596215) (xy 10.502512 -448.514263)
			(xy 10.555078 -448.436489) (xy 10.614051 -448.363454) (xy 10.679004 -448.295682) (xy 10.749471 -448.233663)
			(xy 10.824944 -448.177844) (xy 10.904879 -448.128626) (xy 10.9887 -448.086364) (xy 11.075803 -448.051364)
			(xy 11.16556 -448.023876) (xy 11.257325 -448.004099) (xy 11.350437 -447.992176) (xy 11.444224 -447.988192)
			(xy 11.538011 -447.992176) (xy 11.631123 -448.004099) (xy 11.722888 -448.023876) (xy 11.812645 -448.051364)
			(xy 11.899748 -448.086364) (xy 11.983569 -448.128626) (xy 12.063504 -448.177844) (xy 12.138977 -448.233663)
			(xy 12.209444 -448.295682) (xy 12.274397 -448.363454) (xy 12.33337 -448.436489) (xy 12.385936 -448.514263)
			(xy 12.431717 -448.596215) (xy 12.470383 -448.681754) (xy 12.501655 -448.770263) (xy 12.525309 -448.861106)
			(xy 12.541173 -448.953628) (xy 12.549134 -449.047162) (xy 12.549632 -449.094098) (xy 12.549134 -449.141034)
			(xy 12.541173 -449.234568) (xy 12.525309 -449.32709) (xy 12.501655 -449.417933) (xy 12.470383 -449.506442)
			(xy 12.431717 -449.591981) (xy 12.385936 -449.673933) (xy 12.33337 -449.751707) (xy 12.274397 -449.824742)
			(xy 12.209444 -449.892514) (xy 12.138977 -449.954533) (xy 12.063504 -450.010352) (xy 11.983569 -450.05957)
			(xy 11.899748 -450.101832) (xy 11.812645 -450.136832) (xy 11.722888 -450.16432) (xy 11.631123 -450.184097)
			(xy 11.538011 -450.19602) (xy 11.444224 -450.200005) (xy 11.350437 -450.19602) (xy 11.257325 -450.184097)
			(xy 11.16556 -450.16432) (xy 11.075803 -450.136832) (xy 10.9887 -450.101832) (xy 10.904879 -450.05957)
			(xy 10.824944 -450.010352) (xy 10.749471 -449.954533) (xy 10.679004 -449.892514) (xy 10.614051 -449.824742)
			(xy 10.555078 -449.751707) (xy 10.502512 -449.673933) (xy 10.456731 -449.591981) (xy 10.418065 -449.506442)
			(xy 10.386793 -449.417933) (xy 10.363139 -449.32709) (xy 10.347275 -449.234568) (xy 10.339314 -449.141034)
			(xy 7.049018 -449.141034) (xy 7.041057 -449.234568) (xy 7.025193 -449.32709) (xy 7.001539 -449.417933)
			(xy 6.970267 -449.506442) (xy 6.931601 -449.591981) (xy 6.88582 -449.673933) (xy 6.833254 -449.751707)
			(xy 6.774281 -449.824742) (xy 6.709328 -449.892514) (xy 6.638861 -449.954533) (xy 6.563388 -450.010352)
			(xy 6.483453 -450.05957) (xy 6.399632 -450.101832) (xy 6.312529 -450.136832) (xy 6.222772 -450.16432)
			(xy 6.131007 -450.184097) (xy 6.037895 -450.19602) (xy 5.944108 -450.200005) (xy 5.850321 -450.19602)
			(xy 5.757209 -450.184097) (xy 5.665444 -450.16432) (xy 5.575687 -450.136832) (xy 5.488584 -450.101832)
			(xy 5.404763 -450.05957) (xy 5.324828 -450.010352) (xy 5.249355 -449.954533) (xy 5.178888 -449.892514)
			(xy 5.113935 -449.824742) (xy 5.054962 -449.751707) (xy 5.002396 -449.673933) (xy 4.956615 -449.591981)
			(xy 4.917949 -449.506442) (xy 4.886677 -449.417933) (xy 4.863023 -449.32709) (xy 4.847159 -449.234568)
			(xy 4.839198 -449.141034) (xy 1.525016 -449.141034) (xy 1.525016 -453.340924) (xy 10.339314 -453.340924)
			(xy 10.339314 -453.247052) (xy 10.347275 -453.153518) (xy 10.363139 -453.060996) (xy 10.386793 -452.970153)
			(xy 10.418065 -452.881644) (xy 10.456731 -452.796105) (xy 10.502512 -452.714153) (xy 10.555078 -452.636379)
			(xy 10.614051 -452.563344) (xy 10.679004 -452.495572) (xy 10.749471 -452.433553) (xy 10.824944 -452.377734)
			(xy 10.904879 -452.328516) (xy 10.9887 -452.286254) (xy 11.075803 -452.251254) (xy 11.16556 -452.223766)
			(xy 11.257325 -452.203989) (xy 11.350437 -452.192066) (xy 11.444224 -452.188082) (xy 11.538011 -452.192066)
			(xy 11.631123 -452.203989) (xy 11.722888 -452.223766) (xy 11.812645 -452.251254) (xy 11.829871 -452.258176)
			(xy 26.890724 -452.258176) (xy 26.894795 -452.202554) (xy 26.906921 -452.148117) (xy 26.926844 -452.096026)
			(xy 26.95414 -452.047391) (xy 26.988226 -452.003248) (xy 27.028375 -451.964539) (xy 27.073733 -451.932088)
			(xy 27.123333 -451.906587) (xy 27.176117 -451.88858) (xy 27.23096 -451.87845) (xy 27.286694 -451.876413)
			(xy 27.342131 -451.882513) (xy 27.396088 -451.896619) (xy 27.447417 -451.918431) (xy 27.495023 -451.947485)
			(xy 27.537891 -451.98316) (xy 27.575108 -452.024697) (xy 27.605881 -452.07121) (xy 27.629553 -452.121707)
			(xy 27.645621 -452.175114) (xy 27.653741 -452.23029) (xy 27.65425 -452.258176) (xy 27.653741 -452.286062)
			(xy 27.645621 -452.341238) (xy 27.629553 -452.394645) (xy 27.605881 -452.445142) (xy 27.575108 -452.491655)
			(xy 27.537891 -452.533192) (xy 27.495023 -452.568867) (xy 27.447417 -452.597921) (xy 27.396088 -452.619733)
			(xy 27.342131 -452.633839) (xy 27.286694 -452.639939) (xy 27.23096 -452.637902) (xy 27.176117 -452.627772)
			(xy 27.123333 -452.609765) (xy 27.073733 -452.584264) (xy 27.028375 -452.551813) (xy 26.988226 -452.513104)
			(xy 26.95414 -452.468961) (xy 26.926844 -452.420326) (xy 26.906921 -452.368235) (xy 26.894795 -452.313798)
			(xy 26.890724 -452.258176) (xy 11.829871 -452.258176) (xy 11.899748 -452.286254) (xy 11.983569 -452.328516)
			(xy 12.063504 -452.377734) (xy 12.138977 -452.433553) (xy 12.209444 -452.495572) (xy 12.274397 -452.563344)
			(xy 12.33337 -452.636379) (xy 12.385936 -452.714153) (xy 12.431717 -452.796105) (xy 12.470383 -452.881644)
			(xy 12.501655 -452.970153) (xy 12.525309 -453.060996) (xy 12.541173 -453.153518) (xy 12.549134 -453.247052)
			(xy 12.549632 -453.293988) (xy 12.549134 -453.340924) (xy 12.541173 -453.434458) (xy 12.525309 -453.52698)
			(xy 12.501655 -453.617823) (xy 12.470383 -453.706332) (xy 12.431717 -453.791871) (xy 12.385936 -453.873823)
			(xy 12.33337 -453.951597) (xy 12.274397 -454.024632) (xy 12.209444 -454.092404) (xy 12.138977 -454.154423)
			(xy 12.063504 -454.210242) (xy 11.993473 -454.253362) (xy 29.519874 -454.253362) (xy 29.519874 -454.166462)
			(xy 29.527892 -454.079933) (xy 29.54386 -453.994513) (xy 29.567641 -453.910931) (xy 29.599033 -453.829899)
			(xy 29.637767 -453.75211) (xy 29.683514 -453.678226) (xy 29.735883 -453.608879) (xy 29.794427 -453.544659)
			(xy 29.858647 -453.486115) (xy 29.927994 -453.433746) (xy 30.001878 -453.387999) (xy 30.079667 -453.349265)
			(xy 30.160699 -453.317873) (xy 30.244281 -453.294092) (xy 30.329701 -453.278124) (xy 30.41623 -453.270106)
			(xy 30.50313 -453.270106) (xy 30.589659 -453.278124) (xy 30.675079 -453.294092) (xy 30.758661 -453.317873)
			(xy 30.839693 -453.349265) (xy 30.917482 -453.387999) (xy 30.991366 -453.433746) (xy 31.060713 -453.486115)
			(xy 31.124933 -453.544659) (xy 31.183477 -453.608879) (xy 31.235846 -453.678226) (xy 31.281593 -453.75211)
			(xy 31.320327 -453.829899) (xy 31.351719 -453.910931) (xy 31.3755 -453.994513) (xy 31.391468 -454.079933)
			(xy 31.399486 -454.166462) (xy 31.399988 -454.209912) (xy 31.399486 -454.253362) (xy 34.599874 -454.253362)
			(xy 34.599874 -454.166462) (xy 34.607892 -454.079933) (xy 34.62386 -453.994513) (xy 34.647641 -453.910931)
			(xy 34.679033 -453.829899) (xy 34.717767 -453.75211) (xy 34.763514 -453.678226) (xy 34.815883 -453.608879)
			(xy 34.874427 -453.544659) (xy 34.938647 -453.486115) (xy 35.007994 -453.433746) (xy 35.081878 -453.387999)
			(xy 35.159667 -453.349265) (xy 35.240699 -453.317873) (xy 35.324281 -453.294092) (xy 35.409701 -453.278124)
			(xy 35.49623 -453.270106) (xy 35.58313 -453.270106) (xy 35.669659 -453.278124) (xy 35.755079 -453.294092)
			(xy 35.838661 -453.317873) (xy 35.919693 -453.349265) (xy 35.997482 -453.387999) (xy 36.071366 -453.433746)
			(xy 36.140713 -453.486115) (xy 36.204933 -453.544659) (xy 36.263477 -453.608879) (xy 36.315846 -453.678226)
			(xy 36.361593 -453.75211) (xy 36.400327 -453.829899) (xy 36.431719 -453.910931) (xy 36.4555 -453.994513)
			(xy 36.471468 -454.079933) (xy 36.479486 -454.166462) (xy 36.479988 -454.209912) (xy 36.479486 -454.253362)
			(xy 36.471468 -454.339891) (xy 36.4555 -454.425311) (xy 36.431719 -454.508893) (xy 36.400327 -454.589925)
			(xy 36.361593 -454.667714) (xy 36.315846 -454.741598) (xy 36.263477 -454.810945) (xy 36.204933 -454.875165)
			(xy 36.140713 -454.933709) (xy 36.071366 -454.986078) (xy 35.997482 -455.031825) (xy 35.919693 -455.070559)
			(xy 35.838661 -455.101951) (xy 35.755079 -455.125732) (xy 35.669659 -455.1417) (xy 35.58313 -455.149718)
			(xy 35.49623 -455.149718) (xy 35.409701 -455.1417) (xy 35.324281 -455.125732) (xy 35.240699 -455.101951)
			(xy 35.159667 -455.070559) (xy 35.081878 -455.031825) (xy 35.007994 -454.986078) (xy 34.938647 -454.933709)
			(xy 34.874427 -454.875165) (xy 34.815883 -454.810945) (xy 34.763514 -454.741598) (xy 34.717767 -454.667714)
			(xy 34.679033 -454.589925) (xy 34.647641 -454.508893) (xy 34.62386 -454.425311) (xy 34.607892 -454.339891)
			(xy 34.599874 -454.253362) (xy 31.399486 -454.253362) (xy 31.391468 -454.339891) (xy 31.3755 -454.425311)
			(xy 31.351719 -454.508893) (xy 31.320327 -454.589925) (xy 31.281593 -454.667714) (xy 31.235846 -454.741598)
			(xy 31.183477 -454.810945) (xy 31.124933 -454.875165) (xy 31.060713 -454.933709) (xy 30.991366 -454.986078)
			(xy 30.917482 -455.031825) (xy 30.839693 -455.070559) (xy 30.758661 -455.101951) (xy 30.675079 -455.125732)
			(xy 30.589659 -455.1417) (xy 30.50313 -455.149718) (xy 30.41623 -455.149718) (xy 30.329701 -455.1417)
			(xy 30.244281 -455.125732) (xy 30.160699 -455.101951) (xy 30.079667 -455.070559) (xy 30.001878 -455.031825)
			(xy 29.927994 -454.986078) (xy 29.858647 -454.933709) (xy 29.794427 -454.875165) (xy 29.735883 -454.810945)
			(xy 29.683514 -454.741598) (xy 29.637767 -454.667714) (xy 29.599033 -454.589925) (xy 29.567641 -454.508893)
			(xy 29.54386 -454.425311) (xy 29.527892 -454.339891) (xy 29.519874 -454.253362) (xy 11.993473 -454.253362)
			(xy 11.983569 -454.25946) (xy 11.899748 -454.301722) (xy 11.812645 -454.336722) (xy 11.722888 -454.36421)
			(xy 11.631123 -454.383987) (xy 11.538011 -454.39591) (xy 11.444224 -454.399895) (xy 11.350437 -454.39591)
			(xy 11.257325 -454.383987) (xy 11.16556 -454.36421) (xy 11.075803 -454.336722) (xy 10.9887 -454.301722)
			(xy 10.904879 -454.25946) (xy 10.824944 -454.210242) (xy 10.749471 -454.154423) (xy 10.679004 -454.092404)
			(xy 10.614051 -454.024632) (xy 10.555078 -453.951597) (xy 10.502512 -453.873823) (xy 10.456731 -453.791871)
			(xy 10.418065 -453.706332) (xy 10.386793 -453.617823) (xy 10.363139 -453.52698) (xy 10.347275 -453.434458)
			(xy 10.339314 -453.340924) (xy 1.525016 -453.340924) (xy 1.525016 -455.070073) (xy 26.851826 -455.070073)
			(xy 26.854933 -455.014607) (xy 26.866051 -454.960178) (xy 26.884946 -454.907936) (xy 26.911217 -454.858987)
			(xy 26.944309 -454.814366) (xy 26.983523 -454.775016) (xy 27.02803 -454.741769) (xy 27.076887 -454.715328)
			(xy 27.129063 -454.696252) (xy 27.183453 -454.684945) (xy 27.238908 -454.681646) (xy 27.294256 -454.686424)
			(xy 27.348325 -454.699179) (xy 27.399973 -454.71964) (xy 27.448107 -454.747375) (xy 27.491711 -454.781798)
			(xy 27.52986 -454.822181) (xy 27.56175 -454.867669) (xy 27.586706 -454.917302) (xy 27.604199 -454.970029)
			(xy 27.613861 -455.024736) (xy 27.615487 -455.080265) (xy 27.609042 -455.135443) (xy 27.594662 -455.189104)
			(xy 27.572653 -455.240111) (xy 27.558492 -455.264012) (xy 27.547184 -455.283157) (xy 27.530785 -455.324484)
			(xy 27.521838 -455.368037) (xy 27.520619 -455.412482) (xy 27.527165 -455.456459) (xy 27.541275 -455.498623)
			(xy 27.562517 -455.537682) (xy 27.576018 -455.55535) (xy 27.592935 -455.577387) (xy 27.62084 -455.625427)
			(xy 27.641483 -455.677005) (xy 27.654428 -455.731032) (xy 27.6594 -455.786365) (xy 27.656294 -455.841834)
			(xy 27.645177 -455.896266) (xy 27.626283 -455.94851) (xy 27.600012 -455.997462) (xy 27.566919 -456.042086)
			(xy 27.527705 -456.081439) (xy 27.483197 -456.114689) (xy 27.434338 -456.141132) (xy 27.382161 -456.16021)
			(xy 27.327768 -456.171519) (xy 27.27231 -456.17482) (xy 27.21696 -456.170043) (xy 27.162888 -456.157289)
			(xy 27.111237 -456.136828) (xy 27.0631 -456.109092) (xy 27.019494 -456.074669) (xy 26.981342 -456.034285)
			(xy 26.94945 -455.988795) (xy 26.924492 -455.93916) (xy 26.906997 -455.886431) (xy 26.897334 -455.831722)
			(xy 26.895707 -455.77619) (xy 26.902152 -455.721009) (xy 26.916531 -455.667346) (xy 26.938541 -455.616336)
			(xy 26.952702 -455.592434) (xy 26.963957 -455.573261) (xy 26.980355 -455.531941) (xy 26.989303 -455.488396)
			(xy 26.990528 -455.443958) (xy 26.983992 -455.399986) (xy 26.969895 -455.357825) (xy 26.948669 -455.318766)
			(xy 26.935176 -455.301096) (xy 26.91828 -455.279043) (xy 26.890378 -455.231005) (xy 26.869738 -455.179429)
			(xy 26.856796 -455.125404) (xy 26.851826 -455.070073) (xy 1.525016 -455.070073) (xy 1.525016 -457.541068)
			(xy 10.339314 -457.541068) (xy 10.339314 -457.447196) (xy 10.347275 -457.353662) (xy 10.363139 -457.26114)
			(xy 10.386793 -457.170297) (xy 10.418065 -457.081788) (xy 10.456731 -456.996249) (xy 10.502512 -456.914297)
			(xy 10.555078 -456.836523) (xy 10.614051 -456.763488) (xy 10.679004 -456.695716) (xy 10.749471 -456.633697)
			(xy 10.824944 -456.577878) (xy 10.904879 -456.52866) (xy 10.9887 -456.486398) (xy 11.075803 -456.451398)
			(xy 11.16556 -456.42391) (xy 11.257325 -456.404133) (xy 11.350437 -456.39221) (xy 11.444224 -456.388226)
			(xy 11.538011 -456.39221) (xy 11.631123 -456.404133) (xy 11.722888 -456.42391) (xy 11.812645 -456.451398)
			(xy 11.899748 -456.486398) (xy 11.983569 -456.52866) (xy 12.063504 -456.577878) (xy 12.138977 -456.633697)
			(xy 12.209444 -456.695716) (xy 12.274397 -456.763488) (xy 12.298519 -456.793362) (xy 29.519874 -456.793362)
			(xy 29.519874 -456.706462) (xy 29.527892 -456.619933) (xy 29.54386 -456.534513) (xy 29.567641 -456.450931)
			(xy 29.599033 -456.369899) (xy 29.637767 -456.29211) (xy 29.683514 -456.218226) (xy 29.735883 -456.148879)
			(xy 29.794427 -456.084659) (xy 29.858647 -456.026115) (xy 29.927994 -455.973746) (xy 30.001878 -455.927999)
			(xy 30.079667 -455.889265) (xy 30.160699 -455.857873) (xy 30.244281 -455.834092) (xy 30.329701 -455.818124)
			(xy 30.41623 -455.810106) (xy 30.50313 -455.810106) (xy 30.589659 -455.818124) (xy 30.675079 -455.834092)
			(xy 30.758661 -455.857873) (xy 30.839693 -455.889265) (xy 30.917482 -455.927999) (xy 30.991366 -455.973746)
			(xy 31.060713 -456.026115) (xy 31.124933 -456.084659) (xy 31.183477 -456.148879) (xy 31.235846 -456.218226)
			(xy 31.281593 -456.29211) (xy 31.320327 -456.369899) (xy 31.351719 -456.450931) (xy 31.3755 -456.534513)
			(xy 31.391468 -456.619933) (xy 31.399486 -456.706462) (xy 31.399988 -456.749912) (xy 31.399486 -456.793362)
			(xy 34.599874 -456.793362) (xy 34.599874 -456.706462) (xy 34.607892 -456.619933) (xy 34.62386 -456.534513)
			(xy 34.647641 -456.450931) (xy 34.679033 -456.369899) (xy 34.717767 -456.29211) (xy 34.763514 -456.218226)
			(xy 34.815883 -456.148879) (xy 34.874427 -456.084659) (xy 34.938647 -456.026115) (xy 35.007994 -455.973746)
			(xy 35.081878 -455.927999) (xy 35.159667 -455.889265) (xy 35.240699 -455.857873) (xy 35.324281 -455.834092)
			(xy 35.409701 -455.818124) (xy 35.49623 -455.810106) (xy 35.58313 -455.810106) (xy 35.669659 -455.818124)
			(xy 35.755079 -455.834092) (xy 35.838661 -455.857873) (xy 35.919693 -455.889265) (xy 35.997482 -455.927999)
			(xy 36.071366 -455.973746) (xy 36.140713 -456.026115) (xy 36.204933 -456.084659) (xy 36.263477 -456.148879)
			(xy 36.315846 -456.218226) (xy 36.361593 -456.29211) (xy 36.400327 -456.369899) (xy 36.431719 -456.450931)
			(xy 36.4555 -456.534513) (xy 36.471468 -456.619933) (xy 36.479486 -456.706462) (xy 36.479988 -456.749912)
			(xy 36.479486 -456.793362) (xy 36.471468 -456.879891) (xy 36.4555 -456.965311) (xy 36.431719 -457.048893)
			(xy 36.400327 -457.129925) (xy 36.361593 -457.207714) (xy 36.315846 -457.281598) (xy 36.263477 -457.350945)
			(xy 36.210978 -457.408534) (xy 39.35679 -457.408534) (xy 39.360861 -457.352912) (xy 39.372987 -457.298475)
			(xy 39.39291 -457.246384) (xy 39.420206 -457.197749) (xy 39.454292 -457.153606) (xy 39.494441 -457.114897)
			(xy 39.539799 -457.082446) (xy 39.589399 -457.056945) (xy 39.642183 -457.038938) (xy 39.697026 -457.028808)
			(xy 39.75276 -457.026771) (xy 39.808197 -457.032871) (xy 39.862154 -457.046977) (xy 39.913483 -457.068789)
			(xy 39.961089 -457.097843) (xy 40.003957 -457.133518) (xy 40.041174 -457.175055) (xy 40.071947 -457.221568)
			(xy 40.095619 -457.272065) (xy 40.111687 -457.325472) (xy 40.119807 -457.380648) (xy 40.120316 -457.408534)
			(xy 40.119807 -457.43642) (xy 40.111687 -457.491596) (xy 40.095619 -457.545003) (xy 40.071947 -457.5955)
			(xy 40.041174 -457.642013) (xy 40.003957 -457.68355) (xy 39.961089 -457.719225) (xy 39.913483 -457.748279)
			(xy 39.862154 -457.770091) (xy 39.808197 -457.784197) (xy 39.75276 -457.790297) (xy 39.697026 -457.78826)
			(xy 39.642183 -457.77813) (xy 39.589399 -457.760123) (xy 39.539799 -457.734622) (xy 39.494441 -457.702171)
			(xy 39.454292 -457.663462) (xy 39.420206 -457.619319) (xy 39.39291 -457.570684) (xy 39.372987 -457.518593)
			(xy 39.360861 -457.464156) (xy 39.35679 -457.408534) (xy 36.210978 -457.408534) (xy 36.204933 -457.415165)
			(xy 36.140713 -457.473709) (xy 36.071366 -457.526078) (xy 35.997482 -457.571825) (xy 35.919693 -457.610559)
			(xy 35.838661 -457.641951) (xy 35.755079 -457.665732) (xy 35.669659 -457.6817) (xy 35.58313 -457.689718)
			(xy 35.49623 -457.689718) (xy 35.409701 -457.6817) (xy 35.324281 -457.665732) (xy 35.240699 -457.641951)
			(xy 35.159667 -457.610559) (xy 35.081878 -457.571825) (xy 35.007994 -457.526078) (xy 34.938647 -457.473709)
			(xy 34.874427 -457.415165) (xy 34.815883 -457.350945) (xy 34.763514 -457.281598) (xy 34.717767 -457.207714)
			(xy 34.679033 -457.129925) (xy 34.647641 -457.048893) (xy 34.62386 -456.965311) (xy 34.607892 -456.879891)
			(xy 34.599874 -456.793362) (xy 31.399486 -456.793362) (xy 31.391468 -456.879891) (xy 31.3755 -456.965311)
			(xy 31.351719 -457.048893) (xy 31.320327 -457.129925) (xy 31.281593 -457.207714) (xy 31.235846 -457.281598)
			(xy 31.183477 -457.350945) (xy 31.124933 -457.415165) (xy 31.060713 -457.473709) (xy 30.991366 -457.526078)
			(xy 30.917482 -457.571825) (xy 30.839693 -457.610559) (xy 30.758661 -457.641951) (xy 30.675079 -457.665732)
			(xy 30.589659 -457.6817) (xy 30.50313 -457.689718) (xy 30.41623 -457.689718) (xy 30.329701 -457.6817)
			(xy 30.244281 -457.665732) (xy 30.160699 -457.641951) (xy 30.079667 -457.610559) (xy 30.001878 -457.571825)
			(xy 29.927994 -457.526078) (xy 29.858647 -457.473709) (xy 29.794427 -457.415165) (xy 29.735883 -457.350945)
			(xy 29.683514 -457.281598) (xy 29.637767 -457.207714) (xy 29.599033 -457.129925) (xy 29.567641 -457.048893)
			(xy 29.54386 -456.965311) (xy 29.527892 -456.879891) (xy 29.519874 -456.793362) (xy 12.298519 -456.793362)
			(xy 12.33337 -456.836523) (xy 12.385936 -456.914297) (xy 12.431717 -456.996249) (xy 12.470383 -457.081788)
			(xy 12.501655 -457.170297) (xy 12.525309 -457.26114) (xy 12.541173 -457.353662) (xy 12.549134 -457.447196)
			(xy 12.549632 -457.494132) (xy 12.549134 -457.541068) (xy 12.541173 -457.634602) (xy 12.525309 -457.727124)
			(xy 12.515077 -457.76642) (xy 26.750008 -457.76642) (xy 26.754079 -457.710798) (xy 26.766205 -457.656361)
			(xy 26.786128 -457.60427) (xy 26.813424 -457.555635) (xy 26.84751 -457.511492) (xy 26.887659 -457.472783)
			(xy 26.933017 -457.440332) (xy 26.982617 -457.414831) (xy 27.035401 -457.396824) (xy 27.090244 -457.386694)
			(xy 27.145978 -457.384657) (xy 27.201415 -457.390757) (xy 27.255372 -457.404863) (xy 27.306701 -457.426675)
			(xy 27.354307 -457.455729) (xy 27.397175 -457.491404) (xy 27.434392 -457.532941) (xy 27.465165 -457.579454)
			(xy 27.488837 -457.629951) (xy 27.504905 -457.683358) (xy 27.513025 -457.738534) (xy 27.513534 -457.76642)
			(xy 27.513025 -457.794306) (xy 27.504905 -457.849482) (xy 27.488837 -457.902889) (xy 27.465165 -457.953386)
			(xy 27.434392 -457.999899) (xy 27.397175 -458.041436) (xy 27.354307 -458.077111) (xy 27.306701 -458.106165)
			(xy 27.255372 -458.127977) (xy 27.201415 -458.142083) (xy 27.145978 -458.148183) (xy 27.090244 -458.146146)
			(xy 27.035401 -458.136016) (xy 26.982617 -458.118009) (xy 26.933017 -458.092508) (xy 26.887659 -458.060057)
			(xy 26.84751 -458.021348) (xy 26.813424 -457.977205) (xy 26.786128 -457.92857) (xy 26.766205 -457.876479)
			(xy 26.754079 -457.822042) (xy 26.750008 -457.76642) (xy 12.515077 -457.76642) (xy 12.501655 -457.817967)
			(xy 12.470383 -457.906476) (xy 12.431717 -457.992015) (xy 12.385936 -458.073967) (xy 12.33337 -458.151741)
			(xy 12.274397 -458.224776) (xy 12.209444 -458.292548) (xy 12.138977 -458.354567) (xy 12.063504 -458.410386)
			(xy 11.983569 -458.459604) (xy 11.899748 -458.501866) (xy 11.812645 -458.536866) (xy 11.722888 -458.564354)
			(xy 11.631123 -458.584131) (xy 11.538011 -458.596054) (xy 11.444224 -458.600039) (xy 11.350437 -458.596054)
			(xy 11.257325 -458.584131) (xy 11.16556 -458.564354) (xy 11.075803 -458.536866) (xy 10.9887 -458.501866)
			(xy 10.904879 -458.459604) (xy 10.824944 -458.410386) (xy 10.749471 -458.354567) (xy 10.679004 -458.292548)
			(xy 10.614051 -458.224776) (xy 10.555078 -458.151741) (xy 10.502512 -458.073967) (xy 10.456731 -457.992015)
			(xy 10.418065 -457.906476) (xy 10.386793 -457.817967) (xy 10.363139 -457.727124) (xy 10.347275 -457.634602)
			(xy 10.339314 -457.541068) (xy 1.525016 -457.541068) (xy 1.525016 -460.309635) (xy 27.157359 -460.309635)
			(xy 27.157359 -460.246365) (xy 27.165618 -460.183636) (xy 27.181994 -460.122522) (xy 27.206207 -460.064069)
			(xy 27.237843 -460.009276) (xy 27.276361 -459.959081) (xy 27.321101 -459.914343) (xy 27.371297 -459.875829)
			(xy 27.426092 -459.844196) (xy 27.484547 -459.819986) (xy 27.545662 -459.803613) (xy 27.608391 -459.795357)
			(xy 27.640026 -459.794864) (xy 28.449778 -459.794864) (xy 28.72867 -460.073756) (xy 29.389324 -460.073756)
			(xy 29.412764 -460.073118) (xy 29.458845 -460.064497) (xy 29.502564 -460.04757) (xy 29.542436 -460.022912)
			(xy 29.577108 -459.991358) (xy 29.605406 -459.953981) (xy 29.626367 -459.912047) (xy 29.639281 -459.86698)
			(xy 29.643711 -459.820309) (xy 29.639505 -459.773617) (xy 29.626806 -459.728489) (xy 29.616908 -459.707234)
			(xy 29.598093 -459.668112) (xy 29.566902 -459.587091) (xy 29.543312 -459.503541) (xy 29.527523 -459.418172)
			(xy 29.519669 -459.331711) (xy 29.519818 -459.244894) (xy 29.527968 -459.15846) (xy 29.544049 -459.073145)
			(xy 29.567925 -458.989676) (xy 29.599393 -458.908763) (xy 29.638185 -458.831094) (xy 29.68397 -458.757332)
			(xy 29.736359 -458.688103) (xy 29.794905 -458.623998) (xy 29.859111 -458.565561) (xy 29.928429 -458.513291)
			(xy 30.00227 -458.467632) (xy 30.080005 -458.428974) (xy 30.160972 -458.397645) (xy 30.244482 -458.373911)
			(xy 30.329824 -458.357976) (xy 30.416271 -458.349974) (xy 30.503089 -458.349974) (xy 30.589536 -458.357976)
			(xy 30.674878 -458.373911) (xy 30.758388 -458.397645) (xy 30.839355 -458.428974) (xy 30.91709 -458.467632)
			(xy 30.990931 -458.513291) (xy 31.060249 -458.565561) (xy 31.124455 -458.623998) (xy 31.183001 -458.688103)
			(xy 31.23539 -458.757332) (xy 31.281175 -458.831094) (xy 31.319967 -458.908763) (xy 31.351435 -458.989676)
			(xy 31.375311 -459.073145) (xy 31.391392 -459.15846) (xy 31.399542 -459.244894) (xy 31.399691 -459.331711)
			(xy 31.391837 -459.418172) (xy 31.376048 -459.503541) (xy 31.352458 -459.587091) (xy 31.321267 -459.668112)
			(xy 31.302452 -459.707234) (xy 31.292581 -459.728512) (xy 31.27984 -459.773646) (xy 31.2756 -459.820351)
			(xy 31.280006 -459.867041) (xy 31.292907 -459.91213) (xy 31.313865 -459.954083) (xy 31.342169 -459.991477)
			(xy 31.376855 -460.02304) (xy 31.416746 -460.0477) (xy 31.460485 -460.064618) (xy 31.506587 -460.07322)
			(xy 31.530036 -460.073756) (xy 34.469324 -460.073756) (xy 34.492764 -460.073118) (xy 34.538845 -460.064497)
			(xy 34.582564 -460.04757) (xy 34.622436 -460.022912) (xy 34.657108 -459.991358) (xy 34.685406 -459.953981)
			(xy 34.706367 -459.912047) (xy 34.719281 -459.86698) (xy 34.723711 -459.820309) (xy 34.719505 -459.773617)
			(xy 34.706806 -459.728489) (xy 34.696908 -459.707234) (xy 34.678093 -459.668112) (xy 34.646902 -459.587091)
			(xy 34.623312 -459.503541) (xy 34.607523 -459.418172) (xy 34.599669 -459.331711) (xy 34.599818 -459.244894)
			(xy 34.607968 -459.15846) (xy 34.624049 -459.073145) (xy 34.647925 -458.989676) (xy 34.679393 -458.908763)
			(xy 34.718185 -458.831094) (xy 34.76397 -458.757332) (xy 34.816359 -458.688103) (xy 34.874905 -458.623998)
			(xy 34.939111 -458.565561) (xy 35.008429 -458.513291) (xy 35.08227 -458.467632) (xy 35.160005 -458.428974)
			(xy 35.240972 -458.397645) (xy 35.324482 -458.373911) (xy 35.409824 -458.357976) (xy 35.496271 -458.349974)
			(xy 35.583089 -458.349974) (xy 35.669536 -458.357976) (xy 35.754878 -458.373911) (xy 35.838388 -458.397645)
			(xy 35.919355 -458.428974) (xy 35.99709 -458.467632) (xy 36.070931 -458.513291) (xy 36.081981 -458.521623)
			(xy 63.23697 -458.521623) (xy 63.240854 -458.467267) (xy 63.252435 -458.414018) (xy 63.271476 -458.362958)
			(xy 63.29759 -458.315128) (xy 63.330245 -458.271502) (xy 63.368777 -458.232967) (xy 63.4124 -458.200308)
			(xy 63.460228 -458.17419) (xy 63.511285 -458.155144) (xy 63.564534 -458.143559) (xy 63.618889 -458.13967)
			(xy 63.673245 -458.143556) (xy 63.726494 -458.155138) (xy 63.777553 -458.174181) (xy 63.825382 -458.200297)
			(xy 63.847472 -458.216254) (xy 63.866484 -458.22985) (xy 63.908367 -458.250582) (xy 63.953335 -458.263308)
			(xy 63.999872 -458.267598) (xy 64.046409 -458.263308) (xy 64.091377 -458.250582) (xy 64.13326 -458.22985)
			(xy 64.152272 -458.216254) (xy 64.174396 -458.200343) (xy 64.222222 -458.174223) (xy 64.273278 -458.155175)
			(xy 64.326525 -458.143588) (xy 64.380879 -458.139697) (xy 64.435233 -458.143582) (xy 64.488482 -458.155163)
			(xy 64.53954 -458.174205) (xy 64.587368 -458.20032) (xy 64.630992 -458.232976) (xy 64.669525 -458.271509)
			(xy 64.702181 -458.315133) (xy 64.728296 -458.362962) (xy 64.747337 -458.41402) (xy 64.758918 -458.467268)
			(xy 64.762803 -458.521623) (xy 65.312349 -458.521623) (xy 65.316234 -458.467263) (xy 65.327816 -458.414008)
			(xy 65.34686 -458.362945) (xy 65.372977 -458.315112) (xy 65.405635 -458.271482) (xy 65.444171 -458.232945)
			(xy 65.4878 -458.200284) (xy 65.535632 -458.174166) (xy 65.586695 -458.15512) (xy 65.639949 -458.143536)
			(xy 65.694309 -458.139649) (xy 65.748669 -458.143539) (xy 65.801922 -458.155125) (xy 65.852984 -458.174173)
			(xy 65.900815 -458.200294) (xy 65.922906 -458.216254) (xy 65.941918 -458.22985) (xy 65.983801 -458.250582)
			(xy 66.028769 -458.263308) (xy 66.075306 -458.267598) (xy 66.121843 -458.263308) (xy 66.166811 -458.250582)
			(xy 66.208694 -458.22985) (xy 66.227706 -458.216254) (xy 66.24983 -458.200346) (xy 66.297653 -458.174231)
			(xy 66.348705 -458.155188) (xy 66.401948 -458.143605) (xy 66.456298 -458.139717) (xy 66.510648 -458.143605)
			(xy 66.563891 -458.155187) (xy 66.614944 -458.174229) (xy 66.662767 -458.200344) (xy 66.706387 -458.232999)
			(xy 66.744915 -458.271529) (xy 66.777567 -458.31515) (xy 66.803679 -458.362975) (xy 66.822719 -458.414029)
			(xy 66.834298 -458.467273) (xy 66.838183 -458.521623) (xy 66.838136 -458.522286) (xy 67.536712 -458.522286)
			(xy 67.540602 -458.467936) (xy 67.552186 -458.414693) (xy 67.571231 -458.36364) (xy 67.597347 -458.315818)
			(xy 67.630004 -458.272199) (xy 67.668535 -458.233672) (xy 67.712158 -458.201021) (xy 67.759984 -458.174911)
			(xy 67.811038 -458.155873) (xy 67.864283 -458.144295) (xy 67.918633 -458.140412) (xy 67.972983 -458.144304)
			(xy 68.026225 -458.155892) (xy 68.077277 -458.174939) (xy 68.125098 -458.201057) (xy 68.147184 -458.217016)
			(xy 68.166196 -458.230612) (xy 68.208079 -458.251344) (xy 68.253047 -458.26407) (xy 68.299584 -458.26836)
			(xy 68.346121 -458.26407) (xy 68.391089 -458.251344) (xy 68.432972 -458.230612) (xy 68.451984 -458.217016)
			(xy 68.47405 -458.201022) (xy 68.521878 -458.174896) (xy 68.572938 -458.155843) (xy 68.626189 -458.14425)
			(xy 68.680548 -458.140355) (xy 68.734909 -458.144235) (xy 68.788163 -458.155814) (xy 68.839228 -458.174853)
			(xy 68.887063 -458.200967) (xy 68.930695 -458.233622) (xy 68.969235 -458.272155) (xy 69.001898 -458.315781)
			(xy 69.028019 -458.363612) (xy 69.047068 -458.414673) (xy 69.058655 -458.467926) (xy 69.062545 -458.522286)
			(xy 69.058659 -458.576646) (xy 69.047076 -458.629899) (xy 69.028031 -458.680962) (xy 69.001913 -458.728794)
			(xy 68.969253 -458.772423) (xy 68.930717 -458.810959) (xy 68.887087 -458.843618) (xy 68.839254 -458.869735)
			(xy 68.788191 -458.888778) (xy 68.734937 -458.90036) (xy 68.680577 -458.904245) (xy 68.626218 -458.900354)
			(xy 68.572965 -458.888766) (xy 68.521904 -458.869716) (xy 68.474074 -458.843593) (xy 68.451984 -458.827632)
			(xy 68.432972 -458.814036) (xy 68.391089 -458.793304) (xy 68.346121 -458.780578) (xy 68.299584 -458.776288)
			(xy 68.253047 -458.780578) (xy 68.208079 -458.793304) (xy 68.166196 -458.814036) (xy 68.147184 -458.827632)
			(xy 68.125074 -458.843558) (xy 68.077251 -458.869673) (xy 68.026198 -458.888716) (xy 67.972954 -458.9003)
			(xy 67.918605 -458.904188) (xy 67.864254 -458.900301) (xy 67.811011 -458.888719) (xy 67.759958 -458.869677)
			(xy 67.712134 -458.843563) (xy 67.668514 -458.810909) (xy 67.629985 -458.772379) (xy 67.597332 -458.728758)
			(xy 67.571219 -458.680933) (xy 67.552178 -458.62988) (xy 67.540598 -458.576636) (xy 67.536712 -458.522286)
			(xy 66.838136 -458.522286) (xy 66.834292 -458.575972) (xy 66.822706 -458.629215) (xy 66.80366 -458.680267)
			(xy 66.777543 -458.728088) (xy 66.744885 -458.771706) (xy 66.706352 -458.810231) (xy 66.662729 -458.842881)
			(xy 66.614903 -458.868989) (xy 66.563848 -458.888026) (xy 66.510603 -458.899602) (xy 66.456253 -458.903483)
			(xy 66.401903 -458.899588) (xy 66.348661 -458.887999) (xy 66.297611 -458.86895) (xy 66.249791 -458.84283)
			(xy 66.227706 -458.82687) (xy 66.208694 -458.813274) (xy 66.166811 -458.792542) (xy 66.121843 -458.779816)
			(xy 66.075306 -458.775526) (xy 66.028769 -458.779816) (xy 65.983801 -458.792542) (xy 65.941918 -458.813274)
			(xy 65.922906 -458.82687) (xy 65.900853 -458.842882) (xy 65.853025 -458.869008) (xy 65.801965 -458.888062)
			(xy 65.748714 -458.899655) (xy 65.694354 -458.903551) (xy 65.639994 -458.89967) (xy 65.586739 -458.888093)
			(xy 65.535674 -458.869053) (xy 65.487838 -458.84294) (xy 65.444206 -458.810285) (xy 65.405665 -458.771752)
			(xy 65.373001 -458.728127) (xy 65.346879 -458.680297) (xy 65.327829 -458.629235) (xy 65.316241 -458.575983)
			(xy 65.312349 -458.521623) (xy 64.762803 -458.521623) (xy 64.758912 -458.575977) (xy 64.747324 -458.629224)
			(xy 64.728277 -458.68028) (xy 64.702156 -458.728105) (xy 64.669495 -458.771726) (xy 64.630958 -458.810254)
			(xy 64.58733 -458.842905) (xy 64.539498 -458.869014) (xy 64.488438 -458.88805) (xy 64.435188 -458.899625)
			(xy 64.380833 -458.903503) (xy 64.32648 -458.899606) (xy 64.273234 -458.888012) (xy 64.22218 -458.868958)
			(xy 64.174358 -458.842832) (xy 64.152272 -458.82687) (xy 64.13326 -458.813274) (xy 64.091377 -458.792542)
			(xy 64.046409 -458.779816) (xy 63.999872 -458.775526) (xy 63.953335 -458.779816) (xy 63.908367 -458.792542)
			(xy 63.866484 -458.813274) (xy 63.847472 -458.82687) (xy 63.82542 -458.842879) (xy 63.777594 -458.869)
			(xy 63.726538 -458.888049) (xy 63.67329 -458.899638) (xy 63.618935 -458.90353) (xy 63.564579 -458.899647)
			(xy 63.511329 -458.888069) (xy 63.460269 -458.869029) (xy 63.412439 -458.842917) (xy 63.368811 -458.810263)
			(xy 63.330275 -458.771732) (xy 63.297615 -458.72811) (xy 63.271495 -458.680283) (xy 63.252448 -458.629226)
			(xy 63.240861 -458.575978) (xy 63.23697 -458.521623) (xy 36.081981 -458.521623) (xy 36.140249 -458.565561)
			(xy 36.204455 -458.623998) (xy 36.263001 -458.688103) (xy 36.31539 -458.757332) (xy 36.361175 -458.831094)
			(xy 36.399967 -458.908763) (xy 36.431435 -458.989676) (xy 36.455311 -459.073145) (xy 36.471392 -459.15846)
			(xy 36.479542 -459.244894) (xy 36.479691 -459.331711) (xy 36.471837 -459.418172) (xy 36.456048 -459.503541)
			(xy 36.432458 -459.587091) (xy 36.401267 -459.668112) (xy 36.382452 -459.707234) (xy 36.372581 -459.728512)
			(xy 36.35984 -459.773646) (xy 36.3556 -459.820351) (xy 36.360006 -459.867041) (xy 36.372907 -459.91213)
			(xy 36.393865 -459.954083) (xy 36.422169 -459.991477) (xy 36.456855 -460.02304) (xy 36.496746 -460.0477)
			(xy 36.540485 -460.064618) (xy 36.586587 -460.07322) (xy 36.610036 -460.073756) (xy 42.636186 -460.073756)
			(xy 42.840605 -460.278184) (xy 63.237021 -460.278184) (xy 63.24091 -460.223836) (xy 63.252495 -460.170595)
			(xy 63.271539 -460.119545) (xy 63.297654 -460.071724) (xy 63.330309 -460.028107) (xy 63.368839 -459.989581)
			(xy 63.41246 -459.95693) (xy 63.460284 -459.930821) (xy 63.511337 -459.911783) (xy 63.564579 -459.900204)
			(xy 63.618928 -459.896321) (xy 63.673276 -459.900212) (xy 63.726516 -459.911798) (xy 63.777566 -459.930844)
			(xy 63.825386 -459.95696) (xy 63.847472 -459.972918) (xy 63.866484 -459.986514) (xy 63.908367 -460.007246)
			(xy 63.953335 -460.019972) (xy 63.999872 -460.024262) (xy 64.046409 -460.019972) (xy 64.091377 -460.007246)
			(xy 64.13326 -459.986514) (xy 64.152272 -459.972918) (xy 64.174336 -459.956921) (xy 64.222165 -459.930792)
			(xy 64.273226 -459.911737) (xy 64.326479 -459.900143) (xy 64.38084 -459.896246) (xy 64.435203 -459.900126)
			(xy 64.488459 -459.911703) (xy 64.539526 -459.930743) (xy 64.587363 -459.956856) (xy 64.630997 -459.989512)
			(xy 64.669538 -460.028046) (xy 64.702203 -460.071673) (xy 64.728326 -460.119505) (xy 64.747376 -460.170568)
			(xy 64.758964 -460.223823) (xy 64.762854 -460.278184) (xy 65.312401 -460.278184) (xy 65.316291 -460.223832)
			(xy 65.327876 -460.170586) (xy 65.346922 -460.119531) (xy 65.37304 -460.071707) (xy 65.405699 -460.028087)
			(xy 65.444234 -459.989558) (xy 65.48786 -459.956907) (xy 65.535688 -459.930796) (xy 65.586746 -459.911759)
			(xy 65.639994 -459.900182) (xy 65.694347 -459.896301) (xy 65.748699 -459.900195) (xy 65.801944 -459.911785)
			(xy 65.852997 -459.930835) (xy 65.90082 -459.956957) (xy 65.922906 -459.972918) (xy 65.941918 -459.986514)
			(xy 65.983801 -460.007246) (xy 66.028769 -460.019972) (xy 66.075306 -460.024262) (xy 66.121843 -460.019972)
			(xy 66.166811 -460.007246) (xy 66.208694 -459.986514) (xy 66.227706 -459.972918) (xy 66.24977 -459.956923)
			(xy 66.297596 -459.9308) (xy 66.348654 -459.91175) (xy 66.401903 -459.90016) (xy 66.45626 -459.896266)
			(xy 66.510617 -459.900148) (xy 66.563869 -459.911727) (xy 66.614931 -459.930767) (xy 66.662763 -459.95688)
			(xy 66.706391 -459.989535) (xy 66.744929 -460.028066) (xy 66.77759 -460.07169) (xy 66.80371 -460.119519)
			(xy 66.822757 -460.170578) (xy 66.834344 -460.223827) (xy 66.838234 -460.278184) (xy 66.838175 -460.279007)
			(xy 67.536683 -460.279007) (xy 67.54057 -460.224653) (xy 67.552153 -460.171405) (xy 67.571196 -460.120348)
			(xy 67.597311 -460.072521) (xy 67.629968 -460.028897) (xy 67.6685 -459.990365) (xy 67.712124 -459.957709)
			(xy 67.759952 -459.931594) (xy 67.81101 -459.912551) (xy 67.864258 -459.900969) (xy 67.918612 -459.897083)
			(xy 67.972966 -459.900973) (xy 68.026213 -459.912558) (xy 68.077269 -459.931604) (xy 68.125095 -459.957721)
			(xy 68.147184 -459.97368) (xy 68.166196 -459.987276) (xy 68.208079 -460.008008) (xy 68.253047 -460.020734)
			(xy 68.299584 -460.025024) (xy 68.346121 -460.020734) (xy 68.391089 -460.008008) (xy 68.432972 -459.987276)
			(xy 68.451984 -459.97368) (xy 68.474084 -459.957735) (xy 68.52191 -459.931613) (xy 68.572966 -459.912564)
			(xy 68.626215 -459.900976) (xy 68.68057 -459.897083) (xy 68.734926 -459.900967) (xy 68.788176 -459.912547)
			(xy 68.839236 -459.931588) (xy 68.887066 -459.957703) (xy 68.930692 -459.990358) (xy 68.969227 -460.028891)
			(xy 69.001885 -460.072515) (xy 69.028002 -460.120343) (xy 69.047046 -460.171402) (xy 69.05863 -460.224651)
			(xy 69.062517 -460.279007) (xy 69.058628 -460.333363) (xy 69.047042 -460.386612) (xy 69.027996 -460.43767)
			(xy 69.001877 -460.485497) (xy 68.969217 -460.52912) (xy 68.930681 -460.567651) (xy 68.887054 -460.600305)
			(xy 68.839223 -460.626418) (xy 68.788162 -460.645457) (xy 68.734912 -460.657035) (xy 68.680556 -460.660917)
			(xy 68.6262 -460.657022) (xy 68.572953 -460.645432) (xy 68.521897 -460.626381) (xy 68.474072 -460.600257)
			(xy 68.451984 -460.584296) (xy 68.432972 -460.5707) (xy 68.391089 -460.549968) (xy 68.346121 -460.537242)
			(xy 68.299584 -460.532952) (xy 68.253047 -460.537242) (xy 68.208079 -460.549968) (xy 68.166196 -460.5707)
			(xy 68.147184 -460.584296) (xy 68.125107 -460.600271) (xy 68.077282 -460.62639) (xy 68.026227 -460.645438)
			(xy 67.97298 -460.657025) (xy 67.918626 -460.660917) (xy 67.864272 -460.657033) (xy 67.811023 -460.645453)
			(xy 67.759965 -460.626412) (xy 67.712137 -460.600299) (xy 67.668511 -460.567645) (xy 67.629977 -460.529114)
			(xy 67.597319 -460.485492) (xy 67.571202 -460.437665) (xy 67.552157 -460.386609) (xy 67.540572 -460.333361)
			(xy 67.536683 -460.279007) (xy 66.838175 -460.279007) (xy 66.834348 -460.332542) (xy 66.822766 -460.385792)
			(xy 66.803723 -460.436853) (xy 66.777607 -460.484683) (xy 66.744949 -460.52831) (xy 66.706415 -460.566845)
			(xy 66.662789 -460.599503) (xy 66.614959 -460.62562) (xy 66.563899 -460.644664) (xy 66.510648 -460.656247)
			(xy 66.456291 -460.660134) (xy 66.401934 -460.656245) (xy 66.348684 -460.644659) (xy 66.297625 -460.625613)
			(xy 66.249796 -460.599493) (xy 66.227706 -460.583534) (xy 66.208694 -460.569938) (xy 66.166811 -460.549206)
			(xy 66.121843 -460.53648) (xy 66.075306 -460.53219) (xy 66.028769 -460.53648) (xy 65.983801 -460.549206)
			(xy 65.941918 -460.569938) (xy 65.922906 -460.583534) (xy 65.900793 -460.599459) (xy 65.852969 -460.625578)
			(xy 65.801914 -460.644624) (xy 65.748668 -460.656209) (xy 65.694316 -460.660099) (xy 65.639963 -460.656214)
			(xy 65.586716 -460.644633) (xy 65.53566 -460.625591) (xy 65.487833 -460.599477) (xy 65.44421 -460.566821)
			(xy 65.405679 -460.52829) (xy 65.373024 -460.484667) (xy 65.346909 -460.43684) (xy 65.327868 -460.385784)
			(xy 65.316286 -460.332537) (xy 65.312401 -460.278184) (xy 64.762854 -460.278184) (xy 64.758968 -460.332546)
			(xy 64.747384 -460.385802) (xy 64.728339 -460.436866) (xy 64.70222 -460.4847) (xy 64.669559 -460.52833)
			(xy 64.63102 -460.566867) (xy 64.58739 -460.599527) (xy 64.539555 -460.625644) (xy 64.488489 -460.644688)
			(xy 64.435234 -460.65627) (xy 64.380872 -460.660154) (xy 64.32651 -460.656262) (xy 64.273256 -460.644672)
			(xy 64.222194 -460.625621) (xy 64.174363 -460.599496) (xy 64.152272 -460.583534) (xy 64.13326 -460.569938)
			(xy 64.091377 -460.549206) (xy 64.046409 -460.53648) (xy 63.999872 -460.53219) (xy 63.953335 -460.53648)
			(xy 63.908367 -460.549206) (xy 63.866484 -460.569938) (xy 63.847472 -460.583534) (xy 63.82536 -460.599457)
			(xy 63.777538 -460.625569) (xy 63.726486 -460.644611) (xy 63.673245 -460.656192) (xy 63.618897 -460.660079)
			(xy 63.564548 -460.656191) (xy 63.511307 -460.644609) (xy 63.460256 -460.625566) (xy 63.412434 -460.599453)
			(xy 63.368816 -460.566799) (xy 63.330289 -460.52827) (xy 63.297637 -460.48465) (xy 63.271526 -460.436827)
			(xy 63.252486 -460.385775) (xy 63.240906 -460.332533) (xy 63.237021 -460.278184) (xy 42.840605 -460.278184)
			(xy 44.607142 -462.044802) (xy 63.236997 -462.044802) (xy 63.240884 -461.990451) (xy 63.252467 -461.937206)
			(xy 63.271509 -461.886151) (xy 63.297624 -461.838326) (xy 63.330279 -461.794704) (xy 63.36881 -461.756174)
			(xy 63.412432 -461.72352) (xy 63.460258 -461.697406) (xy 63.511313 -461.678365) (xy 63.564558 -461.666783)
			(xy 63.61891 -461.662897) (xy 63.673261 -461.666786) (xy 63.726506 -461.67837) (xy 63.77756 -461.697414)
			(xy 63.825384 -461.72353) (xy 63.847472 -461.739488) (xy 63.866484 -461.753084) (xy 63.908367 -461.773816)
			(xy 63.953335 -461.786542) (xy 63.999872 -461.790832) (xy 64.046409 -461.786542) (xy 64.091377 -461.773816)
			(xy 64.13326 -461.753084) (xy 64.152272 -461.739488) (xy 64.174365 -461.723531) (xy 64.222192 -461.697406)
			(xy 64.27325 -461.678355) (xy 64.326501 -461.666764) (xy 64.380858 -461.66287) (xy 64.435217 -461.666752)
			(xy 64.48847 -461.678331) (xy 64.539533 -461.697372) (xy 64.587365 -461.723486) (xy 64.630995 -461.756142)
			(xy 64.669532 -461.794676) (xy 64.702193 -461.838302) (xy 64.728312 -461.886132) (xy 64.747358 -461.937192)
			(xy 64.758942 -461.990444) (xy 64.76283 -462.044802) (xy 65.312377 -462.044802) (xy 65.316264 -461.990446)
			(xy 65.327848 -461.937197) (xy 65.346893 -461.886138) (xy 65.373011 -461.838309) (xy 65.405669 -461.794684)
			(xy 65.444205 -461.756152) (xy 65.487831 -461.723496) (xy 65.535662 -461.697382) (xy 65.586722 -461.678341)
			(xy 65.639973 -461.66676) (xy 65.694329 -461.662877) (xy 65.748685 -461.666769) (xy 65.801934 -461.678357)
			(xy 65.852991 -461.697406) (xy 65.900817 -461.723528) (xy 65.922906 -461.739488) (xy 65.941918 -461.753084)
			(xy 65.983801 -461.773816) (xy 66.028769 -461.786542) (xy 66.075306 -461.790832) (xy 66.121843 -461.786542)
			(xy 66.166811 -461.773816) (xy 66.208694 -461.753084) (xy 66.227706 -461.739488) (xy 66.249798 -461.723534)
			(xy 66.297623 -461.697415) (xy 66.348678 -461.678368) (xy 66.401924 -461.666781) (xy 66.456278 -461.66289)
			(xy 66.510632 -461.666775) (xy 66.563879 -461.678355) (xy 66.614937 -461.697396) (xy 66.662765 -461.72351)
			(xy 66.706389 -461.756165) (xy 66.744922 -461.794696) (xy 66.777579 -461.838318) (xy 66.803696 -461.886145)
			(xy 66.822739 -461.937202) (xy 66.834322 -461.990449) (xy 66.83821 -462.044802) (xy 66.838151 -462.045625)
			(xy 67.536659 -462.045625) (xy 67.540544 -461.991267) (xy 67.552125 -461.938016) (xy 67.571166 -461.886954)
			(xy 67.597281 -461.839123) (xy 67.629938 -461.795495) (xy 67.668471 -461.756958) (xy 67.712096 -461.724298)
			(xy 67.759926 -461.698179) (xy 67.810986 -461.679133) (xy 67.864236 -461.667548) (xy 67.918594 -461.663659)
			(xy 67.972951 -461.667546) (xy 68.026202 -461.67913) (xy 68.077263 -461.698174) (xy 68.125093 -461.724291)
			(xy 68.147184 -461.74025) (xy 68.166196 -461.753846) (xy 68.208079 -461.774578) (xy 68.253047 -461.787304)
			(xy 68.299584 -461.791594) (xy 68.346121 -461.787304) (xy 68.391089 -461.774578) (xy 68.432972 -461.753846)
			(xy 68.451984 -461.74025) (xy 68.474112 -461.724345) (xy 68.521936 -461.698228) (xy 68.572991 -461.679182)
			(xy 68.626236 -461.667597) (xy 68.680588 -461.663708) (xy 68.73494 -461.667593) (xy 68.788187 -461.679175)
			(xy 68.839242 -461.698218) (xy 68.887068 -461.724332) (xy 68.93069 -461.756988) (xy 68.969221 -461.79552)
			(xy 69.001875 -461.839143) (xy 69.027988 -461.88697) (xy 69.047028 -461.938026) (xy 69.058608 -461.991273)
			(xy 69.062492 -462.045625) (xy 69.058601 -462.099977) (xy 69.047014 -462.153222) (xy 69.027967 -462.204276)
			(xy 69.001847 -462.252099) (xy 68.969188 -462.295718) (xy 68.930652 -462.334245) (xy 68.887026 -462.366895)
			(xy 68.839196 -462.393003) (xy 68.788138 -462.412039) (xy 68.734891 -462.423614) (xy 68.680538 -462.427492)
			(xy 68.626186 -462.423596) (xy 68.572942 -462.412004) (xy 68.52189 -462.392952) (xy 68.47407 -462.366827)
			(xy 68.451984 -462.350866) (xy 68.432972 -462.33727) (xy 68.391089 -462.316538) (xy 68.346121 -462.303812)
			(xy 68.299584 -462.299522) (xy 68.253047 -462.303812) (xy 68.208079 -462.316538) (xy 68.166196 -462.33727)
			(xy 68.147184 -462.350866) (xy 68.125136 -462.366881) (xy 68.077309 -462.393005) (xy 68.026251 -462.412056)
			(xy 67.973001 -462.423646) (xy 67.918644 -462.427541) (xy 67.864286 -462.423659) (xy 67.811034 -462.412081)
			(xy 67.759972 -462.393042) (xy 67.712139 -462.366929) (xy 67.668509 -462.334275) (xy 67.629971 -462.295743)
			(xy 67.597309 -462.25212) (xy 67.571187 -462.204291) (xy 67.552139 -462.153233) (xy 67.540551 -462.099982)
			(xy 67.536659 -462.045625) (xy 66.838151 -462.045625) (xy 66.834322 -462.099156) (xy 66.822738 -462.152403)
			(xy 66.803694 -462.203459) (xy 66.777577 -462.251286) (xy 66.744919 -462.294908) (xy 66.706386 -462.333438)
			(xy 66.662761 -462.366093) (xy 66.614933 -462.392206) (xy 66.563875 -462.411246) (xy 66.510627 -462.422826)
			(xy 66.456273 -462.42671) (xy 66.40192 -462.422818) (xy 66.348673 -462.411231) (xy 66.297618 -462.392183)
			(xy 66.249794 -462.366063) (xy 66.227706 -462.350104) (xy 66.208694 -462.336508) (xy 66.166811 -462.315776)
			(xy 66.121843 -462.30305) (xy 66.075306 -462.29876) (xy 66.028769 -462.30305) (xy 65.983801 -462.315776)
			(xy 65.941918 -462.336508) (xy 65.922906 -462.350104) (xy 65.900821 -462.36607) (xy 65.852995 -462.392192)
			(xy 65.801938 -462.411242) (xy 65.74869 -462.422831) (xy 65.694334 -462.426723) (xy 65.639977 -462.42284)
			(xy 65.586727 -462.411261) (xy 65.535666 -462.39222) (xy 65.487836 -462.366106) (xy 65.444208 -462.333451)
			(xy 65.405673 -462.294919) (xy 65.373013 -462.251295) (xy 65.346895 -462.203467) (xy 65.32785 -462.152408)
			(xy 65.316265 -462.099159) (xy 65.312377 -462.044802) (xy 64.76283 -462.044802) (xy 64.758942 -462.099161)
			(xy 64.747356 -462.152412) (xy 64.72831 -462.203473) (xy 64.70219 -462.251302) (xy 64.669529 -462.294928)
			(xy 64.630991 -462.333461) (xy 64.587361 -462.366116) (xy 64.539528 -462.39223) (xy 64.488465 -462.41127)
			(xy 64.435212 -462.422849) (xy 64.380854 -462.42673) (xy 64.326496 -462.422835) (xy 64.273246 -462.411244)
			(xy 64.222187 -462.392192) (xy 64.174361 -462.366066) (xy 64.152272 -462.350104) (xy 64.13326 -462.336508)
			(xy 64.091377 -462.315776) (xy 64.046409 -462.30305) (xy 63.999872 -462.29876) (xy 63.953335 -462.30305)
			(xy 63.908367 -462.315776) (xy 63.866484 -462.336508) (xy 63.847472 -462.350104) (xy 63.825388 -462.366067)
			(xy 63.777564 -462.392184) (xy 63.726511 -462.411228) (xy 63.673266 -462.422813) (xy 63.618915 -462.426703)
			(xy 63.564563 -462.422818) (xy 63.511317 -462.411237) (xy 63.460262 -462.392196) (xy 63.412436 -462.366083)
			(xy 63.368814 -462.333429) (xy 63.330282 -462.294899) (xy 63.297626 -462.251278) (xy 63.271511 -462.203453)
			(xy 63.252468 -462.152399) (xy 63.240885 -462.099154) (xy 63.236997 -462.044802) (xy 44.607142 -462.044802)
			(xy 45.702503 -463.140213) (xy 47.82311 -463.140213) (xy 47.82311 -463.059103) (xy 47.83106 -462.978384)
			(xy 47.846883 -462.898833) (xy 47.870428 -462.821217) (xy 47.901467 -462.746281) (xy 47.939702 -462.674749)
			(xy 47.984764 -462.607309) (xy 48.036219 -462.54461) (xy 48.093572 -462.487257) (xy 48.156271 -462.435802)
			(xy 48.223711 -462.39074) (xy 48.295243 -462.352505) (xy 48.370179 -462.321466) (xy 48.447795 -462.297921)
			(xy 48.527346 -462.282098) (xy 48.608065 -462.274148) (xy 48.689175 -462.274148) (xy 48.769894 -462.282098)
			(xy 48.849445 -462.297921) (xy 48.927061 -462.321466) (xy 49.001997 -462.352505) (xy 49.073529 -462.39074)
			(xy 49.140969 -462.435802) (xy 49.203668 -462.487257) (xy 49.261021 -462.54461) (xy 49.312476 -462.607309)
			(xy 49.357538 -462.674749) (xy 49.395773 -462.746281) (xy 49.426812 -462.821217) (xy 49.450357 -462.898833)
			(xy 49.46618 -462.978384) (xy 49.47413 -463.059103) (xy 49.474628 -463.099658) (xy 49.47413 -463.140213)
			(xy 51.32323 -463.140213) (xy 51.32323 -463.059103) (xy 51.33118 -462.978384) (xy 51.347003 -462.898833)
			(xy 51.370548 -462.821217) (xy 51.401587 -462.746281) (xy 51.439822 -462.674749) (xy 51.484884 -462.607309)
			(xy 51.536339 -462.54461) (xy 51.593692 -462.487257) (xy 51.656391 -462.435802) (xy 51.723831 -462.39074)
			(xy 51.795363 -462.352505) (xy 51.870299 -462.321466) (xy 51.947915 -462.297921) (xy 52.027466 -462.282098)
			(xy 52.108185 -462.274148) (xy 52.189295 -462.274148) (xy 52.270014 -462.282098) (xy 52.349565 -462.297921)
			(xy 52.427181 -462.321466) (xy 52.502117 -462.352505) (xy 52.573649 -462.39074) (xy 52.641089 -462.435802)
			(xy 52.703788 -462.487257) (xy 52.761141 -462.54461) (xy 52.812596 -462.607309) (xy 52.857658 -462.674749)
			(xy 52.895893 -462.746281) (xy 52.926932 -462.821217) (xy 52.950477 -462.898833) (xy 52.9663 -462.978384)
			(xy 52.97425 -463.059103) (xy 52.974748 -463.099658) (xy 52.97425 -463.140213) (xy 52.9663 -463.220932)
			(xy 52.950477 -463.300483) (xy 52.926932 -463.378099) (xy 52.895893 -463.453035) (xy 52.857658 -463.524567)
			(xy 52.812596 -463.592007) (xy 52.761141 -463.654706) (xy 52.703788 -463.712059) (xy 52.641089 -463.763514)
			(xy 52.573649 -463.808576) (xy 52.502117 -463.846811) (xy 52.47128 -463.859584) (xy 63.191333 -463.859584)
			(xy 63.195222 -463.805239) (xy 63.206806 -463.752001) (xy 63.225848 -463.700952) (xy 63.251962 -463.653134)
			(xy 63.284615 -463.609518) (xy 63.323142 -463.570994) (xy 63.366761 -463.538344) (xy 63.414581 -463.512235)
			(xy 63.465631 -463.493197) (xy 63.518871 -463.481618) (xy 63.573216 -463.477733) (xy 63.627562 -463.481622)
			(xy 63.6808 -463.493206) (xy 63.731848 -463.512248) (xy 63.779667 -463.538362) (xy 63.801752 -463.554318)
			(xy 63.820764 -463.567914) (xy 63.862647 -463.588646) (xy 63.907615 -463.601372) (xy 63.954152 -463.605662)
			(xy 64.000689 -463.601372) (xy 64.045657 -463.588646) (xy 64.08754 -463.567914) (xy 64.106552 -463.554318)
			(xy 64.128617 -463.538319) (xy 64.176447 -463.512187) (xy 64.22751 -463.493129) (xy 64.280765 -463.481533)
			(xy 64.335129 -463.477634) (xy 64.389494 -463.481512) (xy 64.442754 -463.493089) (xy 64.493824 -463.512128)
			(xy 64.541664 -463.538242) (xy 64.5853 -463.570899) (xy 64.623844 -463.609435) (xy 64.656511 -463.653063)
			(xy 64.682636 -463.700898) (xy 64.701687 -463.751963) (xy 64.713275 -463.80522) (xy 64.717166 -463.859584)
			(xy 65.266713 -463.859584) (xy 65.270602 -463.805235) (xy 65.282187 -463.751991) (xy 65.301232 -463.700939)
			(xy 65.327348 -463.653117) (xy 65.360005 -463.609498) (xy 65.398537 -463.570971) (xy 65.44216 -463.538321)
			(xy 65.489986 -463.512211) (xy 65.541041 -463.493173) (xy 65.594285 -463.481595) (xy 65.648636 -463.477713)
			(xy 65.702985 -463.481605) (xy 65.756228 -463.493193) (xy 65.807279 -463.51224) (xy 65.8551 -463.538359)
			(xy 65.877186 -463.554318) (xy 65.896198 -463.567914) (xy 65.938081 -463.588646) (xy 65.983049 -463.601372)
			(xy 66.029586 -463.605662) (xy 66.076123 -463.601372) (xy 66.121091 -463.588646) (xy 66.162974 -463.567914)
			(xy 66.181986 -463.554318) (xy 66.20405 -463.538322) (xy 66.251878 -463.512195) (xy 66.302938 -463.493142)
			(xy 66.356189 -463.48155) (xy 66.410548 -463.477654) (xy 66.464909 -463.481535) (xy 66.518163 -463.493113)
			(xy 66.569228 -463.512153) (xy 66.617063 -463.538266) (xy 66.660695 -463.570922) (xy 66.699234 -463.609455)
			(xy 66.731898 -463.65308) (xy 66.758019 -463.700911) (xy 66.777068 -463.751972) (xy 66.788655 -463.805225)
			(xy 66.792546 -463.859584) (xy 66.792487 -463.860407) (xy 67.445475 -463.860407) (xy 67.449362 -463.806051)
			(xy 67.460945 -463.752802) (xy 67.479989 -463.701743) (xy 67.506106 -463.653914) (xy 67.538764 -463.610289)
			(xy 67.577298 -463.571756) (xy 67.620924 -463.539099) (xy 67.668754 -463.512984) (xy 67.719814 -463.493942)
			(xy 67.773063 -463.48236) (xy 67.82742 -463.478475) (xy 67.881776 -463.482366) (xy 67.935024 -463.493953)
			(xy 67.986082 -463.513) (xy 68.033909 -463.53912) (xy 68.055998 -463.55508) (xy 68.07501 -463.568676)
			(xy 68.116893 -463.589408) (xy 68.161861 -463.602134) (xy 68.208398 -463.606424) (xy 68.254935 -463.602134)
			(xy 68.299903 -463.589408) (xy 68.341786 -463.568676) (xy 68.360798 -463.55508) (xy 68.382897 -463.539136)
			(xy 68.430722 -463.513017) (xy 68.481778 -463.49397) (xy 68.535024 -463.482383) (xy 68.589378 -463.478492)
			(xy 68.643732 -463.482376) (xy 68.69698 -463.493957) (xy 68.748038 -463.512998) (xy 68.795866 -463.539112)
			(xy 68.83949 -463.571767) (xy 68.878023 -463.610299) (xy 68.91068 -463.653922) (xy 68.936796 -463.701749)
			(xy 68.955839 -463.752806) (xy 68.967421 -463.806053) (xy 68.971308 -463.860407) (xy 68.967419 -463.914761)
			(xy 68.955835 -463.968008) (xy 68.93679 -464.019064) (xy 68.910672 -464.06689) (xy 68.878013 -464.110512)
			(xy 68.839479 -464.149042) (xy 68.795853 -464.181695) (xy 68.748025 -464.207808) (xy 68.696966 -464.226847)
			(xy 68.643718 -464.238426) (xy 68.589364 -464.242308) (xy 68.53501 -464.238415) (xy 68.481764 -464.226826)
			(xy 68.430709 -464.207777) (xy 68.382885 -464.181656) (xy 68.360798 -464.165696) (xy 68.341786 -464.1521)
			(xy 68.299903 -464.131368) (xy 68.254935 -464.118642) (xy 68.208398 -464.114352) (xy 68.161861 -464.118642)
			(xy 68.116893 -464.131368) (xy 68.07501 -464.1521) (xy 68.055998 -464.165696) (xy 68.033921 -464.181672)
			(xy 67.986095 -464.207794) (xy 67.935038 -464.226843) (xy 67.88179 -464.238432) (xy 67.827434 -464.242325)
			(xy 67.773078 -464.238442) (xy 67.719827 -464.226863) (xy 67.668767 -464.207822) (xy 67.620936 -464.181709)
			(xy 67.577309 -464.149054) (xy 67.538773 -464.110522) (xy 67.506113 -464.066898) (xy 67.479995 -464.019071)
			(xy 67.460949 -463.968012) (xy 67.449364 -463.914763) (xy 67.445475 -463.860407) (xy 66.792487 -463.860407)
			(xy 66.78866 -463.913944) (xy 66.777077 -463.967198) (xy 66.758032 -464.018261) (xy 66.731915 -464.066093)
			(xy 66.699255 -464.109722) (xy 66.660718 -464.148258) (xy 66.617089 -464.180917) (xy 66.569256 -464.207034)
			(xy 66.518193 -464.226078) (xy 66.46494 -464.237661) (xy 66.41058 -464.241546) (xy 66.35622 -464.237655)
			(xy 66.302968 -464.226067) (xy 66.251907 -464.207017) (xy 66.204076 -464.180895) (xy 66.181986 -464.164934)
			(xy 66.162974 -464.151338) (xy 66.121091 -464.130606) (xy 66.076123 -464.11788) (xy 66.029586 -464.11359)
			(xy 65.983049 -464.11788) (xy 65.938081 -464.130606) (xy 65.896198 -464.151338) (xy 65.877186 -464.164934)
			(xy 65.855074 -464.180858) (xy 65.807251 -464.206973) (xy 65.756198 -464.226016) (xy 65.702954 -464.237599)
			(xy 65.648604 -464.241487) (xy 65.594254 -464.237601) (xy 65.541011 -464.226018) (xy 65.489957 -464.206977)
			(xy 65.442134 -464.180863) (xy 65.398513 -464.148208) (xy 65.359985 -464.109678) (xy 65.327331 -464.066057)
			(xy 65.301219 -464.018233) (xy 65.282178 -463.967179) (xy 65.270598 -463.913935) (xy 65.266713 -463.859584)
			(xy 64.717166 -463.859584) (xy 64.71328 -463.913949) (xy 64.701695 -463.967207) (xy 64.682649 -464.018274)
			(xy 64.656528 -464.06611) (xy 64.623864 -464.109742) (xy 64.585324 -464.14828) (xy 64.54169 -464.180941)
			(xy 64.493852 -464.207059) (xy 64.442784 -464.226102) (xy 64.389525 -464.237683) (xy 64.33516 -464.241566)
			(xy 64.280796 -464.237672) (xy 64.22754 -464.22608) (xy 64.176476 -464.207026) (xy 64.128643 -464.180898)
			(xy 64.106552 -464.164934) (xy 64.08754 -464.151338) (xy 64.045657 -464.130606) (xy 64.000689 -464.11788)
			(xy 63.954152 -464.11359) (xy 63.907615 -464.11788) (xy 63.862647 -464.130606) (xy 63.820764 -464.151338)
			(xy 63.801752 -464.164934) (xy 63.779641 -464.180855) (xy 63.73182 -464.206964) (xy 63.68077 -464.226003)
			(xy 63.627531 -464.237582) (xy 63.573185 -464.241467) (xy 63.51884 -464.237578) (xy 63.465601 -464.225994)
			(xy 63.414553 -464.206952) (xy 63.366734 -464.180839) (xy 63.323119 -464.148186) (xy 63.284594 -464.109658)
			(xy 63.251945 -464.06604) (xy 63.225835 -464.018219) (xy 63.206797 -463.96717) (xy 63.195218 -463.91393)
			(xy 63.191333 -463.859584) (xy 52.47128 -463.859584) (xy 52.427181 -463.87785) (xy 52.349565 -463.901395)
			(xy 52.270014 -463.917218) (xy 52.189295 -463.925168) (xy 52.108185 -463.925168) (xy 52.027466 -463.917218)
			(xy 51.947915 -463.901395) (xy 51.870299 -463.87785) (xy 51.795363 -463.846811) (xy 51.723831 -463.808576)
			(xy 51.656391 -463.763514) (xy 51.593692 -463.712059) (xy 51.536339 -463.654706) (xy 51.484884 -463.592007)
			(xy 51.439822 -463.524567) (xy 51.401587 -463.453035) (xy 51.370548 -463.378099) (xy 51.347003 -463.300483)
			(xy 51.33118 -463.220932) (xy 51.32323 -463.140213) (xy 49.47413 -463.140213) (xy 49.46618 -463.220932)
			(xy 49.450357 -463.300483) (xy 49.426812 -463.378099) (xy 49.395773 -463.453035) (xy 49.357538 -463.524567)
			(xy 49.312476 -463.592007) (xy 49.261021 -463.654706) (xy 49.203668 -463.712059) (xy 49.140969 -463.763514)
			(xy 49.073529 -463.808576) (xy 49.001997 -463.846811) (xy 48.927061 -463.87785) (xy 48.849445 -463.901395)
			(xy 48.769894 -463.917218) (xy 48.689175 -463.925168) (xy 48.608065 -463.925168) (xy 48.527346 -463.917218)
			(xy 48.447795 -463.901395) (xy 48.370179 -463.87785) (xy 48.295243 -463.846811) (xy 48.223711 -463.808576)
			(xy 48.156271 -463.763514) (xy 48.093572 -463.712059) (xy 48.036219 -463.654706) (xy 47.984764 -463.592007)
			(xy 47.939702 -463.524567) (xy 47.901467 -463.453035) (xy 47.870428 -463.378099) (xy 47.846883 -463.300483)
			(xy 47.83106 -463.220932) (xy 47.82311 -463.140213) (xy 45.702503 -463.140213) (xy 47.072093 -464.509866)
			(xy 86.877404 -464.509866) (xy 86.881424 -464.319215) (xy 86.893478 -464.128902) (xy 86.913544 -463.939267)
			(xy 86.941587 -463.750646) (xy 86.977556 -463.563376) (xy 87.021388 -463.377788) (xy 87.073005 -463.194213)
			(xy 87.132315 -463.012977) (xy 87.199213 -462.834402) (xy 87.273579 -462.658807) (xy 87.355281 -462.486502)
			(xy 87.444175 -462.317795) (xy 87.540101 -462.152985) (xy 87.64289 -461.992366) (xy 87.752359 -461.836223)
			(xy 87.868313 -461.684834) (xy 87.990547 -461.538467) (xy 88.118841 -461.397383) (xy 88.252969 -461.261834)
			(xy 88.392693 -461.132059) (xy 88.537763 -461.008289) (xy 88.687921 -460.890746) (xy 88.842902 -460.779637)
			(xy 89.002429 -460.67516) (xy 89.166218 -460.577501) (xy 89.333978 -460.486834) (xy 89.505412 -460.40332)
			(xy 89.680214 -460.327107) (xy 89.858073 -460.258331) (xy 90.038674 -460.197113) (xy 90.221694 -460.143564)
			(xy 90.40681 -460.097778) (xy 90.593691 -460.059836) (xy 90.782006 -460.029807) (xy 90.971419 -460.007742)
			(xy 91.161593 -459.993683) (xy 91.352192 -459.987653) (xy 91.542875 -459.989663) (xy 91.733304 -459.99971)
			(xy 91.92314 -460.017776) (xy 92.112046 -460.043829) (xy 92.299685 -460.077822) (xy 92.485725 -460.119695)
			(xy 92.669834 -460.169374) (xy 92.851685 -460.22677) (xy 93.030955 -460.291781) (xy 93.207325 -460.364292)
			(xy 93.380481 -460.444173) (xy 93.550116 -460.531283) (xy 93.715928 -460.625467) (xy 93.877622 -460.726558)
			(xy 94.03491 -460.834374) (xy 94.187513 -460.948726) (xy 94.335161 -461.069409) (xy 94.477589 -461.19621)
			(xy 94.614545 -461.328901) (xy 94.745786 -461.467249) (xy 94.871078 -461.611006) (xy 94.990198 -461.759917)
			(xy 95.102934 -461.913718) (xy 95.209087 -462.072134) (xy 95.308467 -462.234885) (xy 95.400897 -462.40168)
			(xy 95.486214 -462.572224) (xy 95.564266 -462.746212) (xy 95.634913 -462.923337) (xy 95.698031 -463.103282)
			(xy 95.753507 -463.285728) (xy 95.801242 -463.470351) (xy 95.841152 -463.656821) (xy 95.873165 -463.844809)
			(xy 95.897225 -464.033979) (xy 95.913288 -464.223995) (xy 95.921327 -464.414519) (xy 95.92183 -464.509866)
			(xy 95.921327 -464.605213) (xy 95.913288 -464.795737) (xy 95.897225 -464.985753) (xy 95.873165 -465.174923)
			(xy 95.841152 -465.362911) (xy 95.801242 -465.549381) (xy 95.753507 -465.734004) (xy 95.698031 -465.91645)
			(xy 95.634913 -466.096395) (xy 95.564266 -466.27352) (xy 95.486214 -466.447508) (xy 95.400897 -466.618052)
			(xy 95.308467 -466.784847) (xy 95.209087 -466.947598) (xy 95.102934 -467.106014) (xy 94.990198 -467.259815)
			(xy 94.871078 -467.408726) (xy 94.745786 -467.552483) (xy 94.614545 -467.690831) (xy 94.477589 -467.823522)
			(xy 94.335161 -467.950323) (xy 94.187513 -468.071006) (xy 94.03491 -468.185358) (xy 93.877622 -468.293174)
			(xy 93.715928 -468.394265) (xy 93.550116 -468.488449) (xy 93.380481 -468.575559) (xy 93.207325 -468.65544)
			(xy 93.030955 -468.727951) (xy 92.851685 -468.792962) (xy 92.669834 -468.850358) (xy 92.485725 -468.900037)
			(xy 92.299685 -468.94191) (xy 92.112046 -468.975903) (xy 91.92314 -469.001956) (xy 91.733304 -469.020022)
			(xy 91.542875 -469.030069) (xy 91.352192 -469.032079) (xy 91.161593 -469.026049) (xy 90.971419 -469.01199)
			(xy 90.782006 -468.989925) (xy 90.593691 -468.959896) (xy 90.40681 -468.921954) (xy 90.221694 -468.876168)
			(xy 90.038674 -468.822619) (xy 89.858073 -468.761401) (xy 89.680214 -468.692625) (xy 89.505412 -468.616412)
			(xy 89.333978 -468.532898) (xy 89.166218 -468.442231) (xy 89.002429 -468.344572) (xy 88.842902 -468.240095)
			(xy 88.687921 -468.128986) (xy 88.537763 -468.011443) (xy 88.392693 -467.887673) (xy 88.252969 -467.757898)
			(xy 88.118841 -467.622349) (xy 87.990547 -467.481265) (xy 87.868313 -467.334898) (xy 87.752359 -467.183509)
			(xy 87.64289 -467.027366) (xy 87.540101 -466.866747) (xy 87.444175 -466.701937) (xy 87.355281 -466.53323)
			(xy 87.273579 -466.360925) (xy 87.199213 -466.18533) (xy 87.132315 -466.006755) (xy 87.073005 -465.825519)
			(xy 87.021388 -465.641944) (xy 86.977556 -465.456356) (xy 86.941587 -465.269086) (xy 86.913544 -465.080465)
			(xy 86.893478 -464.89083) (xy 86.881424 -464.700517) (xy 86.877404 -464.509866) (xy 47.072093 -464.509866)
			(xy 48.178482 -465.616306) (xy 63.191304 -465.616306) (xy 63.195191 -465.561956) (xy 63.206772 -465.508713)
			(xy 63.225813 -465.45766) (xy 63.251926 -465.409836) (xy 63.284579 -465.366216) (xy 63.323107 -465.327686)
			(xy 63.366727 -465.295032) (xy 63.41455 -465.268918) (xy 63.465602 -465.249875) (xy 63.518845 -465.238292)
			(xy 63.573195 -465.234404) (xy 63.627544 -465.238291) (xy 63.680788 -465.249872) (xy 63.731841 -465.268913)
			(xy 63.779664 -465.295026) (xy 63.801752 -465.310982) (xy 63.820764 -465.324578) (xy 63.862647 -465.34531)
			(xy 63.907615 -465.358036) (xy 63.954152 -465.362326) (xy 64.000689 -465.358036) (xy 64.045657 -465.34531)
			(xy 64.08754 -465.324578) (xy 64.106552 -465.310982) (xy 64.128651 -465.295031) (xy 64.176479 -465.268904)
			(xy 64.227539 -465.249851) (xy 64.280791 -465.238258) (xy 64.335151 -465.234363) (xy 64.389511 -465.238244)
			(xy 64.442766 -465.249823) (xy 64.493831 -465.268863) (xy 64.541666 -465.294978) (xy 64.585297 -465.327635)
			(xy 64.623836 -465.36617) (xy 64.656498 -465.409797) (xy 64.682619 -465.457629) (xy 64.701665 -465.508692)
			(xy 64.71325 -465.561946) (xy 64.717137 -465.616306) (xy 65.266684 -465.616306) (xy 65.270571 -465.561952)
			(xy 65.282153 -465.508704) (xy 65.301197 -465.457647) (xy 65.327312 -465.409819) (xy 65.359969 -465.366196)
			(xy 65.398502 -465.327664) (xy 65.442126 -465.295008) (xy 65.489954 -465.268893) (xy 65.541012 -465.249851)
			(xy 65.59426 -465.238269) (xy 65.648614 -465.234384) (xy 65.702968 -465.238273) (xy 65.756215 -465.249859)
			(xy 65.807271 -465.268905) (xy 65.855097 -465.295023) (xy 65.877186 -465.310982) (xy 65.896198 -465.324578)
			(xy 65.938081 -465.34531) (xy 65.983049 -465.358036) (xy 66.029586 -465.362326) (xy 66.076123 -465.358036)
			(xy 66.121091 -465.34531) (xy 66.162974 -465.324578) (xy 66.181986 -465.310982) (xy 66.204084 -465.295034)
			(xy 66.25191 -465.268913) (xy 66.302967 -465.249864) (xy 66.356215 -465.238275) (xy 66.41057 -465.234383)
			(xy 66.464926 -465.238267) (xy 66.518176 -465.249847) (xy 66.569236 -465.268888) (xy 66.617066 -465.295002)
			(xy 66.660692 -465.327658) (xy 66.699227 -465.36619) (xy 66.731885 -465.409814) (xy 66.758002 -465.457643)
			(xy 66.777046 -465.508701) (xy 66.78863 -465.56195) (xy 66.792517 -465.616306) (xy 66.792458 -465.617129)
			(xy 67.445446 -465.617129) (xy 67.44933 -465.562768) (xy 67.460911 -465.509514) (xy 67.479954 -465.45845)
			(xy 67.50607 -465.410616) (xy 67.538728 -465.366986) (xy 67.577263 -465.328448) (xy 67.62089 -465.295786)
			(xy 67.668722 -465.269666) (xy 67.719785 -465.25062) (xy 67.773038 -465.239035) (xy 67.827398 -465.235146)
			(xy 67.881758 -465.239034) (xy 67.935012 -465.250619) (xy 67.986074 -465.269665) (xy 68.033906 -465.295784)
			(xy 68.055998 -465.311744) (xy 68.07501 -465.32534) (xy 68.116893 -465.346072) (xy 68.161861 -465.358798)
			(xy 68.208398 -465.363088) (xy 68.254935 -465.358798) (xy 68.299903 -465.346072) (xy 68.341786 -465.32534)
			(xy 68.360798 -465.311744) (xy 68.382931 -465.295849) (xy 68.430754 -465.269734) (xy 68.481807 -465.250691)
			(xy 68.53505 -465.239108) (xy 68.5894 -465.235221) (xy 68.643749 -465.239108) (xy 68.696993 -465.250691)
			(xy 68.748045 -465.269734) (xy 68.795868 -465.295848) (xy 68.839487 -465.328503) (xy 68.878015 -465.367034)
			(xy 68.910667 -465.410656) (xy 68.936778 -465.458481) (xy 68.955817 -465.509535) (xy 68.967396 -465.562779)
			(xy 68.971279 -465.617129) (xy 68.967388 -465.671478) (xy 68.955801 -465.724721) (xy 68.936754 -465.775772)
			(xy 68.910636 -465.823593) (xy 68.877978 -465.86721) (xy 68.839444 -465.905734) (xy 68.79582 -465.938383)
			(xy 68.747993 -465.96449) (xy 68.696937 -465.983525) (xy 68.643692 -465.9951) (xy 68.589342 -465.998979)
			(xy 68.534993 -465.995084) (xy 68.481751 -465.983493) (xy 68.430702 -465.964442) (xy 68.382883 -465.93832)
			(xy 68.360798 -465.92236) (xy 68.341786 -465.908764) (xy 68.299903 -465.888032) (xy 68.254935 -465.875306)
			(xy 68.208398 -465.871016) (xy 68.161861 -465.875306) (xy 68.116893 -465.888032) (xy 68.07501 -465.908764)
			(xy 68.055998 -465.92236) (xy 68.033955 -465.938385) (xy 67.986127 -465.964511) (xy 67.935067 -465.983565)
			(xy 67.881815 -465.995158) (xy 67.827456 -465.999054) (xy 67.773095 -465.995174) (xy 67.71984 -465.983596)
			(xy 67.668775 -465.964557) (xy 67.620939 -465.938445) (xy 67.577306 -465.90579) (xy 67.538765 -465.867258)
			(xy 67.506101 -465.823632) (xy 67.479978 -465.775802) (xy 67.460928 -465.724741) (xy 67.449338 -465.671489)
			(xy 67.445446 -465.617129) (xy 66.792458 -465.617129) (xy 66.788628 -465.670662) (xy 66.777043 -465.72391)
			(xy 66.757997 -465.774968) (xy 66.731879 -465.822796) (xy 66.699219 -465.866419) (xy 66.660683 -465.90495)
			(xy 66.617056 -465.937605) (xy 66.569225 -465.963717) (xy 66.518164 -465.982757) (xy 66.464914 -465.994335)
			(xy 66.410558 -465.998217) (xy 66.356203 -465.994323) (xy 66.302955 -465.982733) (xy 66.251899 -465.963682)
			(xy 66.204074 -465.937559) (xy 66.181986 -465.921598) (xy 66.162974 -465.908002) (xy 66.121091 -465.88727)
			(xy 66.076123 -465.874544) (xy 66.029586 -465.870254) (xy 65.983049 -465.874544) (xy 65.938081 -465.88727)
			(xy 65.896198 -465.908002) (xy 65.877186 -465.921598) (xy 65.855108 -465.93757) (xy 65.807282 -465.96369)
			(xy 65.756227 -465.982737) (xy 65.70298 -465.994325) (xy 65.648626 -465.998216) (xy 65.594272 -465.994332)
			(xy 65.541023 -465.982752) (xy 65.489965 -465.963712) (xy 65.442136 -465.937598) (xy 65.398511 -465.904944)
			(xy 65.359977 -465.866413) (xy 65.327319 -465.822791) (xy 65.301202 -465.774964) (xy 65.282157 -465.723907)
			(xy 65.270572 -465.67066) (xy 65.266684 -465.616306) (xy 64.717137 -465.616306) (xy 64.713248 -465.670666)
			(xy 64.701662 -465.72392) (xy 64.682614 -465.774982) (xy 64.656492 -465.822813) (xy 64.623829 -465.866439)
			(xy 64.585288 -465.904973) (xy 64.541656 -465.937628) (xy 64.49382 -465.963742) (xy 64.442755 -465.982781)
			(xy 64.3895 -465.994358) (xy 64.335139 -465.998237) (xy 64.280779 -465.99434) (xy 64.227527 -465.982746)
			(xy 64.176468 -465.963691) (xy 64.128641 -465.937562) (xy 64.106552 -465.921598) (xy 64.08754 -465.908002)
			(xy 64.045657 -465.88727) (xy 64.000689 -465.874544) (xy 63.954152 -465.870254) (xy 63.907615 -465.874544)
			(xy 63.862647 -465.88727) (xy 63.820764 -465.908002) (xy 63.801752 -465.921598) (xy 63.779674 -465.937567)
			(xy 63.731852 -465.963682) (xy 63.680799 -465.982724) (xy 63.627556 -465.994308) (xy 63.573207 -465.998196)
			(xy 63.518857 -465.99431) (xy 63.465614 -465.982728) (xy 63.414561 -465.963687) (xy 63.366737 -465.937575)
			(xy 63.323116 -465.904922) (xy 63.284587 -465.866393) (xy 63.251932 -465.822774) (xy 63.225818 -465.774951)
			(xy 63.206775 -465.723898) (xy 63.195192 -465.670655) (xy 63.191304 -465.616306) (xy 48.178482 -465.616306)
			(xy 48.183292 -465.621116) (xy 48.19542 -465.632491) (xy 48.224221 -465.649085) (xy 48.256334 -465.657666)
			(xy 48.272954 -465.6582) (xy 59.412886 -465.6582) (xy 61.13768 -467.382924) (xy 63.19128 -467.382924)
			(xy 63.195164 -467.328571) (xy 63.206744 -467.275324) (xy 63.225784 -467.224266) (xy 63.251896 -467.176439)
			(xy 63.284549 -467.132814) (xy 63.323078 -467.09428) (xy 63.366699 -467.061621) (xy 63.414523 -467.035503)
			(xy 63.465578 -467.016457) (xy 63.518824 -467.004871) (xy 63.573177 -467.00098) (xy 63.62753 -467.004864)
			(xy 63.680777 -467.016444) (xy 63.731834 -467.035484) (xy 63.779662 -467.061596) (xy 63.801752 -467.077552)
			(xy 63.820764 -467.091148) (xy 63.862647 -467.11188) (xy 63.907615 -467.124606) (xy 63.954152 -467.128896)
			(xy 64.000689 -467.124606) (xy 64.045657 -467.11188) (xy 64.08754 -467.091148) (xy 64.106552 -467.077552)
			(xy 64.128679 -467.061642) (xy 64.176505 -467.035519) (xy 64.227563 -467.016469) (xy 64.280812 -467.004879)
			(xy 64.335169 -467.000987) (xy 64.389526 -467.00487) (xy 64.442777 -467.016451) (xy 64.493838 -467.035493)
			(xy 64.541668 -467.061608) (xy 64.585295 -467.094265) (xy 64.62383 -467.132799) (xy 64.656488 -467.176425)
			(xy 64.682604 -467.224256) (xy 64.701647 -467.275316) (xy 64.713229 -467.328567) (xy 64.717113 -467.382924)
			(xy 65.26666 -467.382924) (xy 65.270544 -467.328566) (xy 65.282125 -467.275315) (xy 65.301167 -467.224253)
			(xy 65.327282 -467.176422) (xy 65.359939 -467.132794) (xy 65.398473 -467.094257) (xy 65.442098 -467.061598)
			(xy 65.489928 -467.035479) (xy 65.540988 -467.016433) (xy 65.594239 -467.004848) (xy 65.648596 -467.00096)
			(xy 65.702954 -467.004847) (xy 65.756205 -467.016431) (xy 65.807265 -467.035476) (xy 65.855095 -467.061593)
			(xy 65.877186 -467.077552) (xy 65.896198 -467.091148) (xy 65.938081 -467.11188) (xy 65.983049 -467.124606)
			(xy 66.029586 -467.128896) (xy 66.076123 -467.124606) (xy 66.121091 -467.11188) (xy 66.162974 -467.091148)
			(xy 66.181986 -467.077552) (xy 66.204112 -467.061645) (xy 66.251936 -467.035527) (xy 66.302991 -467.016482)
			(xy 66.356236 -467.004896) (xy 66.410588 -467.001007) (xy 66.46494 -467.004893) (xy 66.518186 -467.016475)
			(xy 66.569242 -467.035517) (xy 66.617068 -467.061632) (xy 66.66069 -467.094287) (xy 66.69922 -467.132819)
			(xy 66.731875 -467.176442) (xy 66.757988 -467.224269) (xy 66.777028 -467.275325) (xy 66.788609 -467.328571)
			(xy 66.792493 -467.382924) (xy 66.792446 -467.383587) (xy 67.445502 -467.383587) (xy 67.449392 -467.329235)
			(xy 67.460977 -467.27599) (xy 67.480022 -467.224935) (xy 67.50614 -467.177111) (xy 67.538798 -467.133491)
			(xy 67.577331 -467.094963) (xy 67.620956 -467.062311) (xy 67.668784 -467.0362) (xy 67.719841 -467.017162)
			(xy 67.773088 -467.005584) (xy 67.82744 -467.001702) (xy 67.881792 -467.005596) (xy 67.935036 -467.017185)
			(xy 67.986089 -467.036233) (xy 68.033911 -467.062354) (xy 68.055998 -467.078314) (xy 68.07501 -467.09191)
			(xy 68.116893 -467.112642) (xy 68.161861 -467.125368) (xy 68.208398 -467.129658) (xy 68.254935 -467.125368)
			(xy 68.299903 -467.112642) (xy 68.341786 -467.09191) (xy 68.360798 -467.078314) (xy 68.382866 -467.062324)
			(xy 68.430693 -467.0362) (xy 68.481751 -467.017149) (xy 68.535 -467.005559) (xy 68.589358 -467.001665)
			(xy 68.643716 -467.005547) (xy 68.696968 -467.017125) (xy 68.74803 -467.036165) (xy 68.795863 -467.062278)
			(xy 68.839492 -467.094933) (xy 68.87803 -467.133466) (xy 68.910692 -467.17709) (xy 68.936812 -467.224919)
			(xy 68.955859 -467.275979) (xy 68.967446 -467.329229) (xy 68.971335 -467.383587) (xy 68.967449 -467.437945)
			(xy 68.955866 -467.491196) (xy 68.936823 -467.542257) (xy 68.910706 -467.590088) (xy 68.878047 -467.633714)
			(xy 68.839512 -467.672249) (xy 68.795885 -467.704907) (xy 68.748054 -467.731024) (xy 68.696993 -467.750067)
			(xy 68.643742 -467.76165) (xy 68.589384 -467.765535) (xy 68.535026 -467.761645) (xy 68.481776 -467.750058)
			(xy 68.430717 -467.731011) (xy 68.382888 -467.70489) (xy 68.360798 -467.68893) (xy 68.341786 -467.675334)
			(xy 68.299903 -467.654602) (xy 68.254935 -467.641876) (xy 68.208398 -467.637586) (xy 68.161861 -467.641876)
			(xy 68.116893 -467.654602) (xy 68.07501 -467.675334) (xy 68.055998 -467.68893) (xy 68.033889 -467.70486)
			(xy 67.986065 -467.730978) (xy 67.935011 -467.750023) (xy 67.881766 -467.761608) (xy 67.827414 -467.765498)
			(xy 67.773061 -467.761612) (xy 67.719815 -467.750031) (xy 67.66876 -467.730989) (xy 67.620934 -467.704875)
			(xy 67.577311 -467.67222) (xy 67.53878 -467.633689) (xy 67.506125 -467.590067) (xy 67.480011 -467.542241)
			(xy 67.460969 -467.491185) (xy 67.449388 -467.437939) (xy 67.445502 -467.383587) (xy 66.792446 -467.383587)
			(xy 66.788602 -467.437276) (xy 66.777015 -467.490521) (xy 66.757968 -467.541575) (xy 66.731849 -467.589398)
			(xy 66.699189 -467.633017) (xy 66.660654 -467.671544) (xy 66.617027 -467.704194) (xy 66.569198 -467.730303)
			(xy 66.51814 -467.749339) (xy 66.464893 -467.760914) (xy 66.41054 -467.764793) (xy 66.356188 -467.760897)
			(xy 66.302944 -467.749305) (xy 66.251892 -467.730253) (xy 66.204072 -467.704129) (xy 66.181986 -467.688168)
			(xy 66.162974 -467.674572) (xy 66.121091 -467.65384) (xy 66.076123 -467.641114) (xy 66.029586 -467.636824)
			(xy 65.983049 -467.641114) (xy 65.938081 -467.65384) (xy 65.896198 -467.674572) (xy 65.877186 -467.688168)
			(xy 65.855136 -467.704181) (xy 65.807309 -467.730304) (xy 65.756251 -467.749355) (xy 65.703001 -467.760946)
			(xy 65.648644 -467.76484) (xy 65.594286 -467.760959) (xy 65.541034 -467.74938) (xy 65.489971 -467.730341)
			(xy 65.442139 -467.704228) (xy 65.398509 -467.671574) (xy 65.359971 -467.633043) (xy 65.327308 -467.589419)
			(xy 65.301187 -467.54159) (xy 65.282139 -467.490532) (xy 65.270551 -467.437281) (xy 65.26666 -467.382924)
			(xy 64.717113 -467.382924) (xy 64.713222 -467.437281) (xy 64.701634 -467.49053) (xy 64.682584 -467.541588)
			(xy 64.656462 -467.589415) (xy 64.623799 -467.633037) (xy 64.585259 -467.671566) (xy 64.541628 -467.704218)
			(xy 64.493794 -467.730327) (xy 64.442731 -467.749363) (xy 64.389478 -467.760937) (xy 64.335121 -467.764813)
			(xy 64.280765 -467.760914) (xy 64.227517 -467.749318) (xy 64.176462 -467.730261) (xy 64.128638 -467.704132)
			(xy 64.106552 -467.688168) (xy 64.08754 -467.674572) (xy 64.045657 -467.65384) (xy 64.000689 -467.641114)
			(xy 63.954152 -467.636824) (xy 63.907615 -467.641114) (xy 63.862647 -467.65384) (xy 63.820764 -467.674572)
			(xy 63.801752 -467.688168) (xy 63.779702 -467.704178) (xy 63.731878 -467.730296) (xy 63.680823 -467.749342)
			(xy 63.627577 -467.760929) (xy 63.573225 -467.76482) (xy 63.518872 -467.760936) (xy 63.465624 -467.749356)
			(xy 63.414567 -467.730317) (xy 63.366739 -467.704205) (xy 63.323114 -467.671552) (xy 63.28458 -467.633023)
			(xy 63.251922 -467.589402) (xy 63.225804 -467.541577) (xy 63.206757 -467.490522) (xy 63.195171 -467.437277)
			(xy 63.19128 -467.382924) (xy 61.13768 -467.382924) (xy 65.678304 -471.923364) (xy 70.676008 -471.923364)
			(xy 70.83933 -471.760042) (xy 70.862063 -471.73804) (xy 70.912255 -471.699527) (xy 70.967044 -471.667894)
			(xy 71.025494 -471.643683) (xy 71.086603 -471.627309) (xy 71.149327 -471.619051) (xy 71.212593 -471.619051)
			(xy 71.275317 -471.627309) (xy 71.336426 -471.643683) (xy 71.394876 -471.667894) (xy 71.449665 -471.699527)
			(xy 71.499857 -471.73804) (xy 71.544592 -471.782775) (xy 71.583105 -471.832967) (xy 71.614738 -471.887756)
			(xy 71.638949 -471.946206) (xy 71.655323 -472.007315) (xy 71.663581 -472.070039) (xy 71.663581 -472.133305)
			(xy 71.655323 -472.196029) (xy 71.638949 -472.257138) (xy 71.614738 -472.315588) (xy 71.583105 -472.370377)
			(xy 71.544592 -472.420569) (xy 71.52259 -472.443302) (xy 71.171562 -472.794076) (xy 71.160107 -472.806214)
			(xy 71.143394 -472.83509) (xy 71.134741 -472.867312) (xy 71.134739 -472.900676) (xy 71.14339 -472.932899)
			(xy 71.1601 -472.961777) (xy 71.171562 -472.973908) (xy 71.455534 -473.25788) (xy 71.477536 -473.280613)
			(xy 71.516049 -473.330805) (xy 71.547682 -473.385594) (xy 71.571893 -473.444044) (xy 71.588267 -473.505153)
			(xy 71.596525 -473.567877) (xy 71.596525 -473.59951) (xy 73.941938 -473.59951) (xy 73.946009 -473.543888)
			(xy 73.958135 -473.489451) (xy 73.978058 -473.43736) (xy 74.005354 -473.388725) (xy 74.03944 -473.344582)
			(xy 74.079589 -473.305873) (xy 74.124947 -473.273422) (xy 74.174547 -473.247921) (xy 74.227331 -473.229914)
			(xy 74.282174 -473.219784) (xy 74.337908 -473.217747) (xy 74.393345 -473.223847) (xy 74.447302 -473.237953)
			(xy 74.498631 -473.259765) (xy 74.546237 -473.288819) (xy 74.589105 -473.324494) (xy 74.626322 -473.366031)
			(xy 74.657095 -473.412544) (xy 74.680767 -473.463041) (xy 74.696835 -473.516448) (xy 74.704955 -473.571624)
			(xy 74.705464 -473.59951) (xy 74.704955 -473.627396) (xy 74.696835 -473.682572) (xy 74.680767 -473.735979)
			(xy 74.657095 -473.786476) (xy 74.626322 -473.832989) (xy 74.589105 -473.874526) (xy 74.546237 -473.910201)
			(xy 74.498631 -473.939255) (xy 74.447302 -473.961067) (xy 74.393345 -473.975173) (xy 74.337908 -473.981273)
			(xy 74.282174 -473.979236) (xy 74.227331 -473.969106) (xy 74.174547 -473.951099) (xy 74.124947 -473.925598)
			(xy 74.079589 -473.893147) (xy 74.03944 -473.854438) (xy 74.005354 -473.810295) (xy 73.978058 -473.76166)
			(xy 73.958135 -473.709569) (xy 73.946009 -473.655132) (xy 73.941938 -473.59951) (xy 71.596525 -473.59951)
			(xy 71.596525 -473.631143) (xy 71.588267 -473.693867) (xy 71.571893 -473.754976) (xy 71.547682 -473.813426)
			(xy 71.516049 -473.868215) (xy 71.477536 -473.918407) (xy 71.432801 -473.963142) (xy 71.382609 -474.001655)
			(xy 71.32782 -474.033288) (xy 71.26937 -474.057499) (xy 71.208261 -474.073873) (xy 71.145537 -474.082131)
			(xy 71.082271 -474.082131) (xy 71.019547 -474.073873) (xy 70.958438 -474.057499) (xy 70.899988 -474.033288)
			(xy 70.845199 -474.001655) (xy 70.795007 -473.963142) (xy 70.772274 -473.94114) (xy 70.58787 -473.756736)
			(xy 64.91859 -473.756736) (xy 58.690256 -467.528148) (xy 58.6781 -467.516805) (xy 58.649313 -467.500199)
			(xy 58.617211 -467.491605) (xy 58.600594 -467.491064) (xy 46.970442 -467.491064) (xy 43.53433 -464.054952)
			(xy 41.74109 -464.054952) (xy 41.717553 -464.055448) (xy 41.671277 -464.064082) (xy 41.627383 -464.08109)
			(xy 41.587373 -464.105891) (xy 41.552613 -464.137636) (xy 41.524294 -464.175239) (xy 41.503384 -464.217415)
			(xy 41.490599 -464.262719) (xy 41.486375 -464.309603) (xy 41.488106 -464.333082) (xy 41.490312 -464.361839)
			(xy 41.487068 -464.41942) (xy 41.475191 -464.475856) (xy 41.454953 -464.529861) (xy 41.426816 -464.580204)
			(xy 41.39142 -464.625736) (xy 41.349572 -464.665421) (xy 41.302227 -464.698354) (xy 41.250464 -464.723783)
			(xy 41.195462 -464.741129) (xy 41.16705 -464.746086) (xy 41.145863 -464.749832) (xy 41.105075 -464.763516)
			(xy 41.067176 -464.783878) (xy 41.033251 -464.810335) (xy 41.004268 -464.84213) (xy 40.981058 -464.878355)
			(xy 40.964284 -464.917972) (xy 40.954425 -464.95985) (xy 40.951763 -465.002789) (xy 40.956376 -465.045564)
			(xy 40.961818 -465.06638) (xy 40.968935 -465.093419) (xy 40.976179 -465.148858) (xy 40.975253 -465.204761)
			(xy 40.966177 -465.259929) (xy 40.949144 -465.313182) (xy 40.924521 -465.363378) (xy 40.892835 -465.409442)
			(xy 40.854763 -465.450388) (xy 40.811123 -465.485337) (xy 40.762848 -465.513542) (xy 40.710974 -465.534398)
			(xy 40.65661 -465.547458) (xy 40.600923 -465.552443) (xy 40.545104 -465.549246) (xy 40.49035 -465.537935)
			(xy 40.437833 -465.518752) (xy 40.38868 -465.492109) (xy 40.343941 -465.458577) (xy 40.304577 -465.418873)
			(xy 40.27143 -465.373848) (xy 40.245211 -465.324467) (xy 40.226481 -465.271787) (xy 40.215641 -465.216938)
			(xy 40.212923 -465.161094) (xy 40.218387 -465.105451) (xy 40.231914 -465.051202) (xy 40.253215 -464.999508)
			(xy 40.281834 -464.951478) (xy 40.317158 -464.90814) (xy 40.358429 -464.870422) (xy 40.404764 -464.839133)
			(xy 40.45517 -464.814942) (xy 40.508567 -464.798368) (xy 40.536114 -464.793584) (xy 40.557292 -464.789799)
			(xy 40.598071 -464.77611) (xy 40.635962 -464.755747) (xy 40.669881 -464.729293) (xy 40.69886 -464.697503)
			(xy 40.722069 -464.661285) (xy 40.738845 -464.621676) (xy 40.74871 -464.579807) (xy 40.75138 -464.536874)
			(xy 40.746781 -464.494105) (xy 40.741346 -464.47329) (xy 40.735251 -464.45048) (xy 40.72809 -464.403812)
			(xy 40.726749 -464.356616) (xy 40.728646 -464.333082) (xy 40.730426 -464.309612) (xy 40.726155 -464.262741)
			(xy 40.713337 -464.217454) (xy 40.692409 -464.175297) (xy 40.664085 -464.137708) (xy 40.629332 -464.105969)
			(xy 40.589334 -464.081163) (xy 40.545456 -464.064136) (xy 40.499195 -464.055469) (xy 40.475662 -464.054952)
			(xy 40.40505 -464.054952) (xy 40.373438 -464.054436) (xy 40.310755 -464.046178) (xy 40.249687 -464.029809)
			(xy 40.191277 -464.005609) (xy 40.136526 -463.973993) (xy 40.086369 -463.935502) (xy 40.041665 -463.890793)
			(xy 40.003179 -463.840633) (xy 39.971569 -463.785878) (xy 39.947375 -463.727466) (xy 39.931013 -463.666395)
			(xy 39.922761 -463.603712) (xy 39.922761 -463.540488) (xy 39.931013 -463.477805) (xy 39.947375 -463.416734)
			(xy 39.971569 -463.358322) (xy 40.003179 -463.303567) (xy 40.041665 -463.253407) (xy 40.086369 -463.208698)
			(xy 40.136526 -463.170207) (xy 40.191277 -463.138591) (xy 40.249687 -463.114391) (xy 40.310755 -463.098022)
			(xy 40.373438 -463.089764) (xy 40.40505 -463.089244) (xy 43.671998 -463.089244) (xy 43.69505 -463.088746)
			(xy 43.740401 -463.080449) (xy 43.783512 -463.064109) (xy 43.822969 -463.040262) (xy 43.857478 -463.00969)
			(xy 43.885908 -462.973396) (xy 43.907326 -462.932569) (xy 43.921029 -462.88855) (xy 43.926569 -462.84278)
			(xy 43.923764 -462.796762) (xy 43.912705 -462.752004) (xy 43.893755 -462.709975) (xy 43.867536 -462.672053)
			(xy 43.851576 -462.655412) (xy 42.235882 -461.039972) (xy 36.606988 -461.039972) (xy 36.583472 -461.040522)
			(xy 36.537243 -461.049176) (xy 36.493395 -461.066187) (xy 36.453425 -461.090974) (xy 36.418697 -461.12269)
			(xy 36.390396 -461.160255) (xy 36.369489 -461.202384) (xy 36.356689 -461.247641) (xy 36.352432 -461.294479)
			(xy 36.356865 -461.341302) (xy 36.369836 -461.38651) (xy 36.379912 -461.407764) (xy 36.399016 -461.446878)
			(xy 36.430741 -461.527947) (xy 36.454837 -461.611601) (xy 36.471098 -461.697124) (xy 36.479384 -461.783784)
			(xy 36.479625 -461.870838) (xy 36.471819 -461.957543) (xy 36.456031 -462.043154) (xy 36.432399 -462.12694)
			(xy 36.401122 -462.208183) (xy 36.362471 -462.286187) (xy 36.316775 -462.360285) (xy 36.264426 -462.429842)
			(xy 36.205871 -462.494262) (xy 36.141613 -462.552995) (xy 36.072202 -462.605536) (xy 35.998231 -462.651437)
			(xy 35.920334 -462.690304) (xy 35.839178 -462.721805) (xy 35.755458 -462.74567) (xy 35.66989 -462.761694)
			(xy 35.583208 -462.76974) (xy 35.496152 -462.76974) (xy 35.40947 -462.761694) (xy 35.323902 -462.74567)
			(xy 35.240182 -462.721805) (xy 35.159026 -462.690304) (xy 35.081129 -462.651437) (xy 35.007158 -462.605536)
			(xy 34.937747 -462.552995) (xy 34.873489 -462.494262) (xy 34.814934 -462.429842) (xy 34.762585 -462.360285)
			(xy 34.716889 -462.286187) (xy 34.678238 -462.208183) (xy 34.646961 -462.12694) (xy 34.623329 -462.043154)
			(xy 34.607541 -461.957543) (xy 34.599735 -461.870838) (xy 34.599976 -461.783784) (xy 34.608262 -461.697124)
			(xy 34.624523 -461.611601) (xy 34.648619 -461.527947) (xy 34.680344 -461.446878) (xy 34.699448 -461.407764)
			(xy 34.709593 -461.386538) (xy 34.72257 -461.341319) (xy 34.727005 -461.294484) (xy 34.722748 -461.247633)
			(xy 34.709944 -461.202365) (xy 34.68903 -461.160226) (xy 34.660719 -461.122653) (xy 34.62598 -461.090931)
			(xy 34.585997 -461.066141) (xy 34.542136 -461.049131) (xy 34.495894 -461.040481) (xy 34.472372 -461.039972)
			(xy 31.526988 -461.039972) (xy 31.503472 -461.040522) (xy 31.457243 -461.049176) (xy 31.413395 -461.066187)
			(xy 31.373425 -461.090974) (xy 31.338697 -461.12269) (xy 31.310396 -461.160255) (xy 31.289489 -461.202384)
			(xy 31.276689 -461.247641) (xy 31.272432 -461.294479) (xy 31.276865 -461.341302) (xy 31.289836 -461.38651)
			(xy 31.299912 -461.407764) (xy 31.319016 -461.446878) (xy 31.350741 -461.527947) (xy 31.374837 -461.611601)
			(xy 31.391098 -461.697124) (xy 31.399384 -461.783784) (xy 31.399625 -461.870838) (xy 31.391819 -461.957543)
			(xy 31.376031 -462.043154) (xy 31.352399 -462.12694) (xy 31.321122 -462.208183) (xy 31.282471 -462.286187)
			(xy 31.236775 -462.360285) (xy 31.184426 -462.429842) (xy 31.125871 -462.494262) (xy 31.061613 -462.552995)
			(xy 30.992202 -462.605536) (xy 30.918231 -462.651437) (xy 30.840334 -462.690304) (xy 30.759178 -462.721805)
			(xy 30.675458 -462.74567) (xy 30.58989 -462.761694) (xy 30.503208 -462.76974) (xy 30.416152 -462.76974)
			(xy 30.32947 -462.761694) (xy 30.243902 -462.74567) (xy 30.160182 -462.721805) (xy 30.079026 -462.690304)
			(xy 30.001129 -462.651437) (xy 29.927158 -462.605536) (xy 29.857747 -462.552995) (xy 29.793489 -462.494262)
			(xy 29.734934 -462.429842) (xy 29.682585 -462.360285) (xy 29.636889 -462.286187) (xy 29.598238 -462.208183)
			(xy 29.566961 -462.12694) (xy 29.543329 -462.043154) (xy 29.527541 -461.957543) (xy 29.519735 -461.870838)
			(xy 29.519976 -461.783784) (xy 29.528262 -461.697124) (xy 29.544523 -461.611601) (xy 29.568619 -461.527947)
			(xy 29.600344 -461.446878) (xy 29.619448 -461.407764) (xy 29.629593 -461.386538) (xy 29.64257 -461.341319)
			(xy 29.647005 -461.294484) (xy 29.642748 -461.247633) (xy 29.629944 -461.202365) (xy 29.60903 -461.160226)
			(xy 29.580719 -461.122653) (xy 29.54598 -461.090931) (xy 29.505997 -461.066141) (xy 29.462136 -461.049131)
			(xy 29.415894 -461.040481) (xy 29.392372 -461.039972) (xy 28.328366 -461.039972) (xy 28.049474 -460.76108)
			(xy 27.640026 -460.76108) (xy 27.608391 -460.760643) (xy 27.545662 -460.752387) (xy 27.484547 -460.736014)
			(xy 27.426092 -460.711804) (xy 27.371297 -460.680171) (xy 27.321101 -460.641657) (xy 27.276361 -460.596919)
			(xy 27.237843 -460.546724) (xy 27.206207 -460.491931) (xy 27.181994 -460.433478) (xy 27.165618 -460.372364)
			(xy 27.157359 -460.309635) (xy 1.525016 -460.309635) (xy 1.525016 -461.740958) (xy 4.839198 -461.740958)
			(xy 4.839198 -461.647086) (xy 4.847159 -461.553552) (xy 4.863023 -461.46103) (xy 4.886677 -461.370187)
			(xy 4.917949 -461.281678) (xy 4.956615 -461.196139) (xy 5.002396 -461.114187) (xy 5.054962 -461.036413)
			(xy 5.113935 -460.963378) (xy 5.178888 -460.895606) (xy 5.249355 -460.833587) (xy 5.324828 -460.777768)
			(xy 5.404763 -460.72855) (xy 5.488584 -460.686288) (xy 5.575687 -460.651288) (xy 5.665444 -460.6238)
			(xy 5.757209 -460.604023) (xy 5.850321 -460.5921) (xy 5.944108 -460.588116) (xy 6.037895 -460.5921)
			(xy 6.131007 -460.604023) (xy 6.222772 -460.6238) (xy 6.312529 -460.651288) (xy 6.399632 -460.686288)
			(xy 6.483453 -460.72855) (xy 6.563388 -460.777768) (xy 6.638861 -460.833587) (xy 6.709328 -460.895606)
			(xy 6.774281 -460.963378) (xy 6.833254 -461.036413) (xy 6.88582 -461.114187) (xy 6.931601 -461.196139)
			(xy 6.970267 -461.281678) (xy 7.001539 -461.370187) (xy 7.025193 -461.46103) (xy 7.041057 -461.553552)
			(xy 7.049018 -461.647086) (xy 7.049516 -461.694022) (xy 7.049018 -461.740958) (xy 10.339314 -461.740958)
			(xy 10.339314 -461.647086) (xy 10.347275 -461.553552) (xy 10.363139 -461.46103) (xy 10.386793 -461.370187)
			(xy 10.418065 -461.281678) (xy 10.456731 -461.196139) (xy 10.502512 -461.114187) (xy 10.555078 -461.036413)
			(xy 10.614051 -460.963378) (xy 10.679004 -460.895606) (xy 10.749471 -460.833587) (xy 10.824944 -460.777768)
			(xy 10.904879 -460.72855) (xy 10.9887 -460.686288) (xy 11.075803 -460.651288) (xy 11.16556 -460.6238)
			(xy 11.257325 -460.604023) (xy 11.350437 -460.5921) (xy 11.444224 -460.588116) (xy 11.538011 -460.5921)
			(xy 11.631123 -460.604023) (xy 11.722888 -460.6238) (xy 11.812645 -460.651288) (xy 11.899748 -460.686288)
			(xy 11.983569 -460.72855) (xy 12.063504 -460.777768) (xy 12.138977 -460.833587) (xy 12.209444 -460.895606)
			(xy 12.274397 -460.963378) (xy 12.33337 -461.036413) (xy 12.385936 -461.114187) (xy 12.431717 -461.196139)
			(xy 12.470383 -461.281678) (xy 12.501655 -461.370187) (xy 12.525309 -461.46103) (xy 12.541173 -461.553552)
			(xy 12.549134 -461.647086) (xy 12.549632 -461.694022) (xy 12.549134 -461.740958) (xy 12.541173 -461.834492)
			(xy 12.525309 -461.927014) (xy 12.501655 -462.017857) (xy 12.470383 -462.106366) (xy 12.431717 -462.191905)
			(xy 12.385936 -462.273857) (xy 12.33337 -462.351631) (xy 12.274397 -462.424666) (xy 12.209444 -462.492438)
			(xy 12.138977 -462.554457) (xy 12.063504 -462.610276) (xy 11.983569 -462.659494) (xy 11.899748 -462.701756)
			(xy 11.812645 -462.736756) (xy 11.722888 -462.764244) (xy 11.631123 -462.784021) (xy 11.538011 -462.795944)
			(xy 11.444224 -462.799929) (xy 11.350437 -462.795944) (xy 11.257325 -462.784021) (xy 11.16556 -462.764244)
			(xy 11.075803 -462.736756) (xy 10.9887 -462.701756) (xy 10.904879 -462.659494) (xy 10.824944 -462.610276)
			(xy 10.749471 -462.554457) (xy 10.679004 -462.492438) (xy 10.614051 -462.424666) (xy 10.555078 -462.351631)
			(xy 10.502512 -462.273857) (xy 10.456731 -462.191905) (xy 10.418065 -462.106366) (xy 10.386793 -462.017857)
			(xy 10.363139 -461.927014) (xy 10.347275 -461.834492) (xy 10.339314 -461.740958) (xy 7.049018 -461.740958)
			(xy 7.041057 -461.834492) (xy 7.025193 -461.927014) (xy 7.001539 -462.017857) (xy 6.970267 -462.106366)
			(xy 6.931601 -462.191905) (xy 6.88582 -462.273857) (xy 6.833254 -462.351631) (xy 6.774281 -462.424666)
			(xy 6.709328 -462.492438) (xy 6.638861 -462.554457) (xy 6.563388 -462.610276) (xy 6.483453 -462.659494)
			(xy 6.399632 -462.701756) (xy 6.312529 -462.736756) (xy 6.222772 -462.764244) (xy 6.131007 -462.784021)
			(xy 6.037895 -462.795944) (xy 5.944108 -462.799929) (xy 5.850321 -462.795944) (xy 5.757209 -462.784021)
			(xy 5.665444 -462.764244) (xy 5.575687 -462.736756) (xy 5.488584 -462.701756) (xy 5.404763 -462.659494)
			(xy 5.324828 -462.610276) (xy 5.249355 -462.554457) (xy 5.178888 -462.492438) (xy 5.113935 -462.424666)
			(xy 5.054962 -462.351631) (xy 5.002396 -462.273857) (xy 4.956615 -462.191905) (xy 4.917949 -462.106366)
			(xy 4.886677 -462.017857) (xy 4.863023 -461.927014) (xy 4.847159 -461.834492) (xy 4.839198 -461.740958)
			(xy 1.525016 -461.740958) (xy 1.525016 -463.41538) (xy 27.258008 -463.41538) (xy 27.262079 -463.359758)
			(xy 27.274205 -463.305321) (xy 27.294128 -463.25323) (xy 27.321424 -463.204595) (xy 27.35551 -463.160452)
			(xy 27.395659 -463.121743) (xy 27.441017 -463.089292) (xy 27.490617 -463.063791) (xy 27.543401 -463.045784)
			(xy 27.598244 -463.035654) (xy 27.653978 -463.033617) (xy 27.709415 -463.039717) (xy 27.763372 -463.053823)
			(xy 27.814701 -463.075635) (xy 27.862307 -463.104689) (xy 27.905175 -463.140364) (xy 27.942392 -463.181901)
			(xy 27.973165 -463.228414) (xy 27.996837 -463.278911) (xy 28.012905 -463.332318) (xy 28.021025 -463.387494)
			(xy 28.021534 -463.41538) (xy 28.021025 -463.443266) (xy 28.012905 -463.498442) (xy 27.996837 -463.551849)
			(xy 27.973165 -463.602346) (xy 27.942392 -463.648859) (xy 27.905175 -463.690396) (xy 27.862307 -463.726071)
			(xy 27.814701 -463.755125) (xy 27.763372 -463.776937) (xy 27.709415 -463.791043) (xy 27.653978 -463.797143)
			(xy 27.598244 -463.795106) (xy 27.543401 -463.784976) (xy 27.490617 -463.766969) (xy 27.441017 -463.741468)
			(xy 27.395659 -463.709017) (xy 27.35551 -463.670308) (xy 27.321424 -463.626165) (xy 27.294128 -463.57753)
			(xy 27.274205 -463.525439) (xy 27.262079 -463.471002) (xy 27.258008 -463.41538) (xy 1.525016 -463.41538)
			(xy 1.525016 -464.413362) (xy 29.519874 -464.413362) (xy 29.519874 -464.326462) (xy 29.527892 -464.239933)
			(xy 29.54386 -464.154513) (xy 29.567641 -464.070931) (xy 29.599033 -463.989899) (xy 29.637767 -463.91211)
			(xy 29.683514 -463.838226) (xy 29.735883 -463.768879) (xy 29.794427 -463.704659) (xy 29.858647 -463.646115)
			(xy 29.927994 -463.593746) (xy 30.001878 -463.547999) (xy 30.079667 -463.509265) (xy 30.160699 -463.477873)
			(xy 30.244281 -463.454092) (xy 30.329701 -463.438124) (xy 30.41623 -463.430106) (xy 30.50313 -463.430106)
			(xy 30.589659 -463.438124) (xy 30.675079 -463.454092) (xy 30.758661 -463.477873) (xy 30.839693 -463.509265)
			(xy 30.917482 -463.547999) (xy 30.991366 -463.593746) (xy 31.060713 -463.646115) (xy 31.124933 -463.704659)
			(xy 31.183477 -463.768879) (xy 31.235846 -463.838226) (xy 31.281593 -463.91211) (xy 31.320327 -463.989899)
			(xy 31.351719 -464.070931) (xy 31.3755 -464.154513) (xy 31.391468 -464.239933) (xy 31.399486 -464.326462)
			(xy 31.399988 -464.369912) (xy 31.399486 -464.413362) (xy 34.599874 -464.413362) (xy 34.599874 -464.326462)
			(xy 34.607892 -464.239933) (xy 34.62386 -464.154513) (xy 34.647641 -464.070931) (xy 34.679033 -463.989899)
			(xy 34.717767 -463.91211) (xy 34.763514 -463.838226) (xy 34.815883 -463.768879) (xy 34.874427 -463.704659)
			(xy 34.938647 -463.646115) (xy 35.007994 -463.593746) (xy 35.081878 -463.547999) (xy 35.159667 -463.509265)
			(xy 35.240699 -463.477873) (xy 35.324281 -463.454092) (xy 35.409701 -463.438124) (xy 35.49623 -463.430106)
			(xy 35.58313 -463.430106) (xy 35.669659 -463.438124) (xy 35.755079 -463.454092) (xy 35.838661 -463.477873)
			(xy 35.919693 -463.509265) (xy 35.997482 -463.547999) (xy 36.071366 -463.593746) (xy 36.140713 -463.646115)
			(xy 36.204933 -463.704659) (xy 36.263477 -463.768879) (xy 36.315846 -463.838226) (xy 36.361593 -463.91211)
			(xy 36.400327 -463.989899) (xy 36.431719 -464.070931) (xy 36.4555 -464.154513) (xy 36.471468 -464.239933)
			(xy 36.479486 -464.326462) (xy 36.479988 -464.369912) (xy 36.479486 -464.413362) (xy 36.471468 -464.499891)
			(xy 36.4555 -464.585311) (xy 36.431719 -464.668893) (xy 36.400327 -464.749925) (xy 36.361593 -464.827714)
			(xy 36.315846 -464.901598) (xy 36.263477 -464.970945) (xy 36.204933 -465.035165) (xy 36.140713 -465.093709)
			(xy 36.071366 -465.146078) (xy 35.997482 -465.191825) (xy 35.919693 -465.230559) (xy 35.838661 -465.261951)
			(xy 35.755079 -465.285732) (xy 35.669659 -465.3017) (xy 35.58313 -465.309718) (xy 35.49623 -465.309718)
			(xy 35.409701 -465.3017) (xy 35.324281 -465.285732) (xy 35.240699 -465.261951) (xy 35.159667 -465.230559)
			(xy 35.081878 -465.191825) (xy 35.007994 -465.146078) (xy 34.938647 -465.093709) (xy 34.874427 -465.035165)
			(xy 34.815883 -464.970945) (xy 34.763514 -464.901598) (xy 34.717767 -464.827714) (xy 34.679033 -464.749925)
			(xy 34.647641 -464.668893) (xy 34.62386 -464.585311) (xy 34.607892 -464.499891) (xy 34.599874 -464.413362)
			(xy 31.399486 -464.413362) (xy 31.391468 -464.499891) (xy 31.3755 -464.585311) (xy 31.351719 -464.668893)
			(xy 31.320327 -464.749925) (xy 31.281593 -464.827714) (xy 31.235846 -464.901598) (xy 31.183477 -464.970945)
			(xy 31.124933 -465.035165) (xy 31.060713 -465.093709) (xy 30.991366 -465.146078) (xy 30.917482 -465.191825)
			(xy 30.839693 -465.230559) (xy 30.758661 -465.261951) (xy 30.675079 -465.285732) (xy 30.589659 -465.3017)
			(xy 30.50313 -465.309718) (xy 30.41623 -465.309718) (xy 30.329701 -465.3017) (xy 30.244281 -465.285732)
			(xy 30.160699 -465.261951) (xy 30.079667 -465.230559) (xy 30.001878 -465.191825) (xy 29.927994 -465.146078)
			(xy 29.858647 -465.093709) (xy 29.794427 -465.035165) (xy 29.735883 -464.970945) (xy 29.683514 -464.901598)
			(xy 29.637767 -464.827714) (xy 29.599033 -464.749925) (xy 29.567641 -464.668893) (xy 29.54386 -464.585311)
			(xy 29.527892 -464.499891) (xy 29.519874 -464.413362) (xy 1.525016 -464.413362) (xy 1.525016 -471.172032)
			(xy 6.671831 -471.172032) (xy 6.675786 -471.080195) (xy 6.687621 -470.989038) (xy 6.707248 -470.899235)
			(xy 6.734522 -470.811453) (xy 6.769242 -470.726339) (xy 6.81115 -470.644526) (xy 6.859936 -470.566618)
			(xy 6.915239 -470.493193) (xy 6.976649 -470.424793) (xy 7.043711 -470.361926) (xy 7.11593 -470.305056)
			(xy 7.19277 -470.254605) (xy 7.273663 -470.210946) (xy 7.358009 -470.174403) (xy 7.445185 -470.145246)
			(xy 7.534544 -470.123692) (xy 7.625425 -470.109898) (xy 7.717156 -470.103968) (xy 7.809057 -470.105946)
			(xy 7.900448 -470.115817) (xy 7.990652 -470.133507) (xy 8.079001 -470.158887) (xy 8.164841 -470.191767)
			(xy 8.247537 -470.231905) (xy 8.326477 -470.279004) (xy 8.401075 -470.332714) (xy 8.470781 -470.392638)
			(xy 8.535076 -470.458332) (xy 8.593487 -470.52931) (xy 8.645579 -470.605047) (xy 8.690968 -470.684982)
			(xy 8.729318 -470.768522) (xy 8.760343 -470.85505) (xy 8.783816 -470.943925) (xy 8.799562 -471.034489)
			(xy 8.807464 -471.126071) (xy 8.807958 -471.172032) (xy 8.807464 -471.217993) (xy 8.799562 -471.309575)
			(xy 8.783816 -471.400139) (xy 8.760343 -471.489014) (xy 8.729318 -471.575542) (xy 8.690968 -471.659082)
			(xy 8.645579 -471.739017) (xy 8.593487 -471.814754) (xy 8.535076 -471.885732) (xy 8.470781 -471.951426)
			(xy 8.401075 -472.01135) (xy 8.326477 -472.06506) (xy 8.247537 -472.112159) (xy 8.164841 -472.152297)
			(xy 8.079001 -472.185177) (xy 7.990652 -472.210557) (xy 7.900448 -472.228247) (xy 7.809057 -472.238118)
			(xy 7.717156 -472.240096) (xy 7.625425 -472.234166) (xy 7.534544 -472.220372) (xy 7.445185 -472.198818)
			(xy 7.358009 -472.169661) (xy 7.273663 -472.133118) (xy 7.19277 -472.089459) (xy 7.11593 -472.039008)
			(xy 7.043711 -471.982138) (xy 6.976649 -471.919271) (xy 6.915239 -471.850871) (xy 6.859936 -471.777446)
			(xy 6.81115 -471.699538) (xy 6.769242 -471.617725) (xy 6.734522 -471.532611) (xy 6.707248 -471.444829)
			(xy 6.687621 -471.355026) (xy 6.675786 -471.263869) (xy 6.671831 -471.172032) (xy 1.525016 -471.172032)
			(xy 1.525016 -473.69984) (xy 11.345672 -473.69984) (xy 11.346163 -473.596662) (xy 11.354255 -473.390463)
			(xy 11.370436 -473.184742) (xy 11.394682 -472.979814) (xy 11.426955 -472.775996) (xy 11.467204 -472.573603)
			(xy 11.515369 -472.372946) (xy 11.571375 -472.174334) (xy 11.635136 -471.978075) (xy 11.706552 -471.78447)
			(xy 11.785515 -471.593818) (xy 11.871902 -471.406413) (xy 11.96558 -471.222545) (xy 12.066404 -471.042496)
			(xy 12.17422 -470.866544) (xy 12.288861 -470.694961) (xy 12.410149 -470.528012) (xy 12.537899 -470.365952)
			(xy 12.671913 -470.209034) (xy 12.811985 -470.057498) (xy 12.957898 -469.911578) (xy 13.109427 -469.771499)
			(xy 13.266339 -469.637478) (xy 13.428392 -469.50972) (xy 13.595336 -469.388424) (xy 13.766914 -469.273775)
			(xy 13.94286 -469.165951) (xy 14.122904 -469.065117) (xy 14.306768 -468.971431) (xy 14.494169 -468.885035)
			(xy 14.684817 -468.806063) (xy 14.878418 -468.734637) (xy 15.074675 -468.670868) (xy 15.273284 -468.614853)
			(xy 15.473939 -468.566678) (xy 15.67633 -468.526419) (xy 15.880146 -468.494136) (xy 16.085073 -468.469881)
			(xy 16.290794 -468.45369) (xy 16.496992 -468.445588) (xy 16.60017 -468.445088) (xy 16.703348 -468.445592)
			(xy 16.909546 -468.453694) (xy 17.115267 -468.469885) (xy 17.320193 -468.49414) (xy 17.524009 -468.526422)
			(xy 17.726401 -468.566682) (xy 17.927055 -468.614856) (xy 18.125664 -468.670872) (xy 18.32192 -468.734641)
			(xy 18.515522 -468.806067) (xy 18.70617 -468.885039) (xy 18.89357 -468.971434) (xy 19.077434 -469.065121)
			(xy 19.257478 -469.165954) (xy 19.433424 -469.273778) (xy 19.605002 -469.388427) (xy 19.771945 -469.509723)
			(xy 19.933998 -469.637481) (xy 20.09091 -469.771502) (xy 20.24244 -469.911581) (xy 20.388352 -470.057501)
			(xy 20.528424 -470.209037) (xy 20.662438 -470.365955) (xy 20.790187 -470.528014) (xy 20.911476 -470.694964)
			(xy 21.026117 -470.866546) (xy 21.133932 -471.042498) (xy 21.234757 -471.222547) (xy 21.328435 -471.406415)
			(xy 21.414822 -471.593819) (xy 21.493784 -471.784471) (xy 21.565201 -471.978076) (xy 21.628961 -472.174335)
			(xy 21.684967 -472.372947) (xy 21.733132 -472.573604) (xy 21.773381 -472.775997) (xy 21.805654 -472.979815)
			(xy 21.8299 -473.184742) (xy 21.846081 -473.390464) (xy 21.854173 -473.596662) (xy 21.854668 -473.69984)
			(xy 21.854174 -473.801741) (xy 21.846271 -474.005391) (xy 21.830478 -474.20858) (xy 21.806818 -474.411005)
			(xy 21.775327 -474.61236) (xy 21.736052 -474.812342) (xy 21.689051 -475.010651) (xy 21.634397 -475.206989)
			(xy 21.572171 -475.401059) (xy 21.502466 -475.592571) (xy 21.425388 -475.781236) (xy 21.341053 -475.96677)
			(xy 21.249586 -476.148895) (xy 21.151127 -476.327336) (xy 21.045822 -476.501825) (xy 20.933831 -476.6721)
			(xy 20.815321 -476.837904) (xy 20.690471 -476.998988) (xy 20.55947 -477.15511) (xy 20.422513 -477.306034)
			(xy 20.279807 -477.451535) (xy 20.131566 -477.591393) (xy 19.978014 -477.725397) (xy 19.879652 -477.804734)
			(xy 74.887582 -477.804734) (xy 74.888066 -477.726859) (xy 74.895869 -477.571306) (xy 74.911442 -477.416337)
			(xy 74.934747 -477.262341) (xy 74.965724 -477.109703) (xy 75.004296 -476.958806) (xy 75.050368 -476.810026)
			(xy 75.103822 -476.663738) (xy 75.164527 -476.520305) (xy 75.232329 -476.380089) (xy 75.307059 -476.243438)
			(xy 75.38853 -476.110697) (xy 75.476538 -475.982196) (xy 75.570863 -475.858258) (xy 75.671268 -475.739192)
			(xy 75.777503 -475.625298) (xy 75.889301 -475.516859) (xy 75.947524 -475.46514) (xy 76.008014 -475.412661)
			(xy 76.133594 -475.313261) (xy 76.264126 -475.220458) (xy 76.399265 -475.134501) (xy 76.53865 -475.055617)
			(xy 76.681912 -474.984015) (xy 76.828672 -474.919886) (xy 76.978539 -474.863399) (xy 77.131117 -474.814705)
			(xy 77.285999 -474.773932) (xy 77.442776 -474.74119) (xy 77.60103 -474.716564) (xy 77.760343 -474.70012)
			(xy 77.920291 -474.691902) (xy 78.08045 -474.691931) (xy 78.240395 -474.700208) (xy 78.399702 -474.71671)
			(xy 78.557948 -474.741394) (xy 78.714712 -474.774195) (xy 78.86958 -474.815024) (xy 79.022139 -474.863774)
			(xy 79.171985 -474.920316) (xy 79.318722 -474.984499) (xy 79.461958 -475.056154) (xy 79.601314 -475.135089)
			(xy 79.736421 -475.221096) (xy 79.866919 -475.313946) (xy 79.992463 -475.413393) (xy 80.052926 -475.465902)
			(xy 80.111074 -475.517651) (xy 80.22278 -475.62608) (xy 80.328926 -475.739959) (xy 80.429246 -475.859002)
			(xy 80.523489 -475.982912) (xy 80.611419 -476.111379) (xy 80.692816 -476.244081) (xy 80.767477 -476.380687)
			(xy 80.835215 -476.520854) (xy 80.89586 -476.664233) (xy 80.949261 -476.810464) (xy 80.995285 -476.959183)
			(xy 81.033815 -477.110016) (xy 81.064757 -477.262588) (xy 81.088032 -477.416515) (xy 81.103582 -477.571413)
			(xy 81.111368 -477.726895) (xy 81.111852 -477.804734) (xy 81.111852 -478.795334) (xy 81.111371 -478.874704)
			(xy 81.103273 -479.033238) (xy 81.087104 -479.191153) (xy 81.062907 -479.348038) (xy 81.030744 -479.503486)
			(xy 80.9907 -479.657093) (xy 80.942878 -479.808459) (xy 80.887402 -479.95719) (xy 80.824417 -480.1029)
			(xy 80.754087 -480.24521) (xy 80.676594 -480.383751) (xy 80.59214 -480.518161) (xy 80.500944 -480.648091)
			(xy 80.403245 -480.773204) (xy 80.299294 -480.893175) (xy 80.189364 -481.00769) (xy 80.073739 -481.116454)
			(xy 80.013556 -481.168202) (xy 79.953637 -481.218513) (xy 79.829479 -481.313747) (xy 79.700688 -481.402615)
			(xy 79.567588 -481.484891) (xy 79.430517 -481.560366) (xy 79.289823 -481.628849) (xy 79.145862 -481.690167)
			(xy 78.998998 -481.744164) (xy 78.849603 -481.790704) (xy 78.698055 -481.829669) (xy 78.54474 -481.86096)
			(xy 78.390044 -481.884498) (xy 78.23436 -481.900223) (xy 78.078082 -481.908096) (xy 77.921606 -481.908096)
			(xy 77.765328 -481.900223) (xy 77.609644 -481.884498) (xy 77.454948 -481.86096) (xy 77.301633 -481.829669)
			(xy 77.150085 -481.790704) (xy 77.00069 -481.744164) (xy 76.853826 -481.690167) (xy 76.709865 -481.628849)
			(xy 76.569171 -481.560366) (xy 76.4321 -481.484891) (xy 76.299 -481.402615) (xy 76.170209 -481.313747)
			(xy 76.046051 -481.218513) (xy 75.986132 -481.168202) (xy 75.925932 -481.116473) (xy 75.810304 -481.007712)
			(xy 75.700371 -480.893197) (xy 75.596418 -480.773228) (xy 75.498717 -480.648114) (xy 75.407521 -480.518183)
			(xy 75.323067 -480.383772) (xy 75.245575 -480.24523) (xy 75.175246 -480.102918) (xy 75.112264 -479.957206)
			(xy 75.056791 -479.808472) (xy 75.008974 -479.657104) (xy 74.968934 -479.503495) (xy 74.936778 -479.348044)
			(xy 74.912588 -479.191157) (xy 74.896428 -479.03324) (xy 74.888339 -478.874705) (xy 74.887836 -478.795334)
			(xy 74.887582 -477.804734) (xy 19.879652 -477.804734) (xy 19.819381 -477.853347) (xy 19.655906 -477.97505)
			(xy 19.487835 -478.090322) (xy 19.315421 -478.19899) (xy 19.138923 -478.300892) (xy 18.958606 -478.395872)
			(xy 18.774742 -478.48379) (xy 18.587607 -478.564512) (xy 18.397483 -478.637917) (xy 18.204656 -478.703895)
			(xy 18.009415 -478.762346) (xy 17.812055 -478.813183) (xy 17.612871 -478.856329) (xy 17.412165 -478.891719)
			(xy 17.210237 -478.9193) (xy 17.007392 -478.93903) (xy 16.803934 -478.95088) (xy 16.60017 -478.954832)
			(xy 16.396406 -478.95088) (xy 16.192948 -478.93903) (xy 15.990103 -478.9193) (xy 15.788175 -478.891719)
			(xy 15.587469 -478.856329) (xy 15.388285 -478.813183) (xy 15.190925 -478.762346) (xy 14.995684 -478.703895)
			(xy 14.802857 -478.637917) (xy 14.612733 -478.564512) (xy 14.425598 -478.48379) (xy 14.241734 -478.395872)
			(xy 14.061417 -478.300892) (xy 13.884919 -478.19899) (xy 13.712505 -478.090322) (xy 13.544434 -477.97505)
			(xy 13.380959 -477.853347) (xy 13.222326 -477.725397) (xy 13.068774 -477.591393) (xy 12.920533 -477.451535)
			(xy 12.777827 -477.306034) (xy 12.64087 -477.15511) (xy 12.509869 -476.998988) (xy 12.385019 -476.837904)
			(xy 12.266509 -476.6721) (xy 12.154518 -476.501825) (xy 12.049213 -476.327336) (xy 11.950754 -476.148895)
			(xy 11.859287 -475.96677) (xy 11.774952 -475.781236) (xy 11.697874 -475.592571) (xy 11.628169 -475.401059)
			(xy 11.565943 -475.206989) (xy 11.511289 -475.010651) (xy 11.464288 -474.812342) (xy 11.425013 -474.61236)
			(xy 11.393522 -474.411005) (xy 11.369862 -474.20858) (xy 11.354069 -474.005391) (xy 11.346166 -473.801741)
			(xy 11.345672 -473.69984) (xy 1.525016 -473.69984) (xy 1.525016 -477.214883) (xy 4.852911 -477.214883)
			(xy 4.852911 -477.129157) (xy 4.860821 -477.043797) (xy 4.876573 -476.95953) (xy 4.900033 -476.877077)
			(xy 4.931001 -476.79714) (xy 4.969212 -476.720401) (xy 5.014341 -476.647515) (xy 5.066002 -476.579104)
			(xy 5.123756 -476.515752) (xy 5.187108 -476.457998) (xy 5.255519 -476.406337) (xy 5.328405 -476.361208)
			(xy 5.405144 -476.322997) (xy 5.485081 -476.292029) (xy 5.567534 -476.268569) (xy 5.651801 -476.252817)
			(xy 5.737161 -476.244907) (xy 5.822887 -476.244907) (xy 5.908247 -476.252817) (xy 5.992514 -476.268569)
			(xy 6.074967 -476.292029) (xy 6.154904 -476.322997) (xy 6.231643 -476.361208) (xy 6.304529 -476.406337)
			(xy 6.37294 -476.457998) (xy 6.436292 -476.515752) (xy 6.494046 -476.579104) (xy 6.545707 -476.647515)
			(xy 6.590836 -476.720401) (xy 6.629047 -476.79714) (xy 6.660015 -476.877077) (xy 6.683475 -476.95953)
			(xy 6.699227 -477.043797) (xy 6.707137 -477.129157) (xy 6.707632 -477.17202) (xy 6.707137 -477.214883)
			(xy 6.699227 -477.300243) (xy 6.683475 -477.38451) (xy 6.660015 -477.466963) (xy 6.629047 -477.5469)
			(xy 6.590836 -477.623639) (xy 6.545707 -477.696525) (xy 6.494046 -477.764936) (xy 6.436292 -477.828288)
			(xy 6.37294 -477.886042) (xy 6.304529 -477.937703) (xy 6.231643 -477.982832) (xy 6.154904 -478.021043)
			(xy 6.074967 -478.052011) (xy 5.992514 -478.075471) (xy 5.908247 -478.091223) (xy 5.822887 -478.099133)
			(xy 5.737161 -478.099133) (xy 5.651801 -478.091223) (xy 5.567534 -478.075471) (xy 5.485081 -478.052011)
			(xy 5.405144 -478.021043) (xy 5.328405 -477.982832) (xy 5.255519 -477.937703) (xy 5.187108 -477.886042)
			(xy 5.123756 -477.828288) (xy 5.066002 -477.764936) (xy 5.014341 -477.696525) (xy 4.969212 -477.623639)
			(xy 4.931001 -477.5469) (xy 4.900033 -477.466963) (xy 4.876573 -477.38451) (xy 4.860821 -477.300243)
			(xy 4.852911 -477.214883) (xy 1.525016 -477.214883) (xy 1.525016 -480.172014) (xy 6.671831 -480.172014)
			(xy 6.675786 -480.080177) (xy 6.687621 -479.98902) (xy 6.707248 -479.899217) (xy 6.734522 -479.811435)
			(xy 6.769242 -479.726321) (xy 6.81115 -479.644508) (xy 6.859936 -479.5666) (xy 6.915239 -479.493175)
			(xy 6.976649 -479.424775) (xy 7.043711 -479.361908) (xy 7.11593 -479.305038) (xy 7.19277 -479.254587)
			(xy 7.273663 -479.210928) (xy 7.358009 -479.174385) (xy 7.445185 -479.145228) (xy 7.534544 -479.123674)
			(xy 7.625425 -479.10988) (xy 7.717156 -479.10395) (xy 7.809057 -479.105928) (xy 7.900448 -479.115799)
			(xy 7.990652 -479.133489) (xy 8.079001 -479.158869) (xy 8.164841 -479.191749) (xy 8.247537 -479.231887)
			(xy 8.326477 -479.278986) (xy 8.401075 -479.332696) (xy 8.470781 -479.39262) (xy 8.535076 -479.458314)
			(xy 8.593487 -479.529292) (xy 8.645579 -479.605029) (xy 8.690968 -479.684964) (xy 8.729318 -479.768504)
			(xy 8.760343 -479.855032) (xy 8.783816 -479.943907) (xy 8.799562 -480.034471) (xy 8.807464 -480.126053)
			(xy 8.807958 -480.172014) (xy 8.807464 -480.217975) (xy 8.799562 -480.309557) (xy 8.783816 -480.400121)
			(xy 8.760343 -480.488996) (xy 8.729318 -480.575524) (xy 8.690968 -480.659064) (xy 8.645579 -480.738999)
			(xy 8.593487 -480.814736) (xy 8.535076 -480.885714) (xy 8.470781 -480.951408) (xy 8.401075 -481.011332)
			(xy 8.326477 -481.065042) (xy 8.247537 -481.112141) (xy 8.164841 -481.152279) (xy 8.079001 -481.185159)
			(xy 7.990652 -481.210539) (xy 7.900448 -481.228229) (xy 7.809057 -481.2381) (xy 7.717156 -481.240078)
			(xy 7.625425 -481.234148) (xy 7.534544 -481.220354) (xy 7.445185 -481.1988) (xy 7.358009 -481.169643)
			(xy 7.273663 -481.1331) (xy 7.19277 -481.089441) (xy 7.11593 -481.03899) (xy 7.043711 -480.98212)
			(xy 6.976649 -480.919253) (xy 6.915239 -480.850853) (xy 6.859936 -480.777428) (xy 6.81115 -480.69952)
			(xy 6.769242 -480.617707) (xy 6.734522 -480.532593) (xy 6.707248 -480.444811) (xy 6.687621 -480.355008)
			(xy 6.675786 -480.263851) (xy 6.671831 -480.172014) (xy 1.525016 -480.172014) (xy 1.525016 -482.747235)
			(xy 47.507896 -482.747235) (xy 47.507896 -482.666125) (xy 47.515846 -482.585406) (xy 47.531669 -482.505855)
			(xy 47.555214 -482.428239) (xy 47.586253 -482.353303) (xy 47.624488 -482.281771) (xy 47.66955 -482.214331)
			(xy 47.721005 -482.151632) (xy 47.778358 -482.094279) (xy 47.841057 -482.042824) (xy 47.908497 -481.997762)
			(xy 47.980029 -481.959527) (xy 48.054965 -481.928488) (xy 48.132581 -481.904943) (xy 48.212132 -481.88912)
			(xy 48.292851 -481.88117) (xy 48.373961 -481.88117) (xy 48.45468 -481.88912) (xy 48.534231 -481.904943)
			(xy 48.611847 -481.928488) (xy 48.686783 -481.959527) (xy 48.758315 -481.997762) (xy 48.825755 -482.042824)
			(xy 48.888454 -482.094279) (xy 48.945807 -482.151632) (xy 48.997262 -482.214331) (xy 49.042324 -482.281771)
			(xy 49.080559 -482.353303) (xy 49.111598 -482.428239) (xy 49.135143 -482.505855) (xy 49.150966 -482.585406)
			(xy 49.158916 -482.666125) (xy 49.159414 -482.70668) (xy 49.158916 -482.747235) (xy 51.008016 -482.747235)
			(xy 51.008016 -482.666125) (xy 51.015966 -482.585406) (xy 51.031789 -482.505855) (xy 51.055334 -482.428239)
			(xy 51.086373 -482.353303) (xy 51.124608 -482.281771) (xy 51.16967 -482.214331) (xy 51.221125 -482.151632)
			(xy 51.278478 -482.094279) (xy 51.341177 -482.042824) (xy 51.408617 -481.997762) (xy 51.480149 -481.959527)
			(xy 51.555085 -481.928488) (xy 51.632701 -481.904943) (xy 51.712252 -481.88912) (xy 51.792971 -481.88117)
			(xy 51.874081 -481.88117) (xy 51.9548 -481.88912) (xy 52.034351 -481.904943) (xy 52.111967 -481.928488)
			(xy 52.186903 -481.959527) (xy 52.258435 -481.997762) (xy 52.325875 -482.042824) (xy 52.388574 -482.094279)
			(xy 52.445927 -482.151632) (xy 52.497382 -482.214331) (xy 52.542444 -482.281771) (xy 52.580679 -482.353303)
			(xy 52.611718 -482.428239) (xy 52.635263 -482.505855) (xy 52.651086 -482.585406) (xy 52.659036 -482.666125)
			(xy 52.659534 -482.70668) (xy 52.659036 -482.747235) (xy 52.651086 -482.827954) (xy 52.635263 -482.907505)
			(xy 52.611718 -482.985121) (xy 52.580679 -483.060057) (xy 52.542444 -483.131589) (xy 52.497382 -483.199029)
			(xy 52.445927 -483.261728) (xy 52.388574 -483.319081) (xy 52.325875 -483.370536) (xy 52.258435 -483.415598)
			(xy 52.186903 -483.453833) (xy 52.111967 -483.484872) (xy 52.034351 -483.508417) (xy 51.9548 -483.52424)
			(xy 51.874081 -483.53219) (xy 51.792971 -483.53219) (xy 51.712252 -483.52424) (xy 51.632701 -483.508417)
			(xy 51.555085 -483.484872) (xy 51.480149 -483.453833) (xy 51.408617 -483.415598) (xy 51.341177 -483.370536)
			(xy 51.278478 -483.319081) (xy 51.221125 -483.261728) (xy 51.16967 -483.199029) (xy 51.124608 -483.131589)
			(xy 51.086373 -483.060057) (xy 51.055334 -482.985121) (xy 51.031789 -482.907505) (xy 51.015966 -482.827954)
			(xy 51.008016 -482.747235) (xy 49.158916 -482.747235) (xy 49.150966 -482.827954) (xy 49.135143 -482.907505)
			(xy 49.111598 -482.985121) (xy 49.080559 -483.060057) (xy 49.042324 -483.131589) (xy 48.997262 -483.199029)
			(xy 48.945807 -483.261728) (xy 48.888454 -483.319081) (xy 48.825755 -483.370536) (xy 48.758315 -483.415598)
			(xy 48.686783 -483.453833) (xy 48.611847 -483.484872) (xy 48.534231 -483.508417) (xy 48.45468 -483.52424)
			(xy 48.373961 -483.53219) (xy 48.292851 -483.53219) (xy 48.212132 -483.52424) (xy 48.132581 -483.508417)
			(xy 48.054965 -483.484872) (xy 47.980029 -483.453833) (xy 47.908497 -483.415598) (xy 47.841057 -483.370536)
			(xy 47.778358 -483.319081) (xy 47.721005 -483.261728) (xy 47.66955 -483.199029) (xy 47.624488 -483.131589)
			(xy 47.586253 -483.060057) (xy 47.555214 -482.985121) (xy 47.531669 -482.907505) (xy 47.515846 -482.827954)
			(xy 47.507896 -482.747235) (xy 1.525016 -482.747235) (xy 1.525016 -485.198883) (xy 73.977596 -485.198883)
			(xy 73.981486 -485.144529) (xy 73.993073 -485.091283) (xy 74.012119 -485.040227) (xy 74.038239 -484.992402)
			(xy 74.070899 -484.948781) (xy 74.109434 -484.910252) (xy 74.153061 -484.8776) (xy 74.200891 -484.85149)
			(xy 74.251951 -484.832453) (xy 74.305199 -484.820876) (xy 74.359554 -484.816996) (xy 74.413907 -484.820892)
			(xy 74.467153 -484.832483) (xy 74.518207 -484.851535) (xy 74.566029 -484.877659) (xy 74.588116 -484.89362)
			(xy 74.607128 -484.907216) (xy 74.649011 -484.927948) (xy 74.693979 -484.940674) (xy 74.740516 -484.944964)
			(xy 74.787053 -484.940674) (xy 74.832021 -484.927948) (xy 74.873904 -484.907216) (xy 74.892916 -484.89362)
			(xy 74.914978 -484.877624) (xy 74.962804 -484.851502) (xy 75.01386 -484.832453) (xy 75.067109 -484.820863)
			(xy 75.121464 -484.816971) (xy 75.175821 -484.820853) (xy 75.229071 -484.832432) (xy 75.280131 -484.851472)
			(xy 75.327962 -484.877585) (xy 75.37159 -484.910239) (xy 75.410126 -484.94877) (xy 75.442787 -484.992393)
			(xy 75.468906 -485.040221) (xy 75.487953 -485.091279) (xy 75.499539 -485.144527) (xy 75.503429 -485.198883)
			(xy 75.906678 -485.198883) (xy 75.910569 -485.144525) (xy 75.922156 -485.091275) (xy 75.941205 -485.040215)
			(xy 75.967327 -484.992387) (xy 75.99999 -484.948763) (xy 76.03853 -484.910232) (xy 76.082161 -484.877579)
			(xy 76.129995 -484.851468) (xy 76.181059 -484.832432) (xy 76.234312 -484.820856) (xy 76.288671 -484.816978)
			(xy 76.343028 -484.820877) (xy 76.396277 -484.832472) (xy 76.447334 -484.851527) (xy 76.495159 -484.877656)
			(xy 76.517246 -484.89362) (xy 76.536258 -484.907216) (xy 76.578141 -484.927948) (xy 76.623109 -484.940674)
			(xy 76.669646 -484.944964) (xy 76.716183 -484.940674) (xy 76.761151 -484.927948) (xy 76.803034 -484.907216)
			(xy 76.822046 -484.89362) (xy 76.844179 -484.877627) (xy 76.892093 -484.851436) (xy 76.943253 -484.832348)
			(xy 76.996613 -484.820753) (xy 77.051081 -484.816889) (xy 77.105543 -484.820833) (xy 77.158885 -484.832507)
			(xy 77.210017 -484.85167) (xy 77.257893 -484.877931) (xy 77.301532 -484.910753) (xy 77.340043 -484.949464)
			(xy 77.356716 -484.97109) (xy 77.370495 -484.988853) (xy 77.40326 -485.019629) (xy 77.44093 -485.044158)
			(xy 77.482328 -485.061676) (xy 77.526163 -485.071635) (xy 77.571067 -485.073726) (xy 77.615637 -485.067881)
			(xy 77.658484 -485.054285) (xy 77.698269 -485.033361) (xy 77.733752 -485.005762) (xy 77.749146 -484.989378)
			(xy 77.76845 -484.968753) (xy 77.812039 -484.932823) (xy 77.86045 -484.903712) (xy 77.912624 -484.882057)
			(xy 77.96742 -484.868332) (xy 78.023641 -484.862836) (xy 78.080058 -484.86569) (xy 78.135438 -484.876831)
			(xy 78.188569 -484.896016) (xy 78.238291 -484.922825) (xy 78.26121 -484.93934) (xy 78.280222 -484.952936)
			(xy 78.322105 -484.973668) (xy 78.367073 -484.986394) (xy 78.41361 -484.990684) (xy 78.460147 -484.986394)
			(xy 78.505115 -484.973668) (xy 78.546998 -484.952936) (xy 78.56601 -484.93934) (xy 78.588053 -484.923316)
			(xy 78.635881 -484.897191) (xy 78.68694 -484.878138) (xy 78.74019 -484.866546) (xy 78.794549 -484.862651)
			(xy 78.848908 -484.866532) (xy 78.902162 -484.878109) (xy 78.953226 -484.897148) (xy 79.001061 -484.923261)
			(xy 79.044692 -484.955915) (xy 79.083232 -484.994447) (xy 79.115896 -485.038072) (xy 79.142018 -485.085901)
			(xy 79.161068 -485.136961) (xy 79.172657 -485.190212) (xy 79.176549 -485.244571) (xy 79.579798 -485.244571)
			(xy 79.58369 -485.190217) (xy 79.595278 -485.136969) (xy 79.614327 -485.085913) (xy 79.640449 -485.038088)
			(xy 79.673112 -484.994468) (xy 79.71165 -484.955941) (xy 79.75528 -484.92329) (xy 79.803112 -484.897182)
			(xy 79.854173 -484.878148) (xy 79.907424 -484.866574) (xy 79.96178 -484.862698) (xy 80.016134 -484.866597)
			(xy 80.069379 -484.878193) (xy 80.120433 -484.897248) (xy 80.168254 -484.923377) (xy 80.19034 -484.93934)
			(xy 80.209352 -484.952936) (xy 80.251235 -484.973668) (xy 80.296203 -484.986394) (xy 80.34274 -484.990684)
			(xy 80.389277 -484.986394) (xy 80.434245 -484.973668) (xy 80.476128 -484.952936) (xy 80.49514 -484.93934)
			(xy 80.517182 -484.923319) (xy 80.565008 -484.897198) (xy 80.616064 -484.87815) (xy 80.669311 -484.866561)
			(xy 80.723666 -484.862669) (xy 80.778021 -484.866552) (xy 80.831271 -484.878131) (xy 80.88233 -484.89717)
			(xy 80.93016 -484.923282) (xy 80.973788 -484.955935) (xy 81.012324 -484.994465) (xy 81.044984 -485.038087)
			(xy 81.071104 -485.085913) (xy 81.090152 -485.136969) (xy 81.101739 -485.190217) (xy 81.105631 -485.244571)
			(xy 81.101747 -485.298926) (xy 81.090168 -485.352176) (xy 81.071128 -485.403235) (xy 81.059113 -485.425242)
			(xy 87.09609 -485.425242) (xy 87.100161 -485.36962) (xy 87.112287 -485.315183) (xy 87.13221 -485.263092)
			(xy 87.159506 -485.214457) (xy 87.193592 -485.170314) (xy 87.233741 -485.131605) (xy 87.279099 -485.099154)
			(xy 87.328699 -485.073653) (xy 87.381483 -485.055646) (xy 87.436326 -485.045516) (xy 87.49206 -485.043479)
			(xy 87.547497 -485.049579) (xy 87.601454 -485.063685) (xy 87.652783 -485.085497) (xy 87.700389 -485.114551)
			(xy 87.743257 -485.150226) (xy 87.780474 -485.191763) (xy 87.811247 -485.238276) (xy 87.834919 -485.288773)
			(xy 87.850987 -485.34218) (xy 87.859107 -485.397356) (xy 87.859616 -485.425242) (xy 87.859107 -485.453128)
			(xy 87.850987 -485.508304) (xy 87.834919 -485.561711) (xy 87.811247 -485.612208) (xy 87.780474 -485.658721)
			(xy 87.743257 -485.700258) (xy 87.700389 -485.735933) (xy 87.652783 -485.764987) (xy 87.601454 -485.786799)
			(xy 87.547497 -485.800905) (xy 87.49206 -485.807005) (xy 87.436326 -485.804968) (xy 87.381483 -485.794838)
			(xy 87.328699 -485.776831) (xy 87.279099 -485.75133) (xy 87.233741 -485.718879) (xy 87.193592 -485.68017)
			(xy 87.159506 -485.636027) (xy 87.13221 -485.587392) (xy 87.112287 -485.535301) (xy 87.100161 -485.480864)
			(xy 87.09609 -485.425242) (xy 81.059113 -485.425242) (xy 81.045015 -485.451065) (xy 81.012361 -485.494692)
			(xy 80.973831 -485.533227) (xy 80.930209 -485.565887) (xy 80.882383 -485.592006) (xy 80.831326 -485.611053)
			(xy 80.778078 -485.62264) (xy 80.723724 -485.626531) (xy 80.669368 -485.622647) (xy 80.616119 -485.611066)
			(xy 80.56506 -485.592026) (xy 80.517231 -485.565912) (xy 80.49514 -485.549956) (xy 80.476128 -485.53636)
			(xy 80.434245 -485.515628) (xy 80.389277 -485.502902) (xy 80.34274 -485.498612) (xy 80.296203 -485.502902)
			(xy 80.251235 -485.515628) (xy 80.209352 -485.53636) (xy 80.19034 -485.549956) (xy 80.168206 -485.565855)
			(xy 80.12038 -485.591975) (xy 80.069324 -485.611024) (xy 80.016077 -485.622611) (xy 79.961722 -485.626502)
			(xy 79.907367 -485.622617) (xy 79.854118 -485.611036) (xy 79.80306 -485.591994) (xy 79.755231 -485.565878)
			(xy 79.711606 -485.533222) (xy 79.673074 -485.494688) (xy 79.640418 -485.451063) (xy 79.614303 -485.403234)
			(xy 79.595262 -485.352175) (xy 79.583682 -485.298926) (xy 79.579798 -485.244571) (xy 79.176549 -485.244571)
			(xy 79.172665 -485.29893) (xy 79.161084 -485.352184) (xy 79.142042 -485.403247) (xy 79.115927 -485.45108)
			(xy 79.08327 -485.494709) (xy 79.044736 -485.533247) (xy 79.001109 -485.565908) (xy 78.953279 -485.592028)
			(xy 78.902218 -485.611074) (xy 78.848965 -485.62266) (xy 78.794606 -485.626549) (xy 78.740247 -485.622662)
			(xy 78.686995 -485.611078) (xy 78.635933 -485.592033) (xy 78.588101 -485.565915) (xy 78.56601 -485.549956)
			(xy 78.546998 -485.53636) (xy 78.505115 -485.515628) (xy 78.460147 -485.502902) (xy 78.41361 -485.498612)
			(xy 78.367073 -485.502902) (xy 78.322105 -485.515628) (xy 78.280222 -485.53636) (xy 78.26121 -485.549956)
			(xy 78.239114 -485.566003) (xy 78.191194 -485.592193) (xy 78.140028 -485.61128) (xy 78.086662 -485.622872)
			(xy 78.032188 -485.626732) (xy 77.977721 -485.622783) (xy 77.924375 -485.611104) (xy 77.87324 -485.591934)
			(xy 77.825363 -485.565665) (xy 77.781722 -485.532835) (xy 77.743212 -485.494116) (xy 77.72654 -485.472486)
			(xy 77.712697 -485.454776) (xy 77.67994 -485.424004) (xy 77.64228 -485.399476) (xy 77.600891 -485.381957)
			(xy 77.557066 -485.371994) (xy 77.512171 -485.369898) (xy 77.467608 -485.375735) (xy 77.424767 -485.389321)
			(xy 77.384986 -485.410234) (xy 77.349505 -485.437821) (xy 77.33411 -485.454198) (xy 77.314845 -485.474861)
			(xy 77.271251 -485.510793) (xy 77.222834 -485.539904) (xy 77.170655 -485.561558) (xy 77.115853 -485.57528)
			(xy 77.059627 -485.580772) (xy 77.003205 -485.577913) (xy 76.947822 -485.566765) (xy 76.894688 -485.547573)
			(xy 76.844965 -485.520755) (xy 76.822046 -485.504236) (xy 76.803034 -485.49064) (xy 76.761151 -485.469908)
			(xy 76.716183 -485.457182) (xy 76.669646 -485.452892) (xy 76.623109 -485.457182) (xy 76.578141 -485.469908)
			(xy 76.536258 -485.49064) (xy 76.517246 -485.504236) (xy 76.49513 -485.520162) (xy 76.447303 -485.546286)
			(xy 76.396245 -485.565338) (xy 76.342995 -485.576928) (xy 76.288637 -485.580822) (xy 76.234279 -485.576939)
			(xy 76.181027 -485.565359) (xy 76.129965 -485.546318) (xy 76.082132 -485.520203) (xy 76.038504 -485.487546)
			(xy 75.999968 -485.449011) (xy 75.967309 -485.405385) (xy 75.941191 -485.357554) (xy 75.922147 -485.306493)
			(xy 75.910564 -485.253241) (xy 75.906678 -485.198883) (xy 75.503429 -485.198883) (xy 75.499544 -485.253239)
			(xy 75.487962 -485.306489) (xy 75.46892 -485.357549) (xy 75.442805 -485.405378) (xy 75.410148 -485.449004)
			(xy 75.371615 -485.487539) (xy 75.327991 -485.520197) (xy 75.280162 -485.546314) (xy 75.229103 -485.565358)
			(xy 75.175854 -485.576942) (xy 75.121498 -485.580829) (xy 75.067142 -485.576941) (xy 75.013893 -485.565357)
			(xy 74.962834 -485.546312) (xy 74.915006 -485.520195) (xy 74.892916 -485.504236) (xy 74.873904 -485.49064)
			(xy 74.832021 -485.469908) (xy 74.787053 -485.457182) (xy 74.740516 -485.452892) (xy 74.693979 -485.457182)
			(xy 74.649011 -485.469908) (xy 74.607128 -485.49064) (xy 74.588116 -485.504236) (xy 74.566001 -485.52016)
			(xy 74.518176 -485.546279) (xy 74.467121 -485.565326) (xy 74.413874 -485.576913) (xy 74.35952 -485.580804)
			(xy 74.305166 -485.576919) (xy 74.251918 -485.565338) (xy 74.200861 -485.546296) (xy 74.153033 -485.520182)
			(xy 74.109409 -485.487526) (xy 74.070876 -485.448994) (xy 74.03822 -485.40537) (xy 74.012105 -485.357542)
			(xy 73.993063 -485.306485) (xy 73.981482 -485.253237) (xy 73.977596 -485.198883) (xy 1.525016 -485.198883)
			(xy 1.525016 -486.955605) (xy 73.977567 -486.955605) (xy 73.981455 -486.901247) (xy 73.993039 -486.847995)
			(xy 74.012084 -486.796935) (xy 74.038203 -486.749104) (xy 74.070863 -486.705478) (xy 74.109399 -486.666945)
			(xy 74.153028 -486.634288) (xy 74.20086 -486.608173) (xy 74.251922 -486.589131) (xy 74.305174 -486.577551)
			(xy 74.359532 -486.573667) (xy 74.41389 -486.57756) (xy 74.46714 -486.589149) (xy 74.518199 -486.6082)
			(xy 74.566027 -486.634323) (xy 74.588116 -486.650284) (xy 74.607128 -486.66388) (xy 74.649011 -486.684612)
			(xy 74.693979 -486.697338) (xy 74.740516 -486.701628) (xy 74.787053 -486.697338) (xy 74.832021 -486.684612)
			(xy 74.873904 -486.66388) (xy 74.892916 -486.650284) (xy 74.915011 -486.634336) (xy 74.962835 -486.608219)
			(xy 75.013889 -486.589174) (xy 75.067134 -486.577589) (xy 75.121486 -486.573699) (xy 75.175838 -486.577585)
			(xy 75.229084 -486.589166) (xy 75.280139 -486.608207) (xy 75.327965 -486.634321) (xy 75.371587 -486.666975)
			(xy 75.410119 -486.705505) (xy 75.442774 -486.749127) (xy 75.468889 -486.796952) (xy 75.487931 -486.848007)
			(xy 75.499514 -486.901253) (xy 75.503401 -486.955605) (xy 75.90665 -486.955605) (xy 75.910537 -486.901243)
			(xy 75.922123 -486.847987) (xy 75.94117 -486.796923) (xy 75.967291 -486.749089) (xy 75.999954 -486.705461)
			(xy 76.038494 -486.666925) (xy 76.082127 -486.634267) (xy 76.129964 -486.608151) (xy 76.18103 -486.58911)
			(xy 76.234287 -486.577531) (xy 76.288649 -486.57365) (xy 76.343011 -486.577545) (xy 76.396265 -486.589138)
			(xy 76.447326 -486.608192) (xy 76.495156 -486.63432) (xy 76.517246 -486.650284) (xy 76.536258 -486.66388)
			(xy 76.578141 -486.684612) (xy 76.623109 -486.697338) (xy 76.669646 -486.701628) (xy 76.716183 -486.697338)
			(xy 76.761151 -486.684612) (xy 76.803034 -486.66388) (xy 76.822046 -486.650284) (xy 76.844171 -486.634278)
			(xy 76.892085 -486.608082) (xy 76.943246 -486.58899) (xy 76.996608 -486.577392) (xy 77.051079 -486.573527)
			(xy 77.105544 -486.577472) (xy 77.158889 -486.589147) (xy 77.210022 -486.608314) (xy 77.257898 -486.63458)
			(xy 77.301537 -486.667407) (xy 77.340045 -486.706125) (xy 77.356716 -486.727754) (xy 77.370493 -486.745516)
			(xy 77.403262 -486.776285) (xy 77.440933 -486.800809) (xy 77.482331 -486.818322) (xy 77.526164 -486.828279)
			(xy 77.571065 -486.830369) (xy 77.615634 -486.824526) (xy 77.65848 -486.810934) (xy 77.698265 -486.790015)
			(xy 77.73375 -486.762423) (xy 77.749146 -486.746042) (xy 77.768454 -486.72542) (xy 77.812041 -486.689484)
			(xy 77.86045 -486.660369) (xy 77.912623 -486.638711) (xy 77.96742 -486.624984) (xy 78.023642 -486.619487)
			(xy 78.08006 -486.622342) (xy 78.13544 -486.633485) (xy 78.188572 -486.652673) (xy 78.238292 -486.679486)
			(xy 78.26121 -486.696004) (xy 78.280222 -486.7096) (xy 78.322105 -486.730332) (xy 78.367073 -486.743058)
			(xy 78.41361 -486.747348) (xy 78.460147 -486.743058) (xy 78.505115 -486.730332) (xy 78.546998 -486.7096)
			(xy 78.56601 -486.696004) (xy 78.588087 -486.680029) (xy 78.635912 -486.653908) (xy 78.686968 -486.63486)
			(xy 78.740216 -486.623272) (xy 78.79457 -486.61938) (xy 78.848926 -486.623263) (xy 78.902175 -486.634843)
			(xy 78.953234 -486.653883) (xy 79.001064 -486.679997) (xy 79.04469 -486.712651) (xy 79.083225 -486.751182)
			(xy 79.115883 -486.794805) (xy 79.142001 -486.842633) (xy 79.161047 -486.89369) (xy 79.172631 -486.946938)
			(xy 79.17652 -487.001293) (xy 79.579769 -487.001293) (xy 79.583658 -486.946934) (xy 79.595245 -486.893682)
			(xy 79.614292 -486.842621) (xy 79.640413 -486.794791) (xy 79.673076 -486.751166) (xy 79.711615 -486.712633)
			(xy 79.755246 -486.679978) (xy 79.80308 -486.653865) (xy 79.854144 -486.634826) (xy 79.907398 -486.623249)
			(xy 79.961758 -486.619369) (xy 80.016116 -486.623266) (xy 80.069367 -486.634859) (xy 80.120425 -486.653913)
			(xy 80.168252 -486.680041) (xy 80.19034 -486.696004) (xy 80.209352 -486.7096) (xy 80.251235 -486.730332)
			(xy 80.296203 -486.743058) (xy 80.34274 -486.747348) (xy 80.389277 -486.743058) (xy 80.434245 -486.730332)
			(xy 80.476128 -486.7096) (xy 80.49514 -486.696004) (xy 80.517216 -486.680031) (xy 80.565039 -486.653915)
			(xy 80.616093 -486.634871) (xy 80.669337 -486.623287) (xy 80.723688 -486.619398) (xy 80.778038 -486.623283)
			(xy 80.831283 -486.634864) (xy 80.882338 -486.653905) (xy 80.930163 -486.680018) (xy 80.973785 -486.712671)
			(xy 81.012316 -486.7512) (xy 81.044972 -486.79482) (xy 81.050931 -486.805732) (xy 87.38438 -486.805732)
			(xy 87.388451 -486.75011) (xy 87.400577 -486.695673) (xy 87.4205 -486.643582) (xy 87.447796 -486.594947)
			(xy 87.481882 -486.550804) (xy 87.522031 -486.512095) (xy 87.567389 -486.479644) (xy 87.616989 -486.454143)
			(xy 87.669773 -486.436136) (xy 87.724616 -486.426006) (xy 87.78035 -486.423969) (xy 87.835787 -486.430069)
			(xy 87.889744 -486.444175) (xy 87.941073 -486.465987) (xy 87.988679 -486.495041) (xy 88.031547 -486.530716)
			(xy 88.068764 -486.572253) (xy 88.099537 -486.618766) (xy 88.123209 -486.669263) (xy 88.139277 -486.72267)
			(xy 88.147397 -486.777846) (xy 88.147906 -486.805732) (xy 88.147397 -486.833618) (xy 88.139277 -486.888794)
			(xy 88.123209 -486.942201) (xy 88.099537 -486.992698) (xy 88.068764 -487.039211) (xy 88.031547 -487.080748)
			(xy 87.988679 -487.116423) (xy 87.941073 -487.145477) (xy 87.889744 -487.167289) (xy 87.835787 -487.181395)
			(xy 87.78035 -487.187495) (xy 87.724616 -487.185458) (xy 87.669773 -487.175328) (xy 87.616989 -487.157321)
			(xy 87.567389 -487.13182) (xy 87.522031 -487.099369) (xy 87.481882 -487.06066) (xy 87.447796 -487.016517)
			(xy 87.4205 -486.967882) (xy 87.400577 -486.915791) (xy 87.388451 -486.861354) (xy 87.38438 -486.805732)
			(xy 81.050931 -486.805732) (xy 81.071087 -486.842644) (xy 81.09013 -486.893698) (xy 81.101714 -486.946942)
			(xy 81.105602 -487.001293) (xy 81.101716 -487.055644) (xy 81.090134 -487.108888) (xy 81.071093 -487.159943)
			(xy 81.044979 -487.207767) (xy 81.012326 -487.251389) (xy 80.973796 -487.28992) (xy 80.930175 -487.322574)
			(xy 80.882351 -487.348689) (xy 80.831297 -487.367732) (xy 80.778053 -487.379315) (xy 80.723702 -487.383202)
			(xy 80.669351 -487.379315) (xy 80.616107 -487.367733) (xy 80.565053 -487.348691) (xy 80.517228 -487.322577)
			(xy 80.49514 -487.30662) (xy 80.476128 -487.293024) (xy 80.434245 -487.272292) (xy 80.389277 -487.259566)
			(xy 80.34274 -487.255276) (xy 80.296203 -487.259566) (xy 80.251235 -487.272292) (xy 80.209352 -487.293024)
			(xy 80.19034 -487.30662) (xy 80.16824 -487.322567) (xy 80.120412 -487.348693) (xy 80.069353 -487.367745)
			(xy 80.016102 -487.379337) (xy 79.961744 -487.383231) (xy 79.907384 -487.379349) (xy 79.854131 -487.36777)
			(xy 79.803067 -487.348729) (xy 79.755234 -487.322614) (xy 79.711604 -487.289958) (xy 79.673066 -487.251424)
			(xy 79.640405 -487.207797) (xy 79.614286 -487.159966) (xy 79.595241 -487.108904) (xy 79.583656 -487.055652)
			(xy 79.579769 -487.001293) (xy 79.17652 -487.001293) (xy 79.172633 -487.055648) (xy 79.161051 -487.108896)
			(xy 79.142007 -487.159954) (xy 79.115891 -487.207782) (xy 79.083234 -487.251407) (xy 79.044701 -487.289939)
			(xy 79.001076 -487.322595) (xy 78.953247 -487.348711) (xy 78.902189 -487.367753) (xy 78.84894 -487.379335)
			(xy 78.794585 -487.38322) (xy 78.74023 -487.37933) (xy 78.686982 -487.367744) (xy 78.635925 -487.348698)
			(xy 78.588099 -487.322579) (xy 78.56601 -487.30662) (xy 78.546998 -487.293024) (xy 78.505115 -487.272292)
			(xy 78.460147 -487.259566) (xy 78.41361 -487.255276) (xy 78.367073 -487.259566) (xy 78.322105 -487.272292)
			(xy 78.280222 -487.293024) (xy 78.26121 -487.30662) (xy 78.239118 -487.322674) (xy 78.191198 -487.348867)
			(xy 78.140031 -487.367956) (xy 78.086664 -487.37955) (xy 78.032189 -487.383411) (xy 77.977721 -487.379461)
			(xy 77.924373 -487.367781) (xy 77.873237 -487.348609) (xy 77.82536 -487.322337) (xy 77.78172 -487.289504)
			(xy 77.743211 -487.250781) (xy 77.72654 -487.22915) (xy 77.712698 -487.211441) (xy 77.679939 -487.180673)
			(xy 77.642278 -487.156148) (xy 77.60089 -487.138631) (xy 77.557065 -487.12867) (xy 77.512172 -487.126574)
			(xy 77.46761 -487.13241) (xy 77.42477 -487.145994) (xy 77.384988 -487.166904) (xy 77.349506 -487.194487)
			(xy 77.33411 -487.210862) (xy 77.314842 -487.231524) (xy 77.27125 -487.267458) (xy 77.222835 -487.296572)
			(xy 77.170655 -487.318227) (xy 77.115853 -487.331951) (xy 77.059626 -487.337443) (xy 77.003204 -487.334584)
			(xy 76.94782 -487.323435) (xy 76.894686 -487.304241) (xy 76.844964 -487.277421) (xy 76.822046 -487.2609)
			(xy 76.803034 -487.247304) (xy 76.761151 -487.226572) (xy 76.716183 -487.213846) (xy 76.669646 -487.209556)
			(xy 76.623109 -487.213846) (xy 76.578141 -487.226572) (xy 76.536258 -487.247304) (xy 76.517246 -487.2609)
			(xy 76.495164 -487.276875) (xy 76.447335 -487.303004) (xy 76.396274 -487.322059) (xy 76.343021 -487.333654)
			(xy 76.288659 -487.33755) (xy 76.234296 -487.33367) (xy 76.181039 -487.322093) (xy 76.129972 -487.303053)
			(xy 76.082135 -487.276938) (xy 76.038502 -487.244281) (xy 75.99996 -487.205747) (xy 75.967296 -487.162119)
			(xy 75.941174 -487.114286) (xy 75.922125 -487.063222) (xy 75.910539 -487.009967) (xy 75.90665 -486.955605)
			(xy 75.503401 -486.955605) (xy 75.499512 -487.009957) (xy 75.487929 -487.063202) (xy 75.468885 -487.114256)
			(xy 75.442769 -487.162081) (xy 75.410112 -487.205702) (xy 75.37158 -487.244231) (xy 75.327957 -487.276884)
			(xy 75.28013 -487.302997) (xy 75.229074 -487.322037) (xy 75.175828 -487.333616) (xy 75.121476 -487.337501)
			(xy 75.067125 -487.33361) (xy 75.01388 -487.322023) (xy 74.962826 -487.302977) (xy 74.915003 -487.276859)
			(xy 74.892916 -487.2609) (xy 74.873904 -487.247304) (xy 74.832021 -487.226572) (xy 74.787053 -487.213846)
			(xy 74.740516 -487.209556) (xy 74.693979 -487.213846) (xy 74.649011 -487.226572) (xy 74.607128 -487.247304)
			(xy 74.588116 -487.2609) (xy 74.566035 -487.276872) (xy 74.518208 -487.302996) (xy 74.46715 -487.322048)
			(xy 74.4139 -487.333639) (xy 74.359542 -487.337533) (xy 74.305184 -487.33365) (xy 74.251931 -487.322071)
			(xy 74.200868 -487.303031) (xy 74.153036 -487.276917) (xy 74.109406 -487.244262) (xy 74.070869 -487.205729)
			(xy 74.038208 -487.162104) (xy 74.012088 -487.114274) (xy 73.993042 -487.063214) (xy 73.981456 -487.009963)
			(xy 73.977567 -486.955605) (xy 1.525016 -486.955605) (xy 1.525016 -488.291886) (xy 86.063326 -488.291886)
			(xy 86.067397 -488.236264) (xy 86.079523 -488.181827) (xy 86.099446 -488.129736) (xy 86.126742 -488.081101)
			(xy 86.160828 -488.036958) (xy 86.200977 -487.998249) (xy 86.246335 -487.965798) (xy 86.295935 -487.940297)
			(xy 86.348719 -487.92229) (xy 86.403562 -487.91216) (xy 86.459296 -487.910123) (xy 86.514733 -487.916223)
			(xy 86.56869 -487.930329) (xy 86.620019 -487.952141) (xy 86.667625 -487.981195) (xy 86.710493 -488.01687)
			(xy 86.74771 -488.058407) (xy 86.778483 -488.10492) (xy 86.802155 -488.155417) (xy 86.818223 -488.208824)
			(xy 86.826343 -488.264) (xy 86.826852 -488.291886) (xy 86.826343 -488.319772) (xy 86.818223 -488.374948)
			(xy 86.802155 -488.428355) (xy 86.778483 -488.478852) (xy 86.74771 -488.525365) (xy 86.710493 -488.566902)
			(xy 86.667625 -488.602577) (xy 86.620019 -488.631631) (xy 86.56869 -488.653443) (xy 86.514733 -488.667549)
			(xy 86.459296 -488.673649) (xy 86.403562 -488.671612) (xy 86.348719 -488.661482) (xy 86.295935 -488.643475)
			(xy 86.246335 -488.617974) (xy 86.200977 -488.585523) (xy 86.160828 -488.546814) (xy 86.126742 -488.502671)
			(xy 86.099446 -488.454036) (xy 86.079523 -488.401945) (xy 86.067397 -488.347508) (xy 86.063326 -488.291886)
			(xy 1.525016 -488.291886) (xy 1.525016 -488.722223) (xy 73.977543 -488.722223) (xy 73.981428 -488.667861)
			(xy 73.993011 -488.614606) (xy 74.012055 -488.563541) (xy 74.038173 -488.515707) (xy 74.070833 -488.472076)
			(xy 74.10937 -488.433538) (xy 74.152999 -488.400877) (xy 74.200833 -488.374758) (xy 74.251898 -488.355713)
			(xy 74.305153 -488.34413) (xy 74.359514 -488.340243) (xy 74.413876 -488.344134) (xy 74.46713 -488.355721)
			(xy 74.518193 -488.37477) (xy 74.566025 -488.400893) (xy 74.588116 -488.416854) (xy 74.607128 -488.43045)
			(xy 74.649011 -488.451182) (xy 74.693979 -488.463908) (xy 74.740516 -488.468198) (xy 74.787053 -488.463908)
			(xy 74.832021 -488.451182) (xy 74.873904 -488.43045) (xy 74.892916 -488.416854) (xy 74.915039 -488.400947)
			(xy 74.962862 -488.374833) (xy 75.013913 -488.355792) (xy 75.067155 -488.34421) (xy 75.121504 -488.340323)
			(xy 75.175852 -488.344211) (xy 75.229094 -488.355794) (xy 75.280145 -488.374837) (xy 75.327967 -488.400951)
			(xy 75.371585 -488.433605) (xy 75.410112 -488.472135) (xy 75.442764 -488.515755) (xy 75.468874 -488.563579)
			(xy 75.487913 -488.614632) (xy 75.499493 -488.667874) (xy 75.503377 -488.722223) (xy 75.906625 -488.722223)
			(xy 75.910511 -488.667857) (xy 75.922094 -488.614598) (xy 75.94114 -488.563529) (xy 75.967261 -488.515692)
			(xy 75.999924 -488.472059) (xy 76.038465 -488.433518) (xy 76.082099 -488.400856) (xy 76.129937 -488.374737)
			(xy 76.181006 -488.355692) (xy 76.234266 -488.34411) (xy 76.288631 -488.340225) (xy 76.342997 -488.344119)
			(xy 76.396254 -488.35571) (xy 76.44732 -488.374763) (xy 76.495154 -488.40089) (xy 76.517246 -488.416854)
			(xy 76.536258 -488.43045) (xy 76.578141 -488.451182) (xy 76.623109 -488.463908) (xy 76.669646 -488.468198)
			(xy 76.716183 -488.463908) (xy 76.761151 -488.451182) (xy 76.803034 -488.43045) (xy 76.822046 -488.416854)
			(xy 76.844175 -488.400854) (xy 76.892089 -488.37466) (xy 76.94325 -488.35557) (xy 76.99661 -488.343974)
			(xy 77.05108 -488.340109) (xy 77.105543 -488.344054) (xy 77.158887 -488.355728) (xy 77.21002 -488.374893)
			(xy 77.257895 -488.401157) (xy 77.301534 -488.433982) (xy 77.340044 -488.472697) (xy 77.356716 -488.494324)
			(xy 77.370494 -488.512086) (xy 77.403261 -488.542858) (xy 77.440932 -488.567385) (xy 77.48233 -488.5849)
			(xy 77.526164 -488.594858) (xy 77.571066 -488.596948) (xy 77.615636 -488.591105) (xy 77.658482 -488.57751)
			(xy 77.698267 -488.556589) (xy 77.733751 -488.528994) (xy 77.749146 -488.512612) (xy 77.768453 -488.491989)
			(xy 77.81204 -488.456055) (xy 77.86045 -488.426942) (xy 77.912623 -488.405286) (xy 77.96742 -488.391559)
			(xy 78.023642 -488.386063) (xy 78.080059 -488.388917) (xy 78.135439 -488.400059) (xy 78.18857 -488.419246)
			(xy 78.238292 -488.446058) (xy 78.26121 -488.462574) (xy 78.280222 -488.47617) (xy 78.322105 -488.496902)
			(xy 78.367073 -488.509628) (xy 78.41361 -488.513918) (xy 78.460147 -488.509628) (xy 78.505115 -488.496902)
			(xy 78.546998 -488.47617) (xy 78.56601 -488.462574) (xy 78.588115 -488.446639) (xy 78.635939 -488.420522)
			(xy 78.686992 -488.401478) (xy 78.740237 -488.389893) (xy 78.794588 -488.386004) (xy 78.84894 -488.38989)
			(xy 78.902185 -488.401471) (xy 78.95324 -488.420513) (xy 79.001066 -488.446627) (xy 79.044688 -488.479281)
			(xy 79.083218 -488.517812) (xy 79.115873 -488.561434) (xy 79.141987 -488.609259) (xy 79.161029 -488.660314)
			(xy 79.17261 -488.713559) (xy 79.176496 -488.767911) (xy 79.579745 -488.767911) (xy 79.583632 -488.713548)
			(xy 79.595217 -488.660292) (xy 79.614263 -488.609227) (xy 79.640383 -488.561393) (xy 79.673046 -488.517763)
			(xy 79.711586 -488.479227) (xy 79.755218 -488.446567) (xy 79.803054 -488.420451) (xy 79.85412 -488.401408)
			(xy 79.907377 -488.389828) (xy 79.96174 -488.385945) (xy 80.016102 -488.389839) (xy 80.069356 -488.401431)
			(xy 80.120419 -488.420484) (xy 80.16825 -488.446611) (xy 80.19034 -488.462574) (xy 80.209352 -488.47617)
			(xy 80.251235 -488.496902) (xy 80.296203 -488.509628) (xy 80.34274 -488.513918) (xy 80.389277 -488.509628)
			(xy 80.434245 -488.496902) (xy 80.476128 -488.47617) (xy 80.49514 -488.462574) (xy 80.517244 -488.446642)
			(xy 80.565066 -488.42053) (xy 80.616117 -488.401489) (xy 80.669358 -488.389908) (xy 80.723706 -488.386022)
			(xy 80.778053 -488.38991) (xy 80.831294 -488.401492) (xy 80.882344 -488.420534) (xy 80.930165 -488.446648)
			(xy 80.973783 -488.479301) (xy 81.01231 -488.517829) (xy 81.044961 -488.561449) (xy 81.071072 -488.609271)
			(xy 81.090112 -488.660322) (xy 81.101693 -488.713563) (xy 81.105578 -488.767911) (xy 81.10169 -488.822258)
			(xy 81.090106 -488.875499) (xy 81.071063 -488.926549) (xy 81.044949 -488.97437) (xy 81.012296 -489.017987)
			(xy 80.973767 -489.056513) (xy 80.930147 -489.089164) (xy 80.882325 -489.115275) (xy 80.831273 -489.134314)
			(xy 80.778031 -489.145893) (xy 80.723684 -489.149778) (xy 80.669337 -489.145889) (xy 80.616096 -489.134305)
			(xy 80.565046 -489.115261) (xy 80.517226 -489.089147) (xy 80.49514 -489.07319) (xy 80.476128 -489.059594)
			(xy 80.434245 -489.038862) (xy 80.389277 -489.026136) (xy 80.34274 -489.021846) (xy 80.296203 -489.026136)
			(xy 80.251235 -489.038862) (xy 80.209352 -489.059594) (xy 80.19034 -489.07319) (xy 80.168268 -489.089178)
			(xy 80.120438 -489.115307) (xy 80.069377 -489.134363) (xy 80.016123 -489.145958) (xy 79.961762 -489.149855)
			(xy 79.907399 -489.145975) (xy 79.854141 -489.134398) (xy 79.803074 -489.115358) (xy 79.755236 -489.089244)
			(xy 79.711602 -489.056587) (xy 79.67306 -489.018053) (xy 79.640395 -488.974425) (xy 79.614272 -488.926592)
			(xy 79.595223 -488.875528) (xy 79.583635 -488.822273) (xy 79.579745 -488.767911) (xy 79.176496 -488.767911)
			(xy 79.172607 -488.822262) (xy 79.161022 -488.875507) (xy 79.141978 -488.926561) (xy 79.115861 -488.974385)
			(xy 79.083204 -489.018005) (xy 79.044671 -489.056533) (xy 79.001048 -489.089185) (xy 78.953221 -489.115296)
			(xy 78.902165 -489.134335) (xy 78.848919 -489.145913) (xy 78.794567 -489.149796) (xy 78.740216 -489.145904)
			(xy 78.686972 -489.134316) (xy 78.635919 -489.115269) (xy 78.588097 -489.089149) (xy 78.56601 -489.07319)
			(xy 78.546998 -489.059594) (xy 78.505115 -489.038862) (xy 78.460147 -489.026136) (xy 78.41361 -489.021846)
			(xy 78.367073 -489.026136) (xy 78.322105 -489.038862) (xy 78.280222 -489.059594) (xy 78.26121 -489.07319)
			(xy 78.239109 -489.08923) (xy 78.191189 -489.115417) (xy 78.140024 -489.134502) (xy 78.08666 -489.146093)
			(xy 78.032188 -489.149953) (xy 77.977722 -489.146003) (xy 77.924376 -489.134325) (xy 77.873242 -489.115157)
			(xy 77.825365 -489.088891) (xy 77.781725 -489.056064) (xy 77.743213 -489.017348) (xy 77.72654 -488.99572)
			(xy 77.712698 -488.978011) (xy 77.679938 -488.947246) (xy 77.642276 -488.922724) (xy 77.600888 -488.90521)
			(xy 77.557065 -488.89525) (xy 77.512173 -488.893154) (xy 77.467612 -488.898989) (xy 77.424772 -488.912572)
			(xy 77.38499 -488.933479) (xy 77.349507 -488.961058) (xy 77.33411 -488.977432) (xy 77.314847 -488.998097)
			(xy 77.271251 -489.034026) (xy 77.222834 -489.063135) (xy 77.170655 -489.084786) (xy 77.115853 -489.098508)
			(xy 77.059627 -489.103999) (xy 77.003206 -489.10114) (xy 76.947823 -489.089994) (xy 76.894689 -489.070803)
			(xy 76.844965 -489.043988) (xy 76.822046 -489.02747) (xy 76.803034 -489.013874) (xy 76.761151 -488.993142)
			(xy 76.716183 -488.980416) (xy 76.669646 -488.976126) (xy 76.623109 -488.980416) (xy 76.578141 -488.993142)
			(xy 76.536258 -489.013874) (xy 76.517246 -489.02747) (xy 76.495192 -489.043485) (xy 76.447361 -489.069618)
			(xy 76.396298 -489.088677) (xy 76.343042 -489.100275) (xy 76.288677 -489.104175) (xy 76.234311 -489.100297)
			(xy 76.18105 -489.088721) (xy 76.129979 -489.069682) (xy 76.082137 -489.043568) (xy 76.038499 -489.010911)
			(xy 75.999954 -488.972376) (xy 75.967286 -488.928747) (xy 75.941159 -488.880912) (xy 75.922107 -488.829846)
			(xy 75.910517 -488.776588) (xy 75.906625 -488.722223) (xy 75.503377 -488.722223) (xy 75.499486 -488.776571)
			(xy 75.4879 -488.829812) (xy 75.468855 -488.880863) (xy 75.442739 -488.928683) (xy 75.410082 -488.9723)
			(xy 75.371551 -489.010825) (xy 75.327929 -489.043474) (xy 75.280104 -489.069582) (xy 75.22905 -489.088619)
			(xy 75.175807 -489.100195) (xy 75.121458 -489.104077) (xy 75.06711 -489.100183) (xy 75.01387 -489.088595)
			(xy 74.96282 -489.069548) (xy 74.915001 -489.043429) (xy 74.892916 -489.02747) (xy 74.873904 -489.013874)
			(xy 74.832021 -488.993142) (xy 74.787053 -488.980416) (xy 74.740516 -488.976126) (xy 74.693979 -488.980416)
			(xy 74.649011 -488.993142) (xy 74.607128 -489.013874) (xy 74.588116 -489.02747) (xy 74.566063 -489.043483)
			(xy 74.518234 -489.069611) (xy 74.467174 -489.088666) (xy 74.413921 -489.10026) (xy 74.35956 -489.104157)
			(xy 74.305198 -489.100277) (xy 74.251941 -489.0887) (xy 74.200875 -489.069661) (xy 74.153038 -489.043547)
			(xy 74.109404 -489.010892) (xy 74.070863 -488.972358) (xy 74.038197 -488.928732) (xy 74.012074 -488.8809)
			(xy 73.993024 -488.829838) (xy 73.981435 -488.776584) (xy 73.977543 -488.722223) (xy 1.525016 -488.722223)
			(xy 1.525016 -489.403898) (xy 84.047328 -489.403898) (xy 84.051399 -489.348276) (xy 84.063525 -489.293839)
			(xy 84.083448 -489.241748) (xy 84.110744 -489.193113) (xy 84.14483 -489.14897) (xy 84.184979 -489.110261)
			(xy 84.230337 -489.07781) (xy 84.279937 -489.052309) (xy 84.332721 -489.034302) (xy 84.387564 -489.024172)
			(xy 84.443298 -489.022135) (xy 84.498735 -489.028235) (xy 84.552692 -489.042341) (xy 84.604021 -489.064153)
			(xy 84.651627 -489.093207) (xy 84.694495 -489.128882) (xy 84.731712 -489.170419) (xy 84.762485 -489.216932)
			(xy 84.786157 -489.267429) (xy 84.802225 -489.320836) (xy 84.810345 -489.376012) (xy 84.810854 -489.403898)
			(xy 84.810345 -489.431784) (xy 84.802225 -489.48696) (xy 84.786157 -489.540367) (xy 84.762485 -489.590864)
			(xy 84.731712 -489.637377) (xy 84.694495 -489.678914) (xy 84.651627 -489.714589) (xy 84.604021 -489.743643)
			(xy 84.552692 -489.765455) (xy 84.498735 -489.779561) (xy 84.443298 -489.785661) (xy 84.387564 -489.783624)
			(xy 84.332721 -489.773494) (xy 84.279937 -489.755487) (xy 84.230337 -489.729986) (xy 84.184979 -489.697535)
			(xy 84.14483 -489.658826) (xy 84.110744 -489.614683) (xy 84.083448 -489.566048) (xy 84.063525 -489.513957)
			(xy 84.051399 -489.45952) (xy 84.047328 -489.403898) (xy 1.525016 -489.403898) (xy 1.525016 -491.999778)
			(xy 6.671831 -491.999778) (xy 6.675786 -491.907941) (xy 6.687621 -491.816784) (xy 6.707248 -491.726981)
			(xy 6.734522 -491.639199) (xy 6.769242 -491.554085) (xy 6.81115 -491.472272) (xy 6.859936 -491.394364)
			(xy 6.915239 -491.320939) (xy 6.976649 -491.252539) (xy 7.043711 -491.189672) (xy 7.11593 -491.132802)
			(xy 7.19277 -491.082351) (xy 7.273663 -491.038692) (xy 7.358009 -491.002149) (xy 7.445185 -490.972992)
			(xy 7.534544 -490.951438) (xy 7.625425 -490.937644) (xy 7.717156 -490.931714) (xy 7.809057 -490.933692)
			(xy 7.900448 -490.943563) (xy 7.990652 -490.961253) (xy 8.079001 -490.986633) (xy 8.164841 -491.019513)
			(xy 8.247537 -491.059651) (xy 8.326477 -491.10675) (xy 8.401075 -491.16046) (xy 8.470781 -491.220384)
			(xy 8.535076 -491.286078) (xy 8.593487 -491.357056) (xy 8.645579 -491.432793) (xy 8.690968 -491.512728)
			(xy 8.729318 -491.596268) (xy 8.760343 -491.682796) (xy 8.783816 -491.771671) (xy 8.799562 -491.862235)
			(xy 8.807464 -491.953817) (xy 8.807958 -491.999778) (xy 8.807464 -492.045739) (xy 8.799562 -492.137321)
			(xy 8.783816 -492.227885) (xy 8.760343 -492.31676) (xy 8.729318 -492.403288) (xy 8.690968 -492.486828)
			(xy 8.645579 -492.566763) (xy 8.593487 -492.6425) (xy 8.535076 -492.713478) (xy 8.470781 -492.779172)
			(xy 8.401075 -492.839096) (xy 8.326477 -492.892806) (xy 8.247537 -492.939905) (xy 8.164841 -492.980043)
			(xy 8.079001 -493.012923) (xy 7.990652 -493.038303) (xy 7.900448 -493.055993) (xy 7.809057 -493.065864)
			(xy 7.717156 -493.067842) (xy 7.625425 -493.061912) (xy 7.534544 -493.048118) (xy 7.445185 -493.026564)
			(xy 7.358009 -492.997407) (xy 7.273663 -492.960864) (xy 7.19277 -492.917205) (xy 7.11593 -492.866754)
			(xy 7.043711 -492.809884) (xy 6.976649 -492.747017) (xy 6.915239 -492.678617) (xy 6.859936 -492.605192)
			(xy 6.81115 -492.527284) (xy 6.769242 -492.445471) (xy 6.734522 -492.360357) (xy 6.707248 -492.272575)
			(xy 6.687621 -492.182772) (xy 6.675786 -492.091615) (xy 6.671831 -491.999778) (xy 1.525016 -491.999778)
			(xy 1.525016 -495.86007) (xy 39.818564 -495.86007) (xy 39.819058 -495.802661) (xy 39.826902 -495.688113)
			(xy 39.842544 -495.574366) (xy 39.865911 -495.461952) (xy 39.896896 -495.351394) (xy 39.935352 -495.243209)
			(xy 39.981101 -495.1379) (xy 40.03393 -495.035958) (xy 40.093592 -494.937859) (xy 40.159809 -494.84406)
			(xy 40.232272 -494.754998) (xy 40.310645 -494.671089) (xy 40.39456 -494.592723) (xy 40.483627 -494.520266)
			(xy 40.577431 -494.454056) (xy 40.675535 -494.394402) (xy 40.777481 -494.341581) (xy 40.882793 -494.295839)
			(xy 40.990981 -494.257391) (xy 41.101541 -494.226415) (xy 41.213957 -494.203056) (xy 41.327705 -494.187423)
			(xy 41.442254 -494.179588) (xy 41.557072 -494.179588) (xy 41.671621 -494.187423) (xy 41.785369 -494.203056)
			(xy 41.897785 -494.226415) (xy 42.008345 -494.257391) (xy 42.116533 -494.295839) (xy 42.221845 -494.341581)
			(xy 42.323791 -494.394402) (xy 42.421895 -494.454056) (xy 42.501239 -494.51006) (xy 63.647577 -494.51006)
			(xy 63.651612 -494.434356) (xy 63.663671 -494.359511) (xy 63.683617 -494.28637) (xy 63.711224 -494.215765)
			(xy 63.74618 -494.148494) (xy 63.788088 -494.085319) (xy 63.836474 -494.026957) (xy 63.89079 -493.974069)
			(xy 63.950419 -493.927254) (xy 64.014687 -493.887042) (xy 64.082864 -493.85389) (xy 64.15418 -493.828172)
			(xy 64.227825 -493.81018) (xy 64.302965 -493.800118) (xy 64.378749 -493.798099) (xy 64.454319 -493.804148)
			(xy 64.528817 -493.818195) (xy 64.6014 -493.840081) (xy 64.671246 -493.869558) (xy 64.737563 -493.906293)
			(xy 64.799599 -493.949868) (xy 64.856652 -493.99979) (xy 64.908076 -494.055494) (xy 64.953287 -494.116349)
			(xy 64.991774 -494.181664) (xy 65.0231 -494.2507) (xy 65.04691 -494.322675) (xy 65.062935 -494.396773)
			(xy 65.070994 -494.472154) (xy 65.071498 -494.51006) (xy 66.187577 -494.51006) (xy 66.191612 -494.434356)
			(xy 66.203671 -494.359511) (xy 66.223617 -494.28637) (xy 66.251224 -494.215765) (xy 66.28618 -494.148494)
			(xy 66.328088 -494.085319) (xy 66.376474 -494.026957) (xy 66.43079 -493.974069) (xy 66.490419 -493.927254)
			(xy 66.554687 -493.887042) (xy 66.622864 -493.85389) (xy 66.69418 -493.828172) (xy 66.767825 -493.81018)
			(xy 66.842965 -493.800118) (xy 66.918749 -493.798099) (xy 66.994319 -493.804148) (xy 67.068817 -493.818195)
			(xy 67.1414 -493.840081) (xy 67.211246 -493.869558) (xy 67.277563 -493.906293) (xy 67.339599 -493.949868)
			(xy 67.396652 -493.99979) (xy 67.448076 -494.055494) (xy 67.493287 -494.116349) (xy 67.531774 -494.181664)
			(xy 67.5631 -494.2507) (xy 67.58691 -494.322675) (xy 67.602935 -494.396773) (xy 67.610994 -494.472154)
			(xy 67.611498 -494.51006) (xy 68.727577 -494.51006) (xy 68.731612 -494.434356) (xy 68.743671 -494.359511)
			(xy 68.763617 -494.28637) (xy 68.791224 -494.215765) (xy 68.82618 -494.148494) (xy 68.868088 -494.085319)
			(xy 68.916474 -494.026957) (xy 68.97079 -493.974069) (xy 69.030419 -493.927254) (xy 69.094687 -493.887042)
			(xy 69.162864 -493.85389) (xy 69.23418 -493.828172) (xy 69.307825 -493.81018) (xy 69.382965 -493.800118)
			(xy 69.458749 -493.798099) (xy 69.534319 -493.804148) (xy 69.608817 -493.818195) (xy 69.6814 -493.840081)
			(xy 69.751246 -493.869558) (xy 69.817563 -493.906293) (xy 69.879599 -493.949868) (xy 69.936652 -493.99979)
			(xy 69.988076 -494.055494) (xy 70.033287 -494.116349) (xy 70.071774 -494.181664) (xy 70.1031 -494.2507)
			(xy 70.12691 -494.322675) (xy 70.142935 -494.396773) (xy 70.150994 -494.472154) (xy 70.151498 -494.51006)
			(xy 71.267577 -494.51006) (xy 71.271612 -494.434356) (xy 71.283671 -494.359511) (xy 71.303617 -494.28637)
			(xy 71.331224 -494.215765) (xy 71.36618 -494.148494) (xy 71.408088 -494.085319) (xy 71.456474 -494.026957)
			(xy 71.51079 -493.974069) (xy 71.570419 -493.927254) (xy 71.634687 -493.887042) (xy 71.702864 -493.85389)
			(xy 71.77418 -493.828172) (xy 71.847825 -493.81018) (xy 71.922965 -493.800118) (xy 71.998749 -493.798099)
			(xy 72.074319 -493.804148) (xy 72.148817 -493.818195) (xy 72.2214 -493.840081) (xy 72.291246 -493.869558)
			(xy 72.357563 -493.906293) (xy 72.419599 -493.949868) (xy 72.476652 -493.99979) (xy 72.528076 -494.055494)
			(xy 72.573287 -494.116349) (xy 72.611774 -494.181664) (xy 72.6431 -494.2507) (xy 72.66691 -494.322675)
			(xy 72.682935 -494.396773) (xy 72.690994 -494.472154) (xy 72.691498 -494.51006) (xy 73.807577 -494.51006)
			(xy 73.811612 -494.434356) (xy 73.823671 -494.359511) (xy 73.843617 -494.28637) (xy 73.871224 -494.215765)
			(xy 73.90618 -494.148494) (xy 73.948088 -494.085319) (xy 73.996474 -494.026957) (xy 74.05079 -493.974069)
			(xy 74.110419 -493.927254) (xy 74.174687 -493.887042) (xy 74.242864 -493.85389) (xy 74.31418 -493.828172)
			(xy 74.387825 -493.81018) (xy 74.462965 -493.800118) (xy 74.538749 -493.798099) (xy 74.614319 -493.804148)
			(xy 74.688817 -493.818195) (xy 74.7614 -493.840081) (xy 74.831246 -493.869558) (xy 74.897563 -493.906293)
			(xy 74.959599 -493.949868) (xy 75.016652 -493.99979) (xy 75.068076 -494.055494) (xy 75.113287 -494.116349)
			(xy 75.151774 -494.181664) (xy 75.1831 -494.2507) (xy 75.20691 -494.322675) (xy 75.222935 -494.396773)
			(xy 75.230994 -494.472154) (xy 75.231498 -494.51006) (xy 76.347577 -494.51006) (xy 76.351612 -494.434356)
			(xy 76.363671 -494.359511) (xy 76.383617 -494.28637) (xy 76.411224 -494.215765) (xy 76.44618 -494.148494)
			(xy 76.488088 -494.085319) (xy 76.536474 -494.026957) (xy 76.59079 -493.974069) (xy 76.650419 -493.927254)
			(xy 76.714687 -493.887042) (xy 76.782864 -493.85389) (xy 76.85418 -493.828172) (xy 76.927825 -493.81018)
			(xy 77.002965 -493.800118) (xy 77.078749 -493.798099) (xy 77.154319 -493.804148) (xy 77.228817 -493.818195)
			(xy 77.3014 -493.840081) (xy 77.371246 -493.869558) (xy 77.437563 -493.906293) (xy 77.499599 -493.949868)
			(xy 77.556652 -493.99979) (xy 77.608076 -494.055494) (xy 77.653287 -494.116349) (xy 77.691774 -494.181664)
			(xy 77.7231 -494.2507) (xy 77.74691 -494.322675) (xy 77.762935 -494.396773) (xy 77.770994 -494.472154)
			(xy 77.771498 -494.51006) (xy 78.887577 -494.51006) (xy 78.891612 -494.434356) (xy 78.903671 -494.359511)
			(xy 78.923617 -494.28637) (xy 78.951224 -494.215765) (xy 78.98618 -494.148494) (xy 79.028088 -494.085319)
			(xy 79.076474 -494.026957) (xy 79.13079 -493.974069) (xy 79.190419 -493.927254) (xy 79.254687 -493.887042)
			(xy 79.322864 -493.85389) (xy 79.39418 -493.828172) (xy 79.467825 -493.81018) (xy 79.542965 -493.800118)
			(xy 79.618749 -493.798099) (xy 79.694319 -493.804148) (xy 79.768817 -493.818195) (xy 79.8414 -493.840081)
			(xy 79.911246 -493.869558) (xy 79.977563 -493.906293) (xy 80.039599 -493.949868) (xy 80.096652 -493.99979)
			(xy 80.148076 -494.055494) (xy 80.193287 -494.116349) (xy 80.231774 -494.181664) (xy 80.2631 -494.2507)
			(xy 80.28691 -494.322675) (xy 80.302935 -494.396773) (xy 80.310994 -494.472154) (xy 80.311498 -494.51006)
			(xy 81.427577 -494.51006) (xy 81.431612 -494.434356) (xy 81.443671 -494.359511) (xy 81.463617 -494.28637)
			(xy 81.491224 -494.215765) (xy 81.52618 -494.148494) (xy 81.568088 -494.085319) (xy 81.616474 -494.026957)
			(xy 81.67079 -493.974069) (xy 81.730419 -493.927254) (xy 81.794687 -493.887042) (xy 81.862864 -493.85389)
			(xy 81.93418 -493.828172) (xy 82.007825 -493.81018) (xy 82.082965 -493.800118) (xy 82.158749 -493.798099)
			(xy 82.234319 -493.804148) (xy 82.308817 -493.818195) (xy 82.3814 -493.840081) (xy 82.451246 -493.869558)
			(xy 82.517563 -493.906293) (xy 82.579599 -493.949868) (xy 82.636652 -493.99979) (xy 82.688076 -494.055494)
			(xy 82.733287 -494.116349) (xy 82.771774 -494.181664) (xy 82.8031 -494.2507) (xy 82.82691 -494.322675)
			(xy 82.842935 -494.396773) (xy 82.850994 -494.472154) (xy 82.851498 -494.51006) (xy 82.850994 -494.547966)
			(xy 82.842935 -494.623347) (xy 82.82691 -494.697445) (xy 82.8031 -494.76942) (xy 82.771774 -494.838456)
			(xy 82.733287 -494.903771) (xy 82.688076 -494.964626) (xy 82.636652 -495.02033) (xy 82.579599 -495.070252)
			(xy 82.517563 -495.113827) (xy 82.451246 -495.150562) (xy 82.3814 -495.180039) (xy 82.308817 -495.201925)
			(xy 82.234319 -495.215972) (xy 82.158749 -495.222021) (xy 82.082965 -495.220002) (xy 82.007825 -495.20994)
			(xy 81.93418 -495.191948) (xy 81.862864 -495.16623) (xy 81.794687 -495.133078) (xy 81.730419 -495.092866)
			(xy 81.67079 -495.046051) (xy 81.616474 -494.993163) (xy 81.568088 -494.934801) (xy 81.52618 -494.871626)
			(xy 81.491224 -494.804355) (xy 81.463617 -494.73375) (xy 81.443671 -494.660609) (xy 81.431612 -494.585764)
			(xy 81.427577 -494.51006) (xy 80.311498 -494.51006) (xy 80.310994 -494.547966) (xy 80.302935 -494.623347)
			(xy 80.28691 -494.697445) (xy 80.2631 -494.76942) (xy 80.231774 -494.838456) (xy 80.193287 -494.903771)
			(xy 80.148076 -494.964626) (xy 80.096652 -495.02033) (xy 80.039599 -495.070252) (xy 79.977563 -495.113827)
			(xy 79.911246 -495.150562) (xy 79.8414 -495.180039) (xy 79.768817 -495.201925) (xy 79.694319 -495.215972)
			(xy 79.618749 -495.222021) (xy 79.542965 -495.220002) (xy 79.467825 -495.20994) (xy 79.39418 -495.191948)
			(xy 79.322864 -495.16623) (xy 79.254687 -495.133078) (xy 79.190419 -495.092866) (xy 79.13079 -495.046051)
			(xy 79.076474 -494.993163) (xy 79.028088 -494.934801) (xy 78.98618 -494.871626) (xy 78.951224 -494.804355)
			(xy 78.923617 -494.73375) (xy 78.903671 -494.660609) (xy 78.891612 -494.585764) (xy 78.887577 -494.51006)
			(xy 77.771498 -494.51006) (xy 77.770994 -494.547966) (xy 77.762935 -494.623347) (xy 77.74691 -494.697445)
			(xy 77.7231 -494.76942) (xy 77.691774 -494.838456) (xy 77.653287 -494.903771) (xy 77.608076 -494.964626)
			(xy 77.556652 -495.02033) (xy 77.499599 -495.070252) (xy 77.437563 -495.113827) (xy 77.371246 -495.150562)
			(xy 77.3014 -495.180039) (xy 77.228817 -495.201925) (xy 77.154319 -495.215972) (xy 77.078749 -495.222021)
			(xy 77.002965 -495.220002) (xy 76.927825 -495.20994) (xy 76.85418 -495.191948) (xy 76.782864 -495.16623)
			(xy 76.714687 -495.133078) (xy 76.650419 -495.092866) (xy 76.59079 -495.046051) (xy 76.536474 -494.993163)
			(xy 76.488088 -494.934801) (xy 76.44618 -494.871626) (xy 76.411224 -494.804355) (xy 76.383617 -494.73375)
			(xy 76.363671 -494.660609) (xy 76.351612 -494.585764) (xy 76.347577 -494.51006) (xy 75.231498 -494.51006)
			(xy 75.230994 -494.547966) (xy 75.222935 -494.623347) (xy 75.20691 -494.697445) (xy 75.1831 -494.76942)
			(xy 75.151774 -494.838456) (xy 75.113287 -494.903771) (xy 75.068076 -494.964626) (xy 75.016652 -495.02033)
			(xy 74.959599 -495.070252) (xy 74.897563 -495.113827) (xy 74.831246 -495.150562) (xy 74.7614 -495.180039)
			(xy 74.688817 -495.201925) (xy 74.614319 -495.215972) (xy 74.538749 -495.222021) (xy 74.462965 -495.220002)
			(xy 74.387825 -495.20994) (xy 74.31418 -495.191948) (xy 74.242864 -495.16623) (xy 74.174687 -495.133078)
			(xy 74.110419 -495.092866) (xy 74.05079 -495.046051) (xy 73.996474 -494.993163) (xy 73.948088 -494.934801)
			(xy 73.90618 -494.871626) (xy 73.871224 -494.804355) (xy 73.843617 -494.73375) (xy 73.823671 -494.660609)
			(xy 73.811612 -494.585764) (xy 73.807577 -494.51006) (xy 72.691498 -494.51006) (xy 72.690994 -494.547966)
			(xy 72.682935 -494.623347) (xy 72.66691 -494.697445) (xy 72.6431 -494.76942) (xy 72.611774 -494.838456)
			(xy 72.573287 -494.903771) (xy 72.528076 -494.964626) (xy 72.476652 -495.02033) (xy 72.419599 -495.070252)
			(xy 72.357563 -495.113827) (xy 72.291246 -495.150562) (xy 72.2214 -495.180039) (xy 72.148817 -495.201925)
			(xy 72.074319 -495.215972) (xy 71.998749 -495.222021) (xy 71.922965 -495.220002) (xy 71.847825 -495.20994)
			(xy 71.77418 -495.191948) (xy 71.702864 -495.16623) (xy 71.634687 -495.133078) (xy 71.570419 -495.092866)
			(xy 71.51079 -495.046051) (xy 71.456474 -494.993163) (xy 71.408088 -494.934801) (xy 71.36618 -494.871626)
			(xy 71.331224 -494.804355) (xy 71.303617 -494.73375) (xy 71.283671 -494.660609) (xy 71.271612 -494.585764)
			(xy 71.267577 -494.51006) (xy 70.151498 -494.51006) (xy 70.150994 -494.547966) (xy 70.142935 -494.623347)
			(xy 70.12691 -494.697445) (xy 70.1031 -494.76942) (xy 70.071774 -494.838456) (xy 70.033287 -494.903771)
			(xy 69.988076 -494.964626) (xy 69.936652 -495.02033) (xy 69.879599 -495.070252) (xy 69.817563 -495.113827)
			(xy 69.751246 -495.150562) (xy 69.6814 -495.180039) (xy 69.608817 -495.201925) (xy 69.534319 -495.215972)
			(xy 69.458749 -495.222021) (xy 69.382965 -495.220002) (xy 69.307825 -495.20994) (xy 69.23418 -495.191948)
			(xy 69.162864 -495.16623) (xy 69.094687 -495.133078) (xy 69.030419 -495.092866) (xy 68.97079 -495.046051)
			(xy 68.916474 -494.993163) (xy 68.868088 -494.934801) (xy 68.82618 -494.871626) (xy 68.791224 -494.804355)
			(xy 68.763617 -494.73375) (xy 68.743671 -494.660609) (xy 68.731612 -494.585764) (xy 68.727577 -494.51006)
			(xy 67.611498 -494.51006) (xy 67.610994 -494.547966) (xy 67.602935 -494.623347) (xy 67.58691 -494.697445)
			(xy 67.5631 -494.76942) (xy 67.531774 -494.838456) (xy 67.493287 -494.903771) (xy 67.448076 -494.964626)
			(xy 67.396652 -495.02033) (xy 67.339599 -495.070252) (xy 67.277563 -495.113827) (xy 67.211246 -495.150562)
			(xy 67.1414 -495.180039) (xy 67.068817 -495.201925) (xy 66.994319 -495.215972) (xy 66.918749 -495.222021)
			(xy 66.842965 -495.220002) (xy 66.767825 -495.20994) (xy 66.69418 -495.191948) (xy 66.622864 -495.16623)
			(xy 66.554687 -495.133078) (xy 66.490419 -495.092866) (xy 66.43079 -495.046051) (xy 66.376474 -494.993163)
			(xy 66.328088 -494.934801) (xy 66.28618 -494.871626) (xy 66.251224 -494.804355) (xy 66.223617 -494.73375)
			(xy 66.203671 -494.660609) (xy 66.191612 -494.585764) (xy 66.187577 -494.51006) (xy 65.071498 -494.51006)
			(xy 65.070994 -494.547966) (xy 65.062935 -494.623347) (xy 65.04691 -494.697445) (xy 65.0231 -494.76942)
			(xy 64.991774 -494.838456) (xy 64.953287 -494.903771) (xy 64.908076 -494.964626) (xy 64.856652 -495.02033)
			(xy 64.799599 -495.070252) (xy 64.737563 -495.113827) (xy 64.671246 -495.150562) (xy 64.6014 -495.180039)
			(xy 64.528817 -495.201925) (xy 64.454319 -495.215972) (xy 64.378749 -495.222021) (xy 64.302965 -495.220002)
			(xy 64.227825 -495.20994) (xy 64.15418 -495.191948) (xy 64.082864 -495.16623) (xy 64.014687 -495.133078)
			(xy 63.950419 -495.092866) (xy 63.89079 -495.046051) (xy 63.836474 -494.993163) (xy 63.788088 -494.934801)
			(xy 63.74618 -494.871626) (xy 63.711224 -494.804355) (xy 63.683617 -494.73375) (xy 63.663671 -494.660609)
			(xy 63.651612 -494.585764) (xy 63.647577 -494.51006) (xy 42.501239 -494.51006) (xy 42.515699 -494.520266)
			(xy 42.604766 -494.592723) (xy 42.688681 -494.671089) (xy 42.767054 -494.754998) (xy 42.839517 -494.84406)
			(xy 42.905734 -494.937859) (xy 42.965396 -495.035958) (xy 43.018225 -495.1379) (xy 43.063974 -495.243209)
			(xy 43.10243 -495.351394) (xy 43.133415 -495.461952) (xy 43.156782 -495.574366) (xy 43.172424 -495.688113)
			(xy 43.180268 -495.802661) (xy 43.180762 -495.86007) (xy 43.180576 -495.893253) (xy 43.177909 -495.959567)
			(xy 43.175428 -495.992658) (xy 43.170272 -496.050942) (xy 43.152948 -496.166671) (xy 43.127616 -496.280914)
			(xy 43.094401 -496.393119) (xy 43.053462 -496.502742) (xy 43.004999 -496.609253) (xy 42.949245 -496.712135)
			(xy 42.886471 -496.810891) (xy 42.816981 -496.905042) (xy 42.741111 -496.994132) (xy 42.659229 -497.077729)
			(xy 42.571732 -497.15543) (xy 42.500813 -497.21008) (xy 63.647577 -497.21008) (xy 63.651612 -497.134376)
			(xy 63.663671 -497.059531) (xy 63.683617 -496.98639) (xy 63.711224 -496.915785) (xy 63.74618 -496.848514)
			(xy 63.788088 -496.785339) (xy 63.836474 -496.726977) (xy 63.89079 -496.674089) (xy 63.950419 -496.627274)
			(xy 64.014687 -496.587062) (xy 64.082864 -496.55391) (xy 64.15418 -496.528192) (xy 64.227825 -496.5102)
			(xy 64.302965 -496.500138) (xy 64.378749 -496.498119) (xy 64.454319 -496.504168) (xy 64.528817 -496.518215)
			(xy 64.6014 -496.540101) (xy 64.671246 -496.569578) (xy 64.737563 -496.606313) (xy 64.799599 -496.649888)
			(xy 64.856652 -496.69981) (xy 64.908076 -496.755514) (xy 64.953287 -496.816369) (xy 64.991774 -496.881684)
			(xy 65.0231 -496.95072) (xy 65.04691 -497.022695) (xy 65.062935 -497.096793) (xy 65.070994 -497.172174)
			(xy 65.071498 -497.21008) (xy 66.187577 -497.21008) (xy 66.191612 -497.134376) (xy 66.203671 -497.059531)
			(xy 66.223617 -496.98639) (xy 66.251224 -496.915785) (xy 66.28618 -496.848514) (xy 66.328088 -496.785339)
			(xy 66.376474 -496.726977) (xy 66.43079 -496.674089) (xy 66.490419 -496.627274) (xy 66.554687 -496.587062)
			(xy 66.622864 -496.55391) (xy 66.69418 -496.528192) (xy 66.767825 -496.5102) (xy 66.842965 -496.500138)
			(xy 66.918749 -496.498119) (xy 66.994319 -496.504168) (xy 67.068817 -496.518215) (xy 67.1414 -496.540101)
			(xy 67.211246 -496.569578) (xy 67.277563 -496.606313) (xy 67.339599 -496.649888) (xy 67.396652 -496.69981)
			(xy 67.448076 -496.755514) (xy 67.493287 -496.816369) (xy 67.531774 -496.881684) (xy 67.5631 -496.95072)
			(xy 67.58691 -497.022695) (xy 67.602935 -497.096793) (xy 67.610994 -497.172174) (xy 67.611498 -497.21008)
			(xy 68.727577 -497.21008) (xy 68.731612 -497.134376) (xy 68.743671 -497.059531) (xy 68.763617 -496.98639)
			(xy 68.791224 -496.915785) (xy 68.82618 -496.848514) (xy 68.868088 -496.785339) (xy 68.916474 -496.726977)
			(xy 68.97079 -496.674089) (xy 69.030419 -496.627274) (xy 69.094687 -496.587062) (xy 69.162864 -496.55391)
			(xy 69.23418 -496.528192) (xy 69.307825 -496.5102) (xy 69.382965 -496.500138) (xy 69.458749 -496.498119)
			(xy 69.534319 -496.504168) (xy 69.608817 -496.518215) (xy 69.6814 -496.540101) (xy 69.751246 -496.569578)
			(xy 69.817563 -496.606313) (xy 69.879599 -496.649888) (xy 69.936652 -496.69981) (xy 69.988076 -496.755514)
			(xy 70.033287 -496.816369) (xy 70.071774 -496.881684) (xy 70.1031 -496.95072) (xy 70.12691 -497.022695)
			(xy 70.142935 -497.096793) (xy 70.150994 -497.172174) (xy 70.151498 -497.21008) (xy 71.267577 -497.21008)
			(xy 71.271612 -497.134376) (xy 71.283671 -497.059531) (xy 71.303617 -496.98639) (xy 71.331224 -496.915785)
			(xy 71.36618 -496.848514) (xy 71.408088 -496.785339) (xy 71.456474 -496.726977) (xy 71.51079 -496.674089)
			(xy 71.570419 -496.627274) (xy 71.634687 -496.587062) (xy 71.702864 -496.55391) (xy 71.77418 -496.528192)
			(xy 71.847825 -496.5102) (xy 71.922965 -496.500138) (xy 71.998749 -496.498119) (xy 72.074319 -496.504168)
			(xy 72.148817 -496.518215) (xy 72.2214 -496.540101) (xy 72.291246 -496.569578) (xy 72.357563 -496.606313)
			(xy 72.419599 -496.649888) (xy 72.476652 -496.69981) (xy 72.528076 -496.755514) (xy 72.573287 -496.816369)
			(xy 72.611774 -496.881684) (xy 72.6431 -496.95072) (xy 72.66691 -497.022695) (xy 72.682935 -497.096793)
			(xy 72.690994 -497.172174) (xy 72.691498 -497.21008) (xy 73.807577 -497.21008) (xy 73.811612 -497.134376)
			(xy 73.823671 -497.059531) (xy 73.843617 -496.98639) (xy 73.871224 -496.915785) (xy 73.90618 -496.848514)
			(xy 73.948088 -496.785339) (xy 73.996474 -496.726977) (xy 74.05079 -496.674089) (xy 74.110419 -496.627274)
			(xy 74.174687 -496.587062) (xy 74.242864 -496.55391) (xy 74.31418 -496.528192) (xy 74.387825 -496.5102)
			(xy 74.462965 -496.500138) (xy 74.538749 -496.498119) (xy 74.614319 -496.504168) (xy 74.688817 -496.518215)
			(xy 74.7614 -496.540101) (xy 74.831246 -496.569578) (xy 74.897563 -496.606313) (xy 74.959599 -496.649888)
			(xy 75.016652 -496.69981) (xy 75.068076 -496.755514) (xy 75.113287 -496.816369) (xy 75.151774 -496.881684)
			(xy 75.1831 -496.95072) (xy 75.20691 -497.022695) (xy 75.222935 -497.096793) (xy 75.230994 -497.172174)
			(xy 75.231498 -497.21008) (xy 76.347577 -497.21008) (xy 76.351612 -497.134376) (xy 76.363671 -497.059531)
			(xy 76.383617 -496.98639) (xy 76.411224 -496.915785) (xy 76.44618 -496.848514) (xy 76.488088 -496.785339)
			(xy 76.536474 -496.726977) (xy 76.59079 -496.674089) (xy 76.650419 -496.627274) (xy 76.714687 -496.587062)
			(xy 76.782864 -496.55391) (xy 76.85418 -496.528192) (xy 76.927825 -496.5102) (xy 77.002965 -496.500138)
			(xy 77.078749 -496.498119) (xy 77.154319 -496.504168) (xy 77.228817 -496.518215) (xy 77.3014 -496.540101)
			(xy 77.371246 -496.569578) (xy 77.437563 -496.606313) (xy 77.499599 -496.649888) (xy 77.556652 -496.69981)
			(xy 77.608076 -496.755514) (xy 77.653287 -496.816369) (xy 77.691774 -496.881684) (xy 77.7231 -496.95072)
			(xy 77.74691 -497.022695) (xy 77.762935 -497.096793) (xy 77.770994 -497.172174) (xy 77.771498 -497.21008)
			(xy 78.887577 -497.21008) (xy 78.891612 -497.134376) (xy 78.903671 -497.059531) (xy 78.923617 -496.98639)
			(xy 78.951224 -496.915785) (xy 78.98618 -496.848514) (xy 79.028088 -496.785339) (xy 79.076474 -496.726977)
			(xy 79.13079 -496.674089) (xy 79.190419 -496.627274) (xy 79.254687 -496.587062) (xy 79.322864 -496.55391)
			(xy 79.39418 -496.528192) (xy 79.467825 -496.5102) (xy 79.542965 -496.500138) (xy 79.618749 -496.498119)
			(xy 79.694319 -496.504168) (xy 79.768817 -496.518215) (xy 79.8414 -496.540101) (xy 79.911246 -496.569578)
			(xy 79.977563 -496.606313) (xy 80.039599 -496.649888) (xy 80.096652 -496.69981) (xy 80.148076 -496.755514)
			(xy 80.193287 -496.816369) (xy 80.231774 -496.881684) (xy 80.2631 -496.95072) (xy 80.28691 -497.022695)
			(xy 80.302935 -497.096793) (xy 80.310994 -497.172174) (xy 80.311498 -497.21008) (xy 81.427577 -497.21008)
			(xy 81.431612 -497.134376) (xy 81.443671 -497.059531) (xy 81.463617 -496.98639) (xy 81.491224 -496.915785)
			(xy 81.52618 -496.848514) (xy 81.568088 -496.785339) (xy 81.616474 -496.726977) (xy 81.67079 -496.674089)
			(xy 81.730419 -496.627274) (xy 81.794687 -496.587062) (xy 81.862864 -496.55391) (xy 81.93418 -496.528192)
			(xy 82.007825 -496.5102) (xy 82.082965 -496.500138) (xy 82.158749 -496.498119) (xy 82.234319 -496.504168)
			(xy 82.308817 -496.518215) (xy 82.3814 -496.540101) (xy 82.451246 -496.569578) (xy 82.517563 -496.606313)
			(xy 82.579599 -496.649888) (xy 82.636652 -496.69981) (xy 82.688076 -496.755514) (xy 82.733287 -496.816369)
			(xy 82.771774 -496.881684) (xy 82.8031 -496.95072) (xy 82.82691 -497.022695) (xy 82.842935 -497.096793)
			(xy 82.850994 -497.172174) (xy 82.851498 -497.21008) (xy 82.850994 -497.247986) (xy 82.842935 -497.323367)
			(xy 82.82691 -497.397465) (xy 82.8031 -497.46944) (xy 82.771774 -497.538476) (xy 82.733287 -497.603791)
			(xy 82.688076 -497.664646) (xy 82.636652 -497.72035) (xy 82.579599 -497.770272) (xy 82.517563 -497.813847)
			(xy 82.451246 -497.850582) (xy 82.3814 -497.880059) (xy 82.308817 -497.901945) (xy 82.234319 -497.915992)
			(xy 82.158749 -497.922041) (xy 82.082965 -497.920022) (xy 82.007825 -497.90996) (xy 81.93418 -497.891968)
			(xy 81.862864 -497.86625) (xy 81.794687 -497.833098) (xy 81.730419 -497.792886) (xy 81.67079 -497.746071)
			(xy 81.616474 -497.693183) (xy 81.568088 -497.634821) (xy 81.52618 -497.571646) (xy 81.491224 -497.504375)
			(xy 81.463617 -497.43377) (xy 81.443671 -497.360629) (xy 81.431612 -497.285784) (xy 81.427577 -497.21008)
			(xy 80.311498 -497.21008) (xy 80.310994 -497.247986) (xy 80.302935 -497.323367) (xy 80.28691 -497.397465)
			(xy 80.2631 -497.46944) (xy 80.231774 -497.538476) (xy 80.193287 -497.603791) (xy 80.148076 -497.664646)
			(xy 80.096652 -497.72035) (xy 80.039599 -497.770272) (xy 79.977563 -497.813847) (xy 79.911246 -497.850582)
			(xy 79.8414 -497.880059) (xy 79.768817 -497.901945) (xy 79.694319 -497.915992) (xy 79.618749 -497.922041)
			(xy 79.542965 -497.920022) (xy 79.467825 -497.90996) (xy 79.39418 -497.891968) (xy 79.322864 -497.86625)
			(xy 79.254687 -497.833098) (xy 79.190419 -497.792886) (xy 79.13079 -497.746071) (xy 79.076474 -497.693183)
			(xy 79.028088 -497.634821) (xy 78.98618 -497.571646) (xy 78.951224 -497.504375) (xy 78.923617 -497.43377)
			(xy 78.903671 -497.360629) (xy 78.891612 -497.285784) (xy 78.887577 -497.21008) (xy 77.771498 -497.21008)
			(xy 77.770994 -497.247986) (xy 77.762935 -497.323367) (xy 77.74691 -497.397465) (xy 77.7231 -497.46944)
			(xy 77.691774 -497.538476) (xy 77.653287 -497.603791) (xy 77.608076 -497.664646) (xy 77.556652 -497.72035)
			(xy 77.499599 -497.770272) (xy 77.437563 -497.813847) (xy 77.371246 -497.850582) (xy 77.3014 -497.880059)
			(xy 77.228817 -497.901945) (xy 77.154319 -497.915992) (xy 77.078749 -497.922041) (xy 77.002965 -497.920022)
			(xy 76.927825 -497.90996) (xy 76.85418 -497.891968) (xy 76.782864 -497.86625) (xy 76.714687 -497.833098)
			(xy 76.650419 -497.792886) (xy 76.59079 -497.746071) (xy 76.536474 -497.693183) (xy 76.488088 -497.634821)
			(xy 76.44618 -497.571646) (xy 76.411224 -497.504375) (xy 76.383617 -497.43377) (xy 76.363671 -497.360629)
			(xy 76.351612 -497.285784) (xy 76.347577 -497.21008) (xy 75.231498 -497.21008) (xy 75.230994 -497.247986)
			(xy 75.222935 -497.323367) (xy 75.20691 -497.397465) (xy 75.1831 -497.46944) (xy 75.151774 -497.538476)
			(xy 75.113287 -497.603791) (xy 75.068076 -497.664646) (xy 75.016652 -497.72035) (xy 74.959599 -497.770272)
			(xy 74.897563 -497.813847) (xy 74.831246 -497.850582) (xy 74.7614 -497.880059) (xy 74.688817 -497.901945)
			(xy 74.614319 -497.915992) (xy 74.538749 -497.922041) (xy 74.462965 -497.920022) (xy 74.387825 -497.90996)
			(xy 74.31418 -497.891968) (xy 74.242864 -497.86625) (xy 74.174687 -497.833098) (xy 74.110419 -497.792886)
			(xy 74.05079 -497.746071) (xy 73.996474 -497.693183) (xy 73.948088 -497.634821) (xy 73.90618 -497.571646)
			(xy 73.871224 -497.504375) (xy 73.843617 -497.43377) (xy 73.823671 -497.360629) (xy 73.811612 -497.285784)
			(xy 73.807577 -497.21008) (xy 72.691498 -497.21008) (xy 72.690994 -497.247986) (xy 72.682935 -497.323367)
			(xy 72.66691 -497.397465) (xy 72.6431 -497.46944) (xy 72.611774 -497.538476) (xy 72.573287 -497.603791)
			(xy 72.528076 -497.664646) (xy 72.476652 -497.72035) (xy 72.419599 -497.770272) (xy 72.357563 -497.813847)
			(xy 72.291246 -497.850582) (xy 72.2214 -497.880059) (xy 72.148817 -497.901945) (xy 72.074319 -497.915992)
			(xy 71.998749 -497.922041) (xy 71.922965 -497.920022) (xy 71.847825 -497.90996) (xy 71.77418 -497.891968)
			(xy 71.702864 -497.86625) (xy 71.634687 -497.833098) (xy 71.570419 -497.792886) (xy 71.51079 -497.746071)
			(xy 71.456474 -497.693183) (xy 71.408088 -497.634821) (xy 71.36618 -497.571646) (xy 71.331224 -497.504375)
			(xy 71.303617 -497.43377) (xy 71.283671 -497.360629) (xy 71.271612 -497.285784) (xy 71.267577 -497.21008)
			(xy 70.151498 -497.21008) (xy 70.150994 -497.247986) (xy 70.142935 -497.323367) (xy 70.12691 -497.397465)
			(xy 70.1031 -497.46944) (xy 70.071774 -497.538476) (xy 70.033287 -497.603791) (xy 69.988076 -497.664646)
			(xy 69.936652 -497.72035) (xy 69.879599 -497.770272) (xy 69.817563 -497.813847) (xy 69.751246 -497.850582)
			(xy 69.6814 -497.880059) (xy 69.608817 -497.901945) (xy 69.534319 -497.915992) (xy 69.458749 -497.922041)
			(xy 69.382965 -497.920022) (xy 69.307825 -497.90996) (xy 69.23418 -497.891968) (xy 69.162864 -497.86625)
			(xy 69.094687 -497.833098) (xy 69.030419 -497.792886) (xy 68.97079 -497.746071) (xy 68.916474 -497.693183)
			(xy 68.868088 -497.634821) (xy 68.82618 -497.571646) (xy 68.791224 -497.504375) (xy 68.763617 -497.43377)
			(xy 68.743671 -497.360629) (xy 68.731612 -497.285784) (xy 68.727577 -497.21008) (xy 67.611498 -497.21008)
			(xy 67.610994 -497.247986) (xy 67.602935 -497.323367) (xy 67.58691 -497.397465) (xy 67.5631 -497.46944)
			(xy 67.531774 -497.538476) (xy 67.493287 -497.603791) (xy 67.448076 -497.664646) (xy 67.396652 -497.72035)
			(xy 67.339599 -497.770272) (xy 67.277563 -497.813847) (xy 67.211246 -497.850582) (xy 67.1414 -497.880059)
			(xy 67.068817 -497.901945) (xy 66.994319 -497.915992) (xy 66.918749 -497.922041) (xy 66.842965 -497.920022)
			(xy 66.767825 -497.90996) (xy 66.69418 -497.891968) (xy 66.622864 -497.86625) (xy 66.554687 -497.833098)
			(xy 66.490419 -497.792886) (xy 66.43079 -497.746071) (xy 66.376474 -497.693183) (xy 66.328088 -497.634821)
			(xy 66.28618 -497.571646) (xy 66.251224 -497.504375) (xy 66.223617 -497.43377) (xy 66.203671 -497.360629)
			(xy 66.191612 -497.285784) (xy 66.187577 -497.21008) (xy 65.071498 -497.21008) (xy 65.070994 -497.247986)
			(xy 65.062935 -497.323367) (xy 65.04691 -497.397465) (xy 65.0231 -497.46944) (xy 64.991774 -497.538476)
			(xy 64.953287 -497.603791) (xy 64.908076 -497.664646) (xy 64.856652 -497.72035) (xy 64.799599 -497.770272)
			(xy 64.737563 -497.813847) (xy 64.671246 -497.850582) (xy 64.6014 -497.880059) (xy 64.528817 -497.901945)
			(xy 64.454319 -497.915992) (xy 64.378749 -497.922041) (xy 64.302965 -497.920022) (xy 64.227825 -497.90996)
			(xy 64.15418 -497.891968) (xy 64.082864 -497.86625) (xy 64.014687 -497.833098) (xy 63.950419 -497.792886)
			(xy 63.89079 -497.746071) (xy 63.836474 -497.693183) (xy 63.788088 -497.634821) (xy 63.74618 -497.571646)
			(xy 63.711224 -497.504375) (xy 63.683617 -497.43377) (xy 63.663671 -497.360629) (xy 63.651612 -497.285784)
			(xy 63.647577 -497.21008) (xy 42.500813 -497.21008) (xy 42.479042 -497.226857) (xy 42.381609 -497.291665)
			(xy 42.279905 -497.34954) (xy 42.174422 -497.400202) (xy 42.065671 -497.443404) (xy 41.954179 -497.478939)
			(xy 41.840485 -497.506634) (xy 41.725141 -497.526354) (xy 41.608704 -497.538005) (xy 41.491739 -497.54153)
			(xy 41.374812 -497.536912) (xy 41.258489 -497.524173) (xy 41.143334 -497.503375) (xy 41.029905 -497.474618)
			(xy 40.91875 -497.438042) (xy 40.810407 -497.393825) (xy 40.705403 -497.342179) (xy 40.604244 -497.283356)
			(xy 40.507421 -497.21764) (xy 40.415403 -497.145349) (xy 40.328636 -497.066834) (xy 40.247539 -496.982474)
			(xy 40.172506 -496.892679) (xy 40.103899 -496.797883) (xy 40.042051 -496.698544) (xy 39.987262 -496.595145)
			(xy 39.939796 -496.488186) (xy 39.899884 -496.378185) (xy 39.86772 -496.265674) (xy 39.843457 -496.151199)
			(xy 39.827215 -496.035313) (xy 39.819072 -495.918579) (xy 39.818564 -495.86007) (xy 1.525016 -495.86007)
			(xy 1.525016 -498.042629) (xy 4.852911 -498.042629) (xy 4.852911 -497.956903) (xy 4.860821 -497.871543)
			(xy 4.876573 -497.787276) (xy 4.900033 -497.704823) (xy 4.931001 -497.624886) (xy 4.969212 -497.548147)
			(xy 5.014341 -497.475261) (xy 5.066002 -497.40685) (xy 5.123756 -497.343498) (xy 5.187108 -497.285744)
			(xy 5.255519 -497.234083) (xy 5.328405 -497.188954) (xy 5.405144 -497.150743) (xy 5.485081 -497.119775)
			(xy 5.567534 -497.096315) (xy 5.651801 -497.080563) (xy 5.737161 -497.072653) (xy 5.822887 -497.072653)
			(xy 5.908247 -497.080563) (xy 5.992514 -497.096315) (xy 6.074967 -497.119775) (xy 6.154904 -497.150743)
			(xy 6.231643 -497.188954) (xy 6.304529 -497.234083) (xy 6.37294 -497.285744) (xy 6.436292 -497.343498)
			(xy 6.494046 -497.40685) (xy 6.514067 -497.433362) (xy 29.519874 -497.433362) (xy 29.519874 -497.346462)
			(xy 29.527892 -497.259933) (xy 29.54386 -497.174513) (xy 29.567641 -497.090931) (xy 29.599033 -497.009899)
			(xy 29.637767 -496.93211) (xy 29.683514 -496.858226) (xy 29.735883 -496.788879) (xy 29.794427 -496.724659)
			(xy 29.858647 -496.666115) (xy 29.927994 -496.613746) (xy 30.001878 -496.567999) (xy 30.079667 -496.529265)
			(xy 30.160699 -496.497873) (xy 30.244281 -496.474092) (xy 30.329701 -496.458124) (xy 30.41623 -496.450106)
			(xy 30.50313 -496.450106) (xy 30.589659 -496.458124) (xy 30.675079 -496.474092) (xy 30.758661 -496.497873)
			(xy 30.839693 -496.529265) (xy 30.917482 -496.567999) (xy 30.991366 -496.613746) (xy 31.060713 -496.666115)
			(xy 31.124933 -496.724659) (xy 31.183477 -496.788879) (xy 31.235846 -496.858226) (xy 31.281593 -496.93211)
			(xy 31.320327 -497.009899) (xy 31.351719 -497.090931) (xy 31.3755 -497.174513) (xy 31.391468 -497.259933)
			(xy 31.399486 -497.346462) (xy 31.399988 -497.389912) (xy 31.399486 -497.433362) (xy 34.599874 -497.433362)
			(xy 34.599874 -497.346462) (xy 34.607892 -497.259933) (xy 34.62386 -497.174513) (xy 34.647641 -497.090931)
			(xy 34.679033 -497.009899) (xy 34.717767 -496.93211) (xy 34.763514 -496.858226) (xy 34.815883 -496.788879)
			(xy 34.874427 -496.724659) (xy 34.938647 -496.666115) (xy 35.007994 -496.613746) (xy 35.081878 -496.567999)
			(xy 35.159667 -496.529265) (xy 35.240699 -496.497873) (xy 35.324281 -496.474092) (xy 35.409701 -496.458124)
			(xy 35.49623 -496.450106) (xy 35.58313 -496.450106) (xy 35.669659 -496.458124) (xy 35.755079 -496.474092)
			(xy 35.838661 -496.497873) (xy 35.919693 -496.529265) (xy 35.997482 -496.567999) (xy 36.071366 -496.613746)
			(xy 36.140713 -496.666115) (xy 36.204933 -496.724659) (xy 36.263477 -496.788879) (xy 36.315846 -496.858226)
			(xy 36.361593 -496.93211) (xy 36.400327 -497.009899) (xy 36.431719 -497.090931) (xy 36.4555 -497.174513)
			(xy 36.471468 -497.259933) (xy 36.479486 -497.346462) (xy 36.479988 -497.389912) (xy 36.479486 -497.433362)
			(xy 36.471468 -497.519891) (xy 36.4555 -497.605311) (xy 36.431719 -497.688893) (xy 36.400327 -497.769925)
			(xy 36.361593 -497.847714) (xy 36.315846 -497.921598) (xy 36.263477 -497.990945) (xy 36.204933 -498.055165)
			(xy 36.140713 -498.113709) (xy 36.071366 -498.166078) (xy 35.997482 -498.211825) (xy 35.919693 -498.250559)
			(xy 35.838661 -498.281951) (xy 35.755079 -498.305732) (xy 35.669659 -498.3217) (xy 35.58313 -498.329718)
			(xy 35.49623 -498.329718) (xy 35.409701 -498.3217) (xy 35.324281 -498.305732) (xy 35.240699 -498.281951)
			(xy 35.159667 -498.250559) (xy 35.081878 -498.211825) (xy 35.007994 -498.166078) (xy 34.938647 -498.113709)
			(xy 34.874427 -498.055165) (xy 34.815883 -497.990945) (xy 34.763514 -497.921598) (xy 34.717767 -497.847714)
			(xy 34.679033 -497.769925) (xy 34.647641 -497.688893) (xy 34.62386 -497.605311) (xy 34.607892 -497.519891)
			(xy 34.599874 -497.433362) (xy 31.399486 -497.433362) (xy 31.391468 -497.519891) (xy 31.3755 -497.605311)
			(xy 31.351719 -497.688893) (xy 31.320327 -497.769925) (xy 31.281593 -497.847714) (xy 31.235846 -497.921598)
			(xy 31.183477 -497.990945) (xy 31.124933 -498.055165) (xy 31.060713 -498.113709) (xy 30.991366 -498.166078)
			(xy 30.917482 -498.211825) (xy 30.839693 -498.250559) (xy 30.758661 -498.281951) (xy 30.675079 -498.305732)
			(xy 30.589659 -498.3217) (xy 30.50313 -498.329718) (xy 30.41623 -498.329718) (xy 30.329701 -498.3217)
			(xy 30.244281 -498.305732) (xy 30.160699 -498.281951) (xy 30.079667 -498.250559) (xy 30.001878 -498.211825)
			(xy 29.927994 -498.166078) (xy 29.858647 -498.113709) (xy 29.794427 -498.055165) (xy 29.735883 -497.990945)
			(xy 29.683514 -497.921598) (xy 29.637767 -497.847714) (xy 29.599033 -497.769925) (xy 29.567641 -497.688893)
			(xy 29.54386 -497.605311) (xy 29.527892 -497.519891) (xy 29.519874 -497.433362) (xy 6.514067 -497.433362)
			(xy 6.545707 -497.475261) (xy 6.590836 -497.548147) (xy 6.629047 -497.624886) (xy 6.660015 -497.704823)
			(xy 6.683475 -497.787276) (xy 6.699227 -497.871543) (xy 6.707137 -497.956903) (xy 6.707632 -497.999766)
			(xy 6.707137 -498.042629) (xy 6.699227 -498.127989) (xy 6.683475 -498.212256) (xy 6.660015 -498.294709)
			(xy 6.629047 -498.374646) (xy 6.590836 -498.451385) (xy 6.545707 -498.524271) (xy 6.494046 -498.592682)
			(xy 6.436292 -498.656034) (xy 6.37294 -498.713788) (xy 6.304529 -498.765449) (xy 6.231643 -498.810578)
			(xy 6.154904 -498.848789) (xy 6.074967 -498.879757) (xy 5.992514 -498.903217) (xy 5.908247 -498.918969)
			(xy 5.822887 -498.926879) (xy 5.737161 -498.926879) (xy 5.651801 -498.918969) (xy 5.567534 -498.903217)
			(xy 5.485081 -498.879757) (xy 5.405144 -498.848789) (xy 5.328405 -498.810578) (xy 5.255519 -498.765449)
			(xy 5.187108 -498.713788) (xy 5.123756 -498.656034) (xy 5.066002 -498.592682) (xy 5.014341 -498.524271)
			(xy 4.969212 -498.451385) (xy 4.931001 -498.374646) (xy 4.900033 -498.294709) (xy 4.876573 -498.212256)
			(xy 4.860821 -498.127989) (xy 4.852911 -498.042629) (xy 1.525016 -498.042629) (xy 1.525016 -500.99976)
			(xy 6.671831 -500.99976) (xy 6.675786 -500.907923) (xy 6.687621 -500.816766) (xy 6.707248 -500.726963)
			(xy 6.734522 -500.639181) (xy 6.769242 -500.554067) (xy 6.81115 -500.472254) (xy 6.859936 -500.394346)
			(xy 6.915239 -500.320921) (xy 6.976649 -500.252521) (xy 7.043711 -500.189654) (xy 7.11593 -500.132784)
			(xy 7.19277 -500.082333) (xy 7.273663 -500.038674) (xy 7.358009 -500.002131) (xy 7.445185 -499.972974)
			(xy 7.534544 -499.95142) (xy 7.625425 -499.937626) (xy 7.717156 -499.931696) (xy 7.809057 -499.933674)
			(xy 7.900448 -499.943545) (xy 7.990652 -499.961235) (xy 8.032867 -499.973362) (xy 29.519874 -499.973362)
			(xy 29.519874 -499.886462) (xy 29.527892 -499.799933) (xy 29.54386 -499.714513) (xy 29.567641 -499.630931)
			(xy 29.599033 -499.549899) (xy 29.637767 -499.47211) (xy 29.683514 -499.398226) (xy 29.735883 -499.328879)
			(xy 29.794427 -499.264659) (xy 29.858647 -499.206115) (xy 29.927994 -499.153746) (xy 30.001878 -499.107999)
			(xy 30.079667 -499.069265) (xy 30.160699 -499.037873) (xy 30.244281 -499.014092) (xy 30.329701 -498.998124)
			(xy 30.41623 -498.990106) (xy 30.50313 -498.990106) (xy 30.589659 -498.998124) (xy 30.675079 -499.014092)
			(xy 30.758661 -499.037873) (xy 30.839693 -499.069265) (xy 30.917482 -499.107999) (xy 30.991366 -499.153746)
			(xy 31.060713 -499.206115) (xy 31.124933 -499.264659) (xy 31.183477 -499.328879) (xy 31.235846 -499.398226)
			(xy 31.281593 -499.47211) (xy 31.320327 -499.549899) (xy 31.351719 -499.630931) (xy 31.3755 -499.714513)
			(xy 31.391468 -499.799933) (xy 31.399486 -499.886462) (xy 31.399988 -499.929912) (xy 31.399486 -499.973362)
			(xy 34.599874 -499.973362) (xy 34.599874 -499.886462) (xy 34.607892 -499.799933) (xy 34.62386 -499.714513)
			(xy 34.647641 -499.630931) (xy 34.679033 -499.549899) (xy 34.717767 -499.47211) (xy 34.763514 -499.398226)
			(xy 34.815883 -499.328879) (xy 34.874427 -499.264659) (xy 34.938647 -499.206115) (xy 35.007994 -499.153746)
			(xy 35.081878 -499.107999) (xy 35.159667 -499.069265) (xy 35.240699 -499.037873) (xy 35.324281 -499.014092)
			(xy 35.409701 -498.998124) (xy 35.49623 -498.990106) (xy 35.58313 -498.990106) (xy 35.669659 -498.998124)
			(xy 35.755079 -499.014092) (xy 35.838661 -499.037873) (xy 35.919693 -499.069265) (xy 35.997482 -499.107999)
			(xy 36.071366 -499.153746) (xy 36.140713 -499.206115) (xy 36.204933 -499.264659) (xy 36.263477 -499.328879)
			(xy 36.315846 -499.398226) (xy 36.361593 -499.47211) (xy 36.400327 -499.549899) (xy 36.431719 -499.630931)
			(xy 36.4555 -499.714513) (xy 36.471468 -499.799933) (xy 36.479486 -499.886462) (xy 36.479988 -499.929912)
			(xy 36.479486 -499.973362) (xy 36.471468 -500.059891) (xy 36.4555 -500.145311) (xy 36.431719 -500.228893)
			(xy 36.400327 -500.309925) (xy 36.361593 -500.387714) (xy 36.315846 -500.461598) (xy 36.263477 -500.530945)
			(xy 36.204933 -500.595165) (xy 36.140713 -500.653709) (xy 36.071366 -500.706078) (xy 35.997482 -500.751825)
			(xy 35.919693 -500.790559) (xy 35.838661 -500.821951) (xy 35.755079 -500.845732) (xy 35.669659 -500.8617)
			(xy 35.58313 -500.869718) (xy 35.49623 -500.869718) (xy 35.409701 -500.8617) (xy 35.324281 -500.845732)
			(xy 35.240699 -500.821951) (xy 35.159667 -500.790559) (xy 35.081878 -500.751825) (xy 35.007994 -500.706078)
			(xy 34.938647 -500.653709) (xy 34.874427 -500.595165) (xy 34.815883 -500.530945) (xy 34.763514 -500.461598)
			(xy 34.717767 -500.387714) (xy 34.679033 -500.309925) (xy 34.647641 -500.228893) (xy 34.62386 -500.145311)
			(xy 34.607892 -500.059891) (xy 34.599874 -499.973362) (xy 31.399486 -499.973362) (xy 31.391468 -500.059891)
			(xy 31.3755 -500.145311) (xy 31.351719 -500.228893) (xy 31.320327 -500.309925) (xy 31.281593 -500.387714)
			(xy 31.235846 -500.461598) (xy 31.183477 -500.530945) (xy 31.124933 -500.595165) (xy 31.060713 -500.653709)
			(xy 30.991366 -500.706078) (xy 30.917482 -500.751825) (xy 30.839693 -500.790559) (xy 30.758661 -500.821951)
			(xy 30.675079 -500.845732) (xy 30.589659 -500.8617) (xy 30.50313 -500.869718) (xy 30.41623 -500.869718)
			(xy 30.329701 -500.8617) (xy 30.244281 -500.845732) (xy 30.160699 -500.821951) (xy 30.079667 -500.790559)
			(xy 30.001878 -500.751825) (xy 29.927994 -500.706078) (xy 29.858647 -500.653709) (xy 29.794427 -500.595165)
			(xy 29.735883 -500.530945) (xy 29.683514 -500.461598) (xy 29.637767 -500.387714) (xy 29.599033 -500.309925)
			(xy 29.567641 -500.228893) (xy 29.54386 -500.145311) (xy 29.527892 -500.059891) (xy 29.519874 -499.973362)
			(xy 8.032867 -499.973362) (xy 8.079001 -499.986615) (xy 8.164841 -500.019495) (xy 8.247537 -500.059633)
			(xy 8.326477 -500.106732) (xy 8.401075 -500.160442) (xy 8.470781 -500.220366) (xy 8.535076 -500.28606)
			(xy 8.593487 -500.357038) (xy 8.645579 -500.432775) (xy 8.690968 -500.51271) (xy 8.729318 -500.59625)
			(xy 8.760343 -500.682778) (xy 8.783816 -500.771653) (xy 8.799562 -500.862217) (xy 8.807464 -500.953799)
			(xy 8.807958 -500.99976) (xy 8.807464 -501.045721) (xy 8.799562 -501.137303) (xy 8.783816 -501.227867)
			(xy 8.760343 -501.316742) (xy 8.729318 -501.40327) (xy 8.690968 -501.48681) (xy 8.645579 -501.566745)
			(xy 8.593487 -501.642482) (xy 8.535076 -501.71346) (xy 8.470781 -501.779154) (xy 8.401075 -501.839078)
			(xy 8.326477 -501.892788) (xy 8.247537 -501.939887) (xy 8.164841 -501.980025) (xy 8.079001 -502.012905)
			(xy 7.990652 -502.038285) (xy 7.900448 -502.055975) (xy 7.809057 -502.065846) (xy 7.717156 -502.067824)
			(xy 7.625425 -502.061894) (xy 7.534544 -502.0481) (xy 7.445185 -502.026546) (xy 7.358009 -501.997389)
			(xy 7.273663 -501.960846) (xy 7.19277 -501.917187) (xy 7.11593 -501.866736) (xy 7.043711 -501.809866)
			(xy 6.976649 -501.746999) (xy 6.915239 -501.678599) (xy 6.859936 -501.605174) (xy 6.81115 -501.527266)
			(xy 6.769242 -501.445453) (xy 6.734522 -501.360339) (xy 6.707248 -501.272557) (xy 6.687621 -501.182754)
			(xy 6.675786 -501.091597) (xy 6.671831 -500.99976) (xy 1.525016 -500.99976) (xy 1.525016 -502.513362)
			(xy 29.519874 -502.513362) (xy 29.519874 -502.426462) (xy 29.527892 -502.339933) (xy 29.54386 -502.254513)
			(xy 29.567641 -502.170931) (xy 29.599033 -502.089899) (xy 29.637767 -502.01211) (xy 29.683514 -501.938226)
			(xy 29.735883 -501.868879) (xy 29.794427 -501.804659) (xy 29.858647 -501.746115) (xy 29.927994 -501.693746)
			(xy 30.001878 -501.647999) (xy 30.079667 -501.609265) (xy 30.160699 -501.577873) (xy 30.244281 -501.554092)
			(xy 30.329701 -501.538124) (xy 30.41623 -501.530106) (xy 30.50313 -501.530106) (xy 30.589659 -501.538124)
			(xy 30.675079 -501.554092) (xy 30.758661 -501.577873) (xy 30.839693 -501.609265) (xy 30.917482 -501.647999)
			(xy 30.991366 -501.693746) (xy 31.060713 -501.746115) (xy 31.124933 -501.804659) (xy 31.183477 -501.868879)
			(xy 31.235846 -501.938226) (xy 31.281593 -502.01211) (xy 31.320327 -502.089899) (xy 31.351719 -502.170931)
			(xy 31.3755 -502.254513) (xy 31.391468 -502.339933) (xy 31.399486 -502.426462) (xy 31.399988 -502.469912)
			(xy 31.399486 -502.513362) (xy 34.599874 -502.513362) (xy 34.599874 -502.426462) (xy 34.607892 -502.339933)
			(xy 34.62386 -502.254513) (xy 34.647641 -502.170931) (xy 34.679033 -502.089899) (xy 34.717767 -502.01211)
			(xy 34.763514 -501.938226) (xy 34.815883 -501.868879) (xy 34.874427 -501.804659) (xy 34.938647 -501.746115)
			(xy 35.007994 -501.693746) (xy 35.081878 -501.647999) (xy 35.159667 -501.609265) (xy 35.240699 -501.577873)
			(xy 35.324281 -501.554092) (xy 35.409701 -501.538124) (xy 35.49623 -501.530106) (xy 35.58313 -501.530106)
			(xy 35.669659 -501.538124) (xy 35.755079 -501.554092) (xy 35.838661 -501.577873) (xy 35.919693 -501.609265)
			(xy 35.997482 -501.647999) (xy 36.071366 -501.693746) (xy 36.140713 -501.746115) (xy 36.204933 -501.804659)
			(xy 36.263477 -501.868879) (xy 36.315846 -501.938226) (xy 36.361593 -502.01211) (xy 36.400327 -502.089899)
			(xy 36.431719 -502.170931) (xy 36.4555 -502.254513) (xy 36.471468 -502.339933) (xy 36.479486 -502.426462)
			(xy 36.479988 -502.469912) (xy 36.479486 -502.513362) (xy 36.471468 -502.599891) (xy 36.4555 -502.685311)
			(xy 36.431719 -502.768893) (xy 36.400327 -502.849925) (xy 36.361593 -502.927714) (xy 36.315846 -503.001598)
			(xy 36.263477 -503.070945) (xy 36.204933 -503.135165) (xy 36.140713 -503.193709) (xy 36.071366 -503.246078)
			(xy 35.997482 -503.291825) (xy 35.919693 -503.330559) (xy 35.838661 -503.361951) (xy 35.755079 -503.385732)
			(xy 35.669659 -503.4017) (xy 35.58313 -503.409718) (xy 35.49623 -503.409718) (xy 35.409701 -503.4017)
			(xy 35.324281 -503.385732) (xy 35.240699 -503.361951) (xy 35.159667 -503.330559) (xy 35.081878 -503.291825)
			(xy 35.007994 -503.246078) (xy 34.938647 -503.193709) (xy 34.874427 -503.135165) (xy 34.815883 -503.070945)
			(xy 34.763514 -503.001598) (xy 34.717767 -502.927714) (xy 34.679033 -502.849925) (xy 34.647641 -502.768893)
			(xy 34.62386 -502.685311) (xy 34.607892 -502.599891) (xy 34.599874 -502.513362) (xy 31.399486 -502.513362)
			(xy 31.391468 -502.599891) (xy 31.3755 -502.685311) (xy 31.351719 -502.768893) (xy 31.320327 -502.849925)
			(xy 31.281593 -502.927714) (xy 31.235846 -503.001598) (xy 31.183477 -503.070945) (xy 31.124933 -503.135165)
			(xy 31.060713 -503.193709) (xy 30.991366 -503.246078) (xy 30.917482 -503.291825) (xy 30.839693 -503.330559)
			(xy 30.758661 -503.361951) (xy 30.675079 -503.385732) (xy 30.589659 -503.4017) (xy 30.50313 -503.409718)
			(xy 30.41623 -503.409718) (xy 30.329701 -503.4017) (xy 30.244281 -503.385732) (xy 30.160699 -503.361951)
			(xy 30.079667 -503.330559) (xy 30.001878 -503.291825) (xy 29.927994 -503.246078) (xy 29.858647 -503.193709)
			(xy 29.794427 -503.135165) (xy 29.735883 -503.070945) (xy 29.683514 -503.001598) (xy 29.637767 -502.927714)
			(xy 29.599033 -502.849925) (xy 29.567641 -502.768893) (xy 29.54386 -502.685311) (xy 29.527892 -502.599891)
			(xy 29.519874 -502.513362) (xy 1.525016 -502.513362) (xy 1.525016 -505.053362) (xy 29.519874 -505.053362)
			(xy 29.519874 -504.966462) (xy 29.527892 -504.879933) (xy 29.54386 -504.794513) (xy 29.567641 -504.710931)
			(xy 29.599033 -504.629899) (xy 29.637767 -504.55211) (xy 29.683514 -504.478226) (xy 29.735883 -504.408879)
			(xy 29.794427 -504.344659) (xy 29.858647 -504.286115) (xy 29.927994 -504.233746) (xy 30.001878 -504.187999)
			(xy 30.079667 -504.149265) (xy 30.160699 -504.117873) (xy 30.244281 -504.094092) (xy 30.329701 -504.078124)
			(xy 30.41623 -504.070106) (xy 30.50313 -504.070106) (xy 30.589659 -504.078124) (xy 30.675079 -504.094092)
			(xy 30.758661 -504.117873) (xy 30.839693 -504.149265) (xy 30.917482 -504.187999) (xy 30.991366 -504.233746)
			(xy 31.060713 -504.286115) (xy 31.124933 -504.344659) (xy 31.183477 -504.408879) (xy 31.235846 -504.478226)
			(xy 31.281593 -504.55211) (xy 31.320327 -504.629899) (xy 31.351719 -504.710931) (xy 31.3755 -504.794513)
			(xy 31.391468 -504.879933) (xy 31.399486 -504.966462) (xy 31.399988 -505.009912) (xy 31.399486 -505.053362)
			(xy 34.599874 -505.053362) (xy 34.599874 -504.966462) (xy 34.607892 -504.879933) (xy 34.62386 -504.794513)
			(xy 34.647641 -504.710931) (xy 34.679033 -504.629899) (xy 34.717767 -504.55211) (xy 34.763514 -504.478226)
			(xy 34.815883 -504.408879) (xy 34.874427 -504.344659) (xy 34.938647 -504.286115) (xy 35.007994 -504.233746)
			(xy 35.081878 -504.187999) (xy 35.159667 -504.149265) (xy 35.240699 -504.117873) (xy 35.324281 -504.094092)
			(xy 35.409701 -504.078124) (xy 35.49623 -504.070106) (xy 35.58313 -504.070106) (xy 35.669659 -504.078124)
			(xy 35.755079 -504.094092) (xy 35.838661 -504.117873) (xy 35.919693 -504.149265) (xy 35.997482 -504.187999)
			(xy 36.071366 -504.233746) (xy 36.140713 -504.286115) (xy 36.204933 -504.344659) (xy 36.263477 -504.408879)
			(xy 36.315846 -504.478226) (xy 36.361593 -504.55211) (xy 36.400327 -504.629899) (xy 36.431719 -504.710931)
			(xy 36.4555 -504.794513) (xy 36.471468 -504.879933) (xy 36.479486 -504.966462) (xy 36.479988 -505.009912)
			(xy 36.479486 -505.053362) (xy 36.471468 -505.139891) (xy 36.4555 -505.225311) (xy 36.431719 -505.308893)
			(xy 36.400327 -505.389925) (xy 36.361593 -505.467714) (xy 36.315846 -505.541598) (xy 36.263477 -505.610945)
			(xy 36.204933 -505.675165) (xy 36.140713 -505.733709) (xy 36.071366 -505.786078) (xy 35.997482 -505.831825)
			(xy 35.919693 -505.870559) (xy 35.838661 -505.901951) (xy 35.755079 -505.925732) (xy 35.669659 -505.9417)
			(xy 35.58313 -505.949718) (xy 35.49623 -505.949718) (xy 35.409701 -505.9417) (xy 35.324281 -505.925732)
			(xy 35.240699 -505.901951) (xy 35.159667 -505.870559) (xy 35.081878 -505.831825) (xy 35.007994 -505.786078)
			(xy 34.938647 -505.733709) (xy 34.874427 -505.675165) (xy 34.815883 -505.610945) (xy 34.763514 -505.541598)
			(xy 34.717767 -505.467714) (xy 34.679033 -505.389925) (xy 34.647641 -505.308893) (xy 34.62386 -505.225311)
			(xy 34.607892 -505.139891) (xy 34.599874 -505.053362) (xy 31.399486 -505.053362) (xy 31.391468 -505.139891)
			(xy 31.3755 -505.225311) (xy 31.351719 -505.308893) (xy 31.320327 -505.389925) (xy 31.281593 -505.467714)
			(xy 31.235846 -505.541598) (xy 31.183477 -505.610945) (xy 31.124933 -505.675165) (xy 31.060713 -505.733709)
			(xy 30.991366 -505.786078) (xy 30.917482 -505.831825) (xy 30.839693 -505.870559) (xy 30.758661 -505.901951)
			(xy 30.675079 -505.925732) (xy 30.589659 -505.9417) (xy 30.50313 -505.949718) (xy 30.41623 -505.949718)
			(xy 30.329701 -505.9417) (xy 30.244281 -505.925732) (xy 30.160699 -505.901951) (xy 30.079667 -505.870559)
			(xy 30.001878 -505.831825) (xy 29.927994 -505.786078) (xy 29.858647 -505.733709) (xy 29.794427 -505.675165)
			(xy 29.735883 -505.610945) (xy 29.683514 -505.541598) (xy 29.637767 -505.467714) (xy 29.599033 -505.389925)
			(xy 29.567641 -505.308893) (xy 29.54386 -505.225311) (xy 29.527892 -505.139891) (xy 29.519874 -505.053362)
			(xy 1.525016 -505.053362) (xy 1.525016 -507.593362) (xy 29.519874 -507.593362) (xy 29.519874 -507.506462)
			(xy 29.527892 -507.419933) (xy 29.54386 -507.334513) (xy 29.567641 -507.250931) (xy 29.599033 -507.169899)
			(xy 29.637767 -507.09211) (xy 29.683514 -507.018226) (xy 29.735883 -506.948879) (xy 29.794427 -506.884659)
			(xy 29.858647 -506.826115) (xy 29.927994 -506.773746) (xy 30.001878 -506.727999) (xy 30.079667 -506.689265)
			(xy 30.160699 -506.657873) (xy 30.244281 -506.634092) (xy 30.329701 -506.618124) (xy 30.41623 -506.610106)
			(xy 30.50313 -506.610106) (xy 30.589659 -506.618124) (xy 30.675079 -506.634092) (xy 30.758661 -506.657873)
			(xy 30.839693 -506.689265) (xy 30.917482 -506.727999) (xy 30.991366 -506.773746) (xy 31.060713 -506.826115)
			(xy 31.124933 -506.884659) (xy 31.183477 -506.948879) (xy 31.235846 -507.018226) (xy 31.281593 -507.09211)
			(xy 31.320327 -507.169899) (xy 31.351719 -507.250931) (xy 31.3755 -507.334513) (xy 31.391468 -507.419933)
			(xy 31.399486 -507.506462) (xy 31.399988 -507.549912) (xy 31.399486 -507.593362) (xy 34.599874 -507.593362)
			(xy 34.599874 -507.506462) (xy 34.607892 -507.419933) (xy 34.62386 -507.334513) (xy 34.647641 -507.250931)
			(xy 34.679033 -507.169899) (xy 34.717767 -507.09211) (xy 34.763514 -507.018226) (xy 34.815883 -506.948879)
			(xy 34.874427 -506.884659) (xy 34.938647 -506.826115) (xy 35.007994 -506.773746) (xy 35.081878 -506.727999)
			(xy 35.159667 -506.689265) (xy 35.240699 -506.657873) (xy 35.324281 -506.634092) (xy 35.409701 -506.618124)
			(xy 35.49623 -506.610106) (xy 35.58313 -506.610106) (xy 35.669659 -506.618124) (xy 35.755079 -506.634092)
			(xy 35.838661 -506.657873) (xy 35.919693 -506.689265) (xy 35.997482 -506.727999) (xy 36.071366 -506.773746)
			(xy 36.140713 -506.826115) (xy 36.204933 -506.884659) (xy 36.263477 -506.948879) (xy 36.315846 -507.018226)
			(xy 36.361593 -507.09211) (xy 36.400327 -507.169899) (xy 36.431719 -507.250931) (xy 36.4555 -507.334513)
			(xy 36.471468 -507.419933) (xy 36.479486 -507.506462) (xy 36.479988 -507.549912) (xy 36.479486 -507.593362)
			(xy 36.471468 -507.679891) (xy 36.464349 -507.717975) (xy 47.97424 -507.717975) (xy 47.97424 -507.636865)
			(xy 47.98219 -507.556146) (xy 47.998013 -507.476595) (xy 48.021558 -507.398979) (xy 48.052597 -507.324043)
			(xy 48.090832 -507.252511) (xy 48.135894 -507.185071) (xy 48.187349 -507.122372) (xy 48.244702 -507.065019)
			(xy 48.307401 -507.013564) (xy 48.374841 -506.968502) (xy 48.446373 -506.930267) (xy 48.521309 -506.899228)
			(xy 48.598925 -506.875683) (xy 48.678476 -506.85986) (xy 48.759195 -506.85191) (xy 48.840305 -506.85191)
			(xy 48.921024 -506.85986) (xy 49.000575 -506.875683) (xy 49.078191 -506.899228) (xy 49.153127 -506.930267)
			(xy 49.224659 -506.968502) (xy 49.292099 -507.013564) (xy 49.354798 -507.065019) (xy 49.412151 -507.122372)
			(xy 49.463606 -507.185071) (xy 49.508668 -507.252511) (xy 49.546903 -507.324043) (xy 49.577942 -507.398979)
			(xy 49.601487 -507.476595) (xy 49.61731 -507.556146) (xy 49.62526 -507.636865) (xy 49.625758 -507.67742)
			(xy 49.62526 -507.717975) (xy 51.47436 -507.717975) (xy 51.47436 -507.636865) (xy 51.48231 -507.556146)
			(xy 51.498133 -507.476595) (xy 51.521678 -507.398979) (xy 51.552717 -507.324043) (xy 51.590952 -507.252511)
			(xy 51.636014 -507.185071) (xy 51.687469 -507.122372) (xy 51.744822 -507.065019) (xy 51.807521 -507.013564)
			(xy 51.874961 -506.968502) (xy 51.946493 -506.930267) (xy 52.021429 -506.899228) (xy 52.099045 -506.875683)
			(xy 52.178596 -506.85986) (xy 52.259315 -506.85191) (xy 52.340425 -506.85191) (xy 52.421144 -506.85986)
			(xy 52.500695 -506.875683) (xy 52.578311 -506.899228) (xy 52.653247 -506.930267) (xy 52.724779 -506.968502)
			(xy 52.792219 -507.013564) (xy 52.854918 -507.065019) (xy 52.912271 -507.122372) (xy 52.963726 -507.185071)
			(xy 53.008788 -507.252511) (xy 53.047023 -507.324043) (xy 53.078062 -507.398979) (xy 53.101607 -507.476595)
			(xy 53.11743 -507.556146) (xy 53.12538 -507.636865) (xy 53.125878 -507.67742) (xy 53.12538 -507.717975)
			(xy 53.11743 -507.798694) (xy 53.101607 -507.878245) (xy 53.078062 -507.955861) (xy 53.047023 -508.030797)
			(xy 53.008788 -508.102329) (xy 52.963726 -508.169769) (xy 52.912271 -508.232468) (xy 52.854918 -508.289821)
			(xy 52.792219 -508.341276) (xy 52.724779 -508.386338) (xy 52.653247 -508.424573) (xy 52.578311 -508.455612)
			(xy 52.500695 -508.479157) (xy 52.421144 -508.49498) (xy 52.340425 -508.50293) (xy 52.259315 -508.50293)
			(xy 52.178596 -508.49498) (xy 52.099045 -508.479157) (xy 52.021429 -508.455612) (xy 51.946493 -508.424573)
			(xy 51.874961 -508.386338) (xy 51.807521 -508.341276) (xy 51.744822 -508.289821) (xy 51.687469 -508.232468)
			(xy 51.636014 -508.169769) (xy 51.590952 -508.102329) (xy 51.552717 -508.030797) (xy 51.521678 -507.955861)
			(xy 51.498133 -507.878245) (xy 51.48231 -507.798694) (xy 51.47436 -507.717975) (xy 49.62526 -507.717975)
			(xy 49.61731 -507.798694) (xy 49.601487 -507.878245) (xy 49.577942 -507.955861) (xy 49.546903 -508.030797)
			(xy 49.508668 -508.102329) (xy 49.463606 -508.169769) (xy 49.412151 -508.232468) (xy 49.354798 -508.289821)
			(xy 49.292099 -508.341276) (xy 49.224659 -508.386338) (xy 49.153127 -508.424573) (xy 49.078191 -508.455612)
			(xy 49.000575 -508.479157) (xy 48.921024 -508.49498) (xy 48.840305 -508.50293) (xy 48.759195 -508.50293)
			(xy 48.678476 -508.49498) (xy 48.598925 -508.479157) (xy 48.521309 -508.455612) (xy 48.446373 -508.424573)
			(xy 48.374841 -508.386338) (xy 48.307401 -508.341276) (xy 48.244702 -508.289821) (xy 48.187349 -508.232468)
			(xy 48.135894 -508.169769) (xy 48.090832 -508.102329) (xy 48.052597 -508.030797) (xy 48.021558 -507.955861)
			(xy 47.998013 -507.878245) (xy 47.98219 -507.798694) (xy 47.97424 -507.717975) (xy 36.464349 -507.717975)
			(xy 36.4555 -507.765311) (xy 36.431719 -507.848893) (xy 36.400327 -507.929925) (xy 36.361593 -508.007714)
			(xy 36.315846 -508.081598) (xy 36.263477 -508.150945) (xy 36.204933 -508.215165) (xy 36.140713 -508.273709)
			(xy 36.071366 -508.326078) (xy 35.997482 -508.371825) (xy 35.919693 -508.410559) (xy 35.838661 -508.441951)
			(xy 35.755079 -508.465732) (xy 35.669659 -508.4817) (xy 35.58313 -508.489718) (xy 35.49623 -508.489718)
			(xy 35.409701 -508.4817) (xy 35.324281 -508.465732) (xy 35.240699 -508.441951) (xy 35.159667 -508.410559)
			(xy 35.081878 -508.371825) (xy 35.007994 -508.326078) (xy 34.938647 -508.273709) (xy 34.874427 -508.215165)
			(xy 34.815883 -508.150945) (xy 34.763514 -508.081598) (xy 34.717767 -508.007714) (xy 34.679033 -507.929925)
			(xy 34.647641 -507.848893) (xy 34.62386 -507.765311) (xy 34.607892 -507.679891) (xy 34.599874 -507.593362)
			(xy 31.399486 -507.593362) (xy 31.391468 -507.679891) (xy 31.3755 -507.765311) (xy 31.351719 -507.848893)
			(xy 31.320327 -507.929925) (xy 31.281593 -508.007714) (xy 31.235846 -508.081598) (xy 31.183477 -508.150945)
			(xy 31.124933 -508.215165) (xy 31.060713 -508.273709) (xy 30.991366 -508.326078) (xy 30.917482 -508.371825)
			(xy 30.839693 -508.410559) (xy 30.758661 -508.441951) (xy 30.675079 -508.465732) (xy 30.589659 -508.4817)
			(xy 30.50313 -508.489718) (xy 30.41623 -508.489718) (xy 30.329701 -508.4817) (xy 30.244281 -508.465732)
			(xy 30.160699 -508.441951) (xy 30.079667 -508.410559) (xy 30.001878 -508.371825) (xy 29.927994 -508.326078)
			(xy 29.858647 -508.273709) (xy 29.794427 -508.215165) (xy 29.735883 -508.150945) (xy 29.683514 -508.081598)
			(xy 29.637767 -508.007714) (xy 29.599033 -507.929925) (xy 29.567641 -507.848893) (xy 29.54386 -507.765311)
			(xy 29.527892 -507.679891) (xy 29.519874 -507.593362) (xy 1.525016 -507.593362) (xy 1.525016 -508.96012)
			(xy 86.877404 -508.96012) (xy 86.881424 -508.769469) (xy 86.893478 -508.579156) (xy 86.913544 -508.389521)
			(xy 86.941587 -508.2009) (xy 86.977556 -508.01363) (xy 87.021388 -507.828042) (xy 87.073005 -507.644467)
			(xy 87.132315 -507.463231) (xy 87.199213 -507.284656) (xy 87.273579 -507.109061) (xy 87.355281 -506.936756)
			(xy 87.444175 -506.768049) (xy 87.540101 -506.603239) (xy 87.64289 -506.44262) (xy 87.752359 -506.286477)
			(xy 87.868313 -506.135088) (xy 87.990547 -505.988721) (xy 88.118841 -505.847637) (xy 88.252969 -505.712088)
			(xy 88.392693 -505.582313) (xy 88.537763 -505.458543) (xy 88.687921 -505.341) (xy 88.842902 -505.229891)
			(xy 89.002429 -505.125414) (xy 89.166218 -505.027755) (xy 89.333978 -504.937088) (xy 89.505412 -504.853574)
			(xy 89.680214 -504.777361) (xy 89.858073 -504.708585) (xy 90.038674 -504.647367) (xy 90.221694 -504.593818)
			(xy 90.40681 -504.548032) (xy 90.593691 -504.51009) (xy 90.782006 -504.480061) (xy 90.971419 -504.457996)
			(xy 91.161593 -504.443937) (xy 91.352192 -504.437907) (xy 91.542875 -504.439917) (xy 91.733304 -504.449964)
			(xy 91.92314 -504.46803) (xy 92.112046 -504.494083) (xy 92.299685 -504.528076) (xy 92.485725 -504.569949)
			(xy 92.669834 -504.619628) (xy 92.851685 -504.677024) (xy 93.030955 -504.742035) (xy 93.207325 -504.814546)
			(xy 93.380481 -504.894427) (xy 93.550116 -504.981537) (xy 93.715928 -505.075721) (xy 93.877622 -505.176812)
			(xy 94.03491 -505.284628) (xy 94.187513 -505.39898) (xy 94.335161 -505.519663) (xy 94.477589 -505.646464)
			(xy 94.614545 -505.779155) (xy 94.745786 -505.917503) (xy 94.871078 -506.06126) (xy 94.990198 -506.210171)
			(xy 95.102934 -506.363972) (xy 95.209087 -506.522388) (xy 95.308467 -506.685139) (xy 95.400897 -506.851934)
			(xy 95.486214 -507.022478) (xy 95.564266 -507.196466) (xy 95.634913 -507.373591) (xy 95.698031 -507.553536)
			(xy 95.753507 -507.735982) (xy 95.801242 -507.920605) (xy 95.841152 -508.107075) (xy 95.873165 -508.295063)
			(xy 95.897225 -508.484233) (xy 95.913288 -508.674249) (xy 95.921327 -508.864773) (xy 95.92183 -508.96012)
			(xy 95.921327 -509.055467) (xy 95.913288 -509.245991) (xy 95.897225 -509.436007) (xy 95.873165 -509.625177)
			(xy 95.841152 -509.813165) (xy 95.801242 -509.999635) (xy 95.753507 -510.184258) (xy 95.698031 -510.366704)
			(xy 95.634913 -510.546649) (xy 95.564266 -510.723774) (xy 95.486214 -510.897762) (xy 95.400897 -511.068306)
			(xy 95.308467 -511.235101) (xy 95.209087 -511.397852) (xy 95.102934 -511.556268) (xy 94.990198 -511.710069)
			(xy 94.871078 -511.85898) (xy 94.745786 -512.002737) (xy 94.614545 -512.141085) (xy 94.477589 -512.273776)
			(xy 94.335161 -512.400577) (xy 94.187513 -512.52126) (xy 94.03491 -512.635612) (xy 93.877622 -512.743428)
			(xy 93.715928 -512.844519) (xy 93.550116 -512.938703) (xy 93.380481 -513.025813) (xy 93.207325 -513.105694)
			(xy 93.030955 -513.178205) (xy 92.851685 -513.243216) (xy 92.669834 -513.300612) (xy 92.485725 -513.350291)
			(xy 92.299685 -513.392164) (xy 92.112046 -513.426157) (xy 91.92314 -513.45221) (xy 91.733304 -513.470276)
			(xy 91.542875 -513.480323) (xy 91.352192 -513.482333) (xy 91.161593 -513.476303) (xy 90.971419 -513.462244)
			(xy 90.782006 -513.440179) (xy 90.593691 -513.41015) (xy 90.40681 -513.372208) (xy 90.221694 -513.326422)
			(xy 90.038674 -513.272873) (xy 89.858073 -513.211655) (xy 89.680214 -513.142879) (xy 89.505412 -513.066666)
			(xy 89.333978 -512.983152) (xy 89.166218 -512.892485) (xy 89.002429 -512.794826) (xy 88.842902 -512.690349)
			(xy 88.687921 -512.57924) (xy 88.537763 -512.461697) (xy 88.392693 -512.337927) (xy 88.252969 -512.208152)
			(xy 88.118841 -512.072603) (xy 87.990547 -511.931519) (xy 87.868313 -511.785152) (xy 87.752359 -511.633763)
			(xy 87.64289 -511.47762) (xy 87.540101 -511.317001) (xy 87.444175 -511.152191) (xy 87.355281 -510.983484)
			(xy 87.273579 -510.811179) (xy 87.199213 -510.635584) (xy 87.132315 -510.457009) (xy 87.073005 -510.275773)
			(xy 87.021388 -510.092198) (xy 86.977556 -509.90661) (xy 86.941587 -509.71934) (xy 86.913544 -509.530719)
			(xy 86.893478 -509.341084) (xy 86.881424 -509.150771) (xy 86.877404 -508.96012) (xy 1.525016 -508.96012)
			(xy 1.525016 -511.049778) (xy 6.671831 -511.049778) (xy 6.675786 -510.957941) (xy 6.687621 -510.866784)
			(xy 6.707248 -510.776981) (xy 6.734522 -510.689199) (xy 6.769242 -510.604085) (xy 6.81115 -510.522272)
			(xy 6.859936 -510.444364) (xy 6.915239 -510.370939) (xy 6.976649 -510.302539) (xy 7.043711 -510.239672)
			(xy 7.11593 -510.182802) (xy 7.19277 -510.132351) (xy 7.273663 -510.088692) (xy 7.358009 -510.052149)
			(xy 7.445185 -510.022992) (xy 7.534544 -510.001438) (xy 7.625425 -509.987644) (xy 7.717156 -509.981714)
			(xy 7.809057 -509.983692) (xy 7.900448 -509.993563) (xy 7.990652 -510.011253) (xy 8.079001 -510.036633)
			(xy 8.164841 -510.069513) (xy 8.247537 -510.109651) (xy 8.287278 -510.133362) (xy 29.519874 -510.133362)
			(xy 29.519874 -510.046462) (xy 29.527892 -509.959933) (xy 29.54386 -509.874513) (xy 29.567641 -509.790931)
			(xy 29.599033 -509.709899) (xy 29.637767 -509.63211) (xy 29.683514 -509.558226) (xy 29.735883 -509.488879)
			(xy 29.794427 -509.424659) (xy 29.858647 -509.366115) (xy 29.927994 -509.313746) (xy 30.001878 -509.267999)
			(xy 30.079667 -509.229265) (xy 30.160699 -509.197873) (xy 30.244281 -509.174092) (xy 30.329701 -509.158124)
			(xy 30.41623 -509.150106) (xy 30.50313 -509.150106) (xy 30.589659 -509.158124) (xy 30.675079 -509.174092)
			(xy 30.758661 -509.197873) (xy 30.839693 -509.229265) (xy 30.917482 -509.267999) (xy 30.991366 -509.313746)
			(xy 31.060713 -509.366115) (xy 31.124933 -509.424659) (xy 31.183477 -509.488879) (xy 31.235846 -509.558226)
			(xy 31.281593 -509.63211) (xy 31.320327 -509.709899) (xy 31.351719 -509.790931) (xy 31.3755 -509.874513)
			(xy 31.391468 -509.959933) (xy 31.399486 -510.046462) (xy 31.399988 -510.089912) (xy 31.399486 -510.133362)
			(xy 34.599874 -510.133362) (xy 34.599874 -510.046462) (xy 34.607892 -509.959933) (xy 34.62386 -509.874513)
			(xy 34.647641 -509.790931) (xy 34.679033 -509.709899) (xy 34.717767 -509.63211) (xy 34.763514 -509.558226)
			(xy 34.815883 -509.488879) (xy 34.874427 -509.424659) (xy 34.938647 -509.366115) (xy 35.007994 -509.313746)
			(xy 35.081878 -509.267999) (xy 35.159667 -509.229265) (xy 35.240699 -509.197873) (xy 35.324281 -509.174092)
			(xy 35.409701 -509.158124) (xy 35.49623 -509.150106) (xy 35.58313 -509.150106) (xy 35.669659 -509.158124)
			(xy 35.755079 -509.174092) (xy 35.838661 -509.197873) (xy 35.919693 -509.229265) (xy 35.997482 -509.267999)
			(xy 36.071366 -509.313746) (xy 36.140713 -509.366115) (xy 36.204933 -509.424659) (xy 36.263477 -509.488879)
			(xy 36.315846 -509.558226) (xy 36.361593 -509.63211) (xy 36.400327 -509.709899) (xy 36.431719 -509.790931)
			(xy 36.4555 -509.874513) (xy 36.471468 -509.959933) (xy 36.479486 -510.046462) (xy 36.479988 -510.089912)
			(xy 36.479486 -510.133362) (xy 36.471468 -510.219891) (xy 36.4555 -510.305311) (xy 36.431719 -510.388893)
			(xy 36.400327 -510.469925) (xy 36.361593 -510.547714) (xy 36.315846 -510.621598) (xy 36.263477 -510.690945)
			(xy 36.204933 -510.755165) (xy 36.140713 -510.813709) (xy 36.071366 -510.866078) (xy 35.997482 -510.911825)
			(xy 35.919693 -510.950559) (xy 35.838661 -510.981951) (xy 35.755079 -511.005732) (xy 35.669659 -511.0217)
			(xy 35.58313 -511.029718) (xy 35.49623 -511.029718) (xy 35.409701 -511.0217) (xy 35.324281 -511.005732)
			(xy 35.240699 -510.981951) (xy 35.159667 -510.950559) (xy 35.081878 -510.911825) (xy 35.007994 -510.866078)
			(xy 34.938647 -510.813709) (xy 34.874427 -510.755165) (xy 34.815883 -510.690945) (xy 34.763514 -510.621598)
			(xy 34.717767 -510.547714) (xy 34.679033 -510.469925) (xy 34.647641 -510.388893) (xy 34.62386 -510.305311)
			(xy 34.607892 -510.219891) (xy 34.599874 -510.133362) (xy 31.399486 -510.133362) (xy 31.391468 -510.219891)
			(xy 31.3755 -510.305311) (xy 31.351719 -510.388893) (xy 31.320327 -510.469925) (xy 31.281593 -510.547714)
			(xy 31.235846 -510.621598) (xy 31.183477 -510.690945) (xy 31.124933 -510.755165) (xy 31.060713 -510.813709)
			(xy 30.991366 -510.866078) (xy 30.917482 -510.911825) (xy 30.839693 -510.950559) (xy 30.758661 -510.981951)
			(xy 30.675079 -511.005732) (xy 30.589659 -511.0217) (xy 30.50313 -511.029718) (xy 30.41623 -511.029718)
			(xy 30.329701 -511.0217) (xy 30.244281 -511.005732) (xy 30.160699 -510.981951) (xy 30.079667 -510.950559)
			(xy 30.001878 -510.911825) (xy 29.927994 -510.866078) (xy 29.858647 -510.813709) (xy 29.794427 -510.755165)
			(xy 29.735883 -510.690945) (xy 29.683514 -510.621598) (xy 29.637767 -510.547714) (xy 29.599033 -510.469925)
			(xy 29.567641 -510.388893) (xy 29.54386 -510.305311) (xy 29.527892 -510.219891) (xy 29.519874 -510.133362)
			(xy 8.287278 -510.133362) (xy 8.326477 -510.15675) (xy 8.401075 -510.21046) (xy 8.470781 -510.270384)
			(xy 8.535076 -510.336078) (xy 8.593487 -510.407056) (xy 8.645579 -510.482793) (xy 8.690968 -510.562728)
			(xy 8.729318 -510.646268) (xy 8.760343 -510.732796) (xy 8.783816 -510.821671) (xy 8.799562 -510.912235)
			(xy 8.807464 -511.003817) (xy 8.807958 -511.049778) (xy 8.807464 -511.095739) (xy 8.799562 -511.187321)
			(xy 8.783816 -511.277885) (xy 8.760343 -511.36676) (xy 8.729318 -511.453288) (xy 8.690968 -511.536828)
			(xy 8.645579 -511.616763) (xy 8.593487 -511.6925) (xy 8.535076 -511.763478) (xy 8.470781 -511.829172)
			(xy 8.401075 -511.889096) (xy 8.326477 -511.942806) (xy 8.247537 -511.989905) (xy 8.164841 -512.030043)
			(xy 8.079001 -512.062923) (xy 7.990652 -512.088303) (xy 7.900448 -512.105993) (xy 7.809057 -512.115864)
			(xy 7.717156 -512.117842) (xy 7.625425 -512.111912) (xy 7.534544 -512.098118) (xy 7.445185 -512.076564)
			(xy 7.358009 -512.047407) (xy 7.273663 -512.010864) (xy 7.19277 -511.967205) (xy 7.11593 -511.916754)
			(xy 7.043711 -511.859884) (xy 6.976649 -511.797017) (xy 6.915239 -511.728617) (xy 6.859936 -511.655192)
			(xy 6.81115 -511.577284) (xy 6.769242 -511.495471) (xy 6.734522 -511.410357) (xy 6.707248 -511.322575)
			(xy 6.687621 -511.232772) (xy 6.675786 -511.141615) (xy 6.671831 -511.049778) (xy 1.525016 -511.049778)
			(xy 1.525016 -512.673362) (xy 29.519874 -512.673362) (xy 29.519874 -512.586462) (xy 29.527892 -512.499933)
			(xy 29.54386 -512.414513) (xy 29.567641 -512.330931) (xy 29.599033 -512.249899) (xy 29.637767 -512.17211)
			(xy 29.683514 -512.098226) (xy 29.735883 -512.028879) (xy 29.794427 -511.964659) (xy 29.858647 -511.906115)
			(xy 29.927994 -511.853746) (xy 30.001878 -511.807999) (xy 30.079667 -511.769265) (xy 30.160699 -511.737873)
			(xy 30.244281 -511.714092) (xy 30.329701 -511.698124) (xy 30.41623 -511.690106) (xy 30.50313 -511.690106)
			(xy 30.589659 -511.698124) (xy 30.675079 -511.714092) (xy 30.758661 -511.737873) (xy 30.839693 -511.769265)
			(xy 30.917482 -511.807999) (xy 30.991366 -511.853746) (xy 31.060713 -511.906115) (xy 31.124933 -511.964659)
			(xy 31.183477 -512.028879) (xy 31.235846 -512.098226) (xy 31.281593 -512.17211) (xy 31.320327 -512.249899)
			(xy 31.351719 -512.330931) (xy 31.3755 -512.414513) (xy 31.391468 -512.499933) (xy 31.399486 -512.586462)
			(xy 31.399988 -512.629912) (xy 31.399486 -512.673362) (xy 34.599874 -512.673362) (xy 34.599874 -512.586462)
			(xy 34.607892 -512.499933) (xy 34.62386 -512.414513) (xy 34.647641 -512.330931) (xy 34.679033 -512.249899)
			(xy 34.717767 -512.17211) (xy 34.763514 -512.098226) (xy 34.815883 -512.028879) (xy 34.874427 -511.964659)
			(xy 34.938647 -511.906115) (xy 35.007994 -511.853746) (xy 35.081878 -511.807999) (xy 35.159667 -511.769265)
			(xy 35.240699 -511.737873) (xy 35.324281 -511.714092) (xy 35.409701 -511.698124) (xy 35.49623 -511.690106)
			(xy 35.58313 -511.690106) (xy 35.669659 -511.698124) (xy 35.755079 -511.714092) (xy 35.838661 -511.737873)
			(xy 35.919693 -511.769265) (xy 35.997482 -511.807999) (xy 36.071366 -511.853746) (xy 36.140713 -511.906115)
			(xy 36.204933 -511.964659) (xy 36.263477 -512.028879) (xy 36.315846 -512.098226) (xy 36.361593 -512.17211)
			(xy 36.400327 -512.249899) (xy 36.431719 -512.330931) (xy 36.4555 -512.414513) (xy 36.471468 -512.499933)
			(xy 36.479486 -512.586462) (xy 36.479988 -512.629912) (xy 36.479486 -512.673362) (xy 36.471468 -512.759891)
			(xy 36.4555 -512.845311) (xy 36.431719 -512.928893) (xy 36.400327 -513.009925) (xy 36.361593 -513.087714)
			(xy 36.315846 -513.161598) (xy 36.263477 -513.230945) (xy 36.204933 -513.295165) (xy 36.172085 -513.32511)
			(xy 55.897524 -513.32511) (xy 55.901595 -513.269488) (xy 55.913721 -513.215051) (xy 55.933644 -513.16296)
			(xy 55.96094 -513.114325) (xy 55.995026 -513.070182) (xy 56.035175 -513.031473) (xy 56.080533 -512.999022)
			(xy 56.130133 -512.973521) (xy 56.182917 -512.955514) (xy 56.23776 -512.945384) (xy 56.293494 -512.943347)
			(xy 56.348931 -512.949447) (xy 56.402888 -512.963553) (xy 56.454217 -512.985365) (xy 56.501823 -513.014419)
			(xy 56.544691 -513.050094) (xy 56.581908 -513.091631) (xy 56.612681 -513.138144) (xy 56.636353 -513.188641)
			(xy 56.652421 -513.242048) (xy 56.660541 -513.297224) (xy 56.66105 -513.32511) (xy 57.167524 -513.32511)
			(xy 57.171595 -513.269488) (xy 57.183721 -513.215051) (xy 57.203644 -513.16296) (xy 57.23094 -513.114325)
			(xy 57.265026 -513.070182) (xy 57.305175 -513.031473) (xy 57.350533 -512.999022) (xy 57.400133 -512.973521)
			(xy 57.452917 -512.955514) (xy 57.50776 -512.945384) (xy 57.563494 -512.943347) (xy 57.618931 -512.949447)
			(xy 57.672888 -512.963553) (xy 57.724217 -512.985365) (xy 57.771823 -513.014419) (xy 57.814691 -513.050094)
			(xy 57.851908 -513.091631) (xy 57.882681 -513.138144) (xy 57.906353 -513.188641) (xy 57.922421 -513.242048)
			(xy 57.930541 -513.297224) (xy 57.93105 -513.32511) (xy 58.429396 -513.32511) (xy 58.433467 -513.269488)
			(xy 58.445593 -513.215051) (xy 58.465516 -513.16296) (xy 58.492812 -513.114325) (xy 58.526898 -513.070182)
			(xy 58.567047 -513.031473) (xy 58.612405 -512.999022) (xy 58.662005 -512.973521) (xy 58.714789 -512.955514)
			(xy 58.769632 -512.945384) (xy 58.825366 -512.943347) (xy 58.880803 -512.949447) (xy 58.93476 -512.963553)
			(xy 58.986089 -512.985365) (xy 59.033695 -513.014419) (xy 59.076563 -513.050094) (xy 59.11378 -513.091631)
			(xy 59.144553 -513.138144) (xy 59.168225 -513.188641) (xy 59.184293 -513.242048) (xy 59.192413 -513.297224)
			(xy 59.192922 -513.32511) (xy 59.699396 -513.32511) (xy 59.703467 -513.269488) (xy 59.715593 -513.215051)
			(xy 59.735516 -513.16296) (xy 59.762812 -513.114325) (xy 59.796898 -513.070182) (xy 59.837047 -513.031473)
			(xy 59.882405 -512.999022) (xy 59.932005 -512.973521) (xy 59.984789 -512.955514) (xy 60.039632 -512.945384)
			(xy 60.095366 -512.943347) (xy 60.150803 -512.949447) (xy 60.20476 -512.963553) (xy 60.256089 -512.985365)
			(xy 60.303695 -513.014419) (xy 60.346563 -513.050094) (xy 60.38378 -513.091631) (xy 60.414553 -513.138144)
			(xy 60.438225 -513.188641) (xy 60.454293 -513.242048) (xy 60.462413 -513.297224) (xy 60.462922 -513.32511)
			(xy 61.23381 -513.32511) (xy 61.237881 -513.269488) (xy 61.250007 -513.215051) (xy 61.26993 -513.16296)
			(xy 61.297226 -513.114325) (xy 61.331312 -513.070182) (xy 61.371461 -513.031473) (xy 61.416819 -512.999022)
			(xy 61.466419 -512.973521) (xy 61.519203 -512.955514) (xy 61.574046 -512.945384) (xy 61.62978 -512.943347)
			(xy 61.685217 -512.949447) (xy 61.739174 -512.963553) (xy 61.790503 -512.985365) (xy 61.838109 -513.014419)
			(xy 61.880977 -513.050094) (xy 61.918194 -513.091631) (xy 61.948967 -513.138144) (xy 61.972639 -513.188641)
			(xy 61.988707 -513.242048) (xy 61.996827 -513.297224) (xy 61.997336 -513.32511) (xy 62.50381 -513.32511)
			(xy 62.507881 -513.269488) (xy 62.520007 -513.215051) (xy 62.53993 -513.16296) (xy 62.567226 -513.114325)
			(xy 62.601312 -513.070182) (xy 62.641461 -513.031473) (xy 62.686819 -512.999022) (xy 62.736419 -512.973521)
			(xy 62.789203 -512.955514) (xy 62.844046 -512.945384) (xy 62.89978 -512.943347) (xy 62.955217 -512.949447)
			(xy 63.009174 -512.963553) (xy 63.060503 -512.985365) (xy 63.108109 -513.014419) (xy 63.150977 -513.050094)
			(xy 63.188194 -513.091631) (xy 63.218967 -513.138144) (xy 63.242639 -513.188641) (xy 63.258707 -513.242048)
			(xy 63.266827 -513.297224) (xy 63.267336 -513.32511) (xy 64.47358 -513.32511) (xy 64.477651 -513.269488)
			(xy 64.489777 -513.215051) (xy 64.5097 -513.16296) (xy 64.536996 -513.114325) (xy 64.571082 -513.070182)
			(xy 64.611231 -513.031473) (xy 64.656589 -512.999022) (xy 64.706189 -512.973521) (xy 64.758973 -512.955514)
			(xy 64.813816 -512.945384) (xy 64.86955 -512.943347) (xy 64.924987 -512.949447) (xy 64.978944 -512.963553)
			(xy 65.030273 -512.985365) (xy 65.077879 -513.014419) (xy 65.120747 -513.050094) (xy 65.157964 -513.091631)
			(xy 65.188737 -513.138144) (xy 65.212409 -513.188641) (xy 65.228477 -513.242048) (xy 65.236597 -513.297224)
			(xy 65.237106 -513.32511) (xy 65.74358 -513.32511) (xy 65.747651 -513.269488) (xy 65.759777 -513.215051)
			(xy 65.7797 -513.16296) (xy 65.806996 -513.114325) (xy 65.841082 -513.070182) (xy 65.881231 -513.031473)
			(xy 65.926589 -512.999022) (xy 65.976189 -512.973521) (xy 66.028973 -512.955514) (xy 66.083816 -512.945384)
			(xy 66.13955 -512.943347) (xy 66.194987 -512.949447) (xy 66.248944 -512.963553) (xy 66.300273 -512.985365)
			(xy 66.347879 -513.014419) (xy 66.390747 -513.050094) (xy 66.427964 -513.091631) (xy 66.458737 -513.138144)
			(xy 66.482409 -513.188641) (xy 66.498477 -513.242048) (xy 66.506597 -513.297224) (xy 66.507106 -513.32511)
			(xy 67.465192 -513.32511) (xy 67.469263 -513.269488) (xy 67.481389 -513.215051) (xy 67.501312 -513.16296)
			(xy 67.528608 -513.114325) (xy 67.562694 -513.070182) (xy 67.602843 -513.031473) (xy 67.648201 -512.999022)
			(xy 67.697801 -512.973521) (xy 67.750585 -512.955514) (xy 67.805428 -512.945384) (xy 67.861162 -512.943347)
			(xy 67.916599 -512.949447) (xy 67.970556 -512.963553) (xy 68.021885 -512.985365) (xy 68.069491 -513.014419)
			(xy 68.112359 -513.050094) (xy 68.149576 -513.091631) (xy 68.180349 -513.138144) (xy 68.204021 -513.188641)
			(xy 68.220089 -513.242048) (xy 68.228209 -513.297224) (xy 68.228718 -513.32511) (xy 68.735192 -513.32511)
			(xy 68.739263 -513.269488) (xy 68.751389 -513.215051) (xy 68.771312 -513.16296) (xy 68.798608 -513.114325)
			(xy 68.832694 -513.070182) (xy 68.872843 -513.031473) (xy 68.918201 -512.999022) (xy 68.967801 -512.973521)
			(xy 69.020585 -512.955514) (xy 69.075428 -512.945384) (xy 69.131162 -512.943347) (xy 69.186599 -512.949447)
			(xy 69.240556 -512.963553) (xy 69.291885 -512.985365) (xy 69.339491 -513.014419) (xy 69.382359 -513.050094)
			(xy 69.419576 -513.091631) (xy 69.450349 -513.138144) (xy 69.474021 -513.188641) (xy 69.490089 -513.242048)
			(xy 69.498209 -513.297224) (xy 69.498718 -513.32511) (xy 69.498209 -513.352996) (xy 69.490089 -513.408172)
			(xy 69.474021 -513.461579) (xy 69.450349 -513.512076) (xy 69.419576 -513.558589) (xy 69.382359 -513.600126)
			(xy 69.339491 -513.635801) (xy 69.291885 -513.664855) (xy 69.240556 -513.686667) (xy 69.186599 -513.700773)
			(xy 69.131162 -513.706873) (xy 69.075428 -513.704836) (xy 69.020585 -513.694706) (xy 68.967801 -513.676699)
			(xy 68.918201 -513.651198) (xy 68.872843 -513.618747) (xy 68.832694 -513.580038) (xy 68.798608 -513.535895)
			(xy 68.771312 -513.48726) (xy 68.751389 -513.435169) (xy 68.739263 -513.380732) (xy 68.735192 -513.32511)
			(xy 68.228718 -513.32511) (xy 68.228209 -513.352996) (xy 68.220089 -513.408172) (xy 68.204021 -513.461579)
			(xy 68.180349 -513.512076) (xy 68.149576 -513.558589) (xy 68.112359 -513.600126) (xy 68.069491 -513.635801)
			(xy 68.021885 -513.664855) (xy 67.970556 -513.686667) (xy 67.916599 -513.700773) (xy 67.861162 -513.706873)
			(xy 67.805428 -513.704836) (xy 67.750585 -513.694706) (xy 67.697801 -513.676699) (xy 67.648201 -513.651198)
			(xy 67.602843 -513.618747) (xy 67.562694 -513.580038) (xy 67.528608 -513.535895) (xy 67.501312 -513.48726)
			(xy 67.481389 -513.435169) (xy 67.469263 -513.380732) (xy 67.465192 -513.32511) (xy 66.507106 -513.32511)
			(xy 66.506597 -513.352996) (xy 66.498477 -513.408172) (xy 66.482409 -513.461579) (xy 66.458737 -513.512076)
			(xy 66.427964 -513.558589) (xy 66.390747 -513.600126) (xy 66.347879 -513.635801) (xy 66.300273 -513.664855)
			(xy 66.248944 -513.686667) (xy 66.194987 -513.700773) (xy 66.13955 -513.706873) (xy 66.083816 -513.704836)
			(xy 66.028973 -513.694706) (xy 65.976189 -513.676699) (xy 65.926589 -513.651198) (xy 65.881231 -513.618747)
			(xy 65.841082 -513.580038) (xy 65.806996 -513.535895) (xy 65.7797 -513.48726) (xy 65.759777 -513.435169)
			(xy 65.747651 -513.380732) (xy 65.74358 -513.32511) (xy 65.237106 -513.32511) (xy 65.236597 -513.352996)
			(xy 65.228477 -513.408172) (xy 65.212409 -513.461579) (xy 65.188737 -513.512076) (xy 65.157964 -513.558589)
			(xy 65.120747 -513.600126) (xy 65.077879 -513.635801) (xy 65.030273 -513.664855) (xy 64.978944 -513.686667)
			(xy 64.924987 -513.700773) (xy 64.86955 -513.706873) (xy 64.813816 -513.704836) (xy 64.758973 -513.694706)
			(xy 64.706189 -513.676699) (xy 64.656589 -513.651198) (xy 64.611231 -513.618747) (xy 64.571082 -513.580038)
			(xy 64.536996 -513.535895) (xy 64.5097 -513.48726) (xy 64.489777 -513.435169) (xy 64.477651 -513.380732)
			(xy 64.47358 -513.32511) (xy 63.267336 -513.32511) (xy 63.266827 -513.352996) (xy 63.258707 -513.408172)
			(xy 63.242639 -513.461579) (xy 63.218967 -513.512076) (xy 63.188194 -513.558589) (xy 63.150977 -513.600126)
			(xy 63.108109 -513.635801) (xy 63.060503 -513.664855) (xy 63.009174 -513.686667) (xy 62.955217 -513.700773)
			(xy 62.89978 -513.706873) (xy 62.844046 -513.704836) (xy 62.789203 -513.694706) (xy 62.736419 -513.676699)
			(xy 62.686819 -513.651198) (xy 62.641461 -513.618747) (xy 62.601312 -513.580038) (xy 62.567226 -513.535895)
			(xy 62.53993 -513.48726) (xy 62.520007 -513.435169) (xy 62.507881 -513.380732) (xy 62.50381 -513.32511)
			(xy 61.997336 -513.32511) (xy 61.996827 -513.352996) (xy 61.988707 -513.408172) (xy 61.972639 -513.461579)
			(xy 61.948967 -513.512076) (xy 61.918194 -513.558589) (xy 61.880977 -513.600126) (xy 61.838109 -513.635801)
			(xy 61.790503 -513.664855) (xy 61.739174 -513.686667) (xy 61.685217 -513.700773) (xy 61.62978 -513.706873)
			(xy 61.574046 -513.704836) (xy 61.519203 -513.694706) (xy 61.466419 -513.676699) (xy 61.416819 -513.651198)
			(xy 61.371461 -513.618747) (xy 61.331312 -513.580038) (xy 61.297226 -513.535895) (xy 61.26993 -513.48726)
			(xy 61.250007 -513.435169) (xy 61.237881 -513.380732) (xy 61.23381 -513.32511) (xy 60.462922 -513.32511)
			(xy 60.462413 -513.352996) (xy 60.454293 -513.408172) (xy 60.438225 -513.461579) (xy 60.414553 -513.512076)
			(xy 60.38378 -513.558589) (xy 60.346563 -513.600126) (xy 60.303695 -513.635801) (xy 60.256089 -513.664855)
			(xy 60.20476 -513.686667) (xy 60.150803 -513.700773) (xy 60.095366 -513.706873) (xy 60.039632 -513.704836)
			(xy 59.984789 -513.694706) (xy 59.932005 -513.676699) (xy 59.882405 -513.651198) (xy 59.837047 -513.618747)
			(xy 59.796898 -513.580038) (xy 59.762812 -513.535895) (xy 59.735516 -513.48726) (xy 59.715593 -513.435169)
			(xy 59.703467 -513.380732) (xy 59.699396 -513.32511) (xy 59.192922 -513.32511) (xy 59.192413 -513.352996)
			(xy 59.184293 -513.408172) (xy 59.168225 -513.461579) (xy 59.144553 -513.512076) (xy 59.11378 -513.558589)
			(xy 59.076563 -513.600126) (xy 59.033695 -513.635801) (xy 58.986089 -513.664855) (xy 58.93476 -513.686667)
			(xy 58.880803 -513.700773) (xy 58.825366 -513.706873) (xy 58.769632 -513.704836) (xy 58.714789 -513.694706)
			(xy 58.662005 -513.676699) (xy 58.612405 -513.651198) (xy 58.567047 -513.618747) (xy 58.526898 -513.580038)
			(xy 58.492812 -513.535895) (xy 58.465516 -513.48726) (xy 58.445593 -513.435169) (xy 58.433467 -513.380732)
			(xy 58.429396 -513.32511) (xy 57.93105 -513.32511) (xy 57.930541 -513.352996) (xy 57.922421 -513.408172)
			(xy 57.906353 -513.461579) (xy 57.882681 -513.512076) (xy 57.851908 -513.558589) (xy 57.814691 -513.600126)
			(xy 57.771823 -513.635801) (xy 57.724217 -513.664855) (xy 57.672888 -513.686667) (xy 57.618931 -513.700773)
			(xy 57.563494 -513.706873) (xy 57.50776 -513.704836) (xy 57.452917 -513.694706) (xy 57.400133 -513.676699)
			(xy 57.350533 -513.651198) (xy 57.305175 -513.618747) (xy 57.265026 -513.580038) (xy 57.23094 -513.535895)
			(xy 57.203644 -513.48726) (xy 57.183721 -513.435169) (xy 57.171595 -513.380732) (xy 57.167524 -513.32511)
			(xy 56.66105 -513.32511) (xy 56.660541 -513.352996) (xy 56.652421 -513.408172) (xy 56.636353 -513.461579)
			(xy 56.612681 -513.512076) (xy 56.581908 -513.558589) (xy 56.544691 -513.600126) (xy 56.501823 -513.635801)
			(xy 56.454217 -513.664855) (xy 56.402888 -513.686667) (xy 56.348931 -513.700773) (xy 56.293494 -513.706873)
			(xy 56.23776 -513.704836) (xy 56.182917 -513.694706) (xy 56.130133 -513.676699) (xy 56.080533 -513.651198)
			(xy 56.035175 -513.618747) (xy 55.995026 -513.580038) (xy 55.96094 -513.535895) (xy 55.933644 -513.48726)
			(xy 55.913721 -513.435169) (xy 55.901595 -513.380732) (xy 55.897524 -513.32511) (xy 36.172085 -513.32511)
			(xy 36.140713 -513.353709) (xy 36.071366 -513.406078) (xy 35.997482 -513.451825) (xy 35.919693 -513.490559)
			(xy 35.838661 -513.521951) (xy 35.755079 -513.545732) (xy 35.669659 -513.5617) (xy 35.58313 -513.569718)
			(xy 35.49623 -513.569718) (xy 35.409701 -513.5617) (xy 35.324281 -513.545732) (xy 35.240699 -513.521951)
			(xy 35.159667 -513.490559) (xy 35.081878 -513.451825) (xy 35.007994 -513.406078) (xy 34.938647 -513.353709)
			(xy 34.874427 -513.295165) (xy 34.815883 -513.230945) (xy 34.763514 -513.161598) (xy 34.717767 -513.087714)
			(xy 34.679033 -513.009925) (xy 34.647641 -512.928893) (xy 34.62386 -512.845311) (xy 34.607892 -512.759891)
			(xy 34.599874 -512.673362) (xy 31.399486 -512.673362) (xy 31.391468 -512.759891) (xy 31.3755 -512.845311)
			(xy 31.351719 -512.928893) (xy 31.320327 -513.009925) (xy 31.281593 -513.087714) (xy 31.235846 -513.161598)
			(xy 31.183477 -513.230945) (xy 31.124933 -513.295165) (xy 31.060713 -513.353709) (xy 30.991366 -513.406078)
			(xy 30.917482 -513.451825) (xy 30.839693 -513.490559) (xy 30.758661 -513.521951) (xy 30.675079 -513.545732)
			(xy 30.589659 -513.5617) (xy 30.50313 -513.569718) (xy 30.41623 -513.569718) (xy 30.329701 -513.5617)
			(xy 30.244281 -513.545732) (xy 30.160699 -513.521951) (xy 30.079667 -513.490559) (xy 30.001878 -513.451825)
			(xy 29.927994 -513.406078) (xy 29.858647 -513.353709) (xy 29.794427 -513.295165) (xy 29.735883 -513.230945)
			(xy 29.683514 -513.161598) (xy 29.637767 -513.087714) (xy 29.599033 -513.009925) (xy 29.567641 -512.928893)
			(xy 29.54386 -512.845311) (xy 29.527892 -512.759891) (xy 29.519874 -512.673362) (xy 1.525016 -512.673362)
			(xy 1.525016 -515.213362) (xy 29.519874 -515.213362) (xy 29.519874 -515.126462) (xy 29.527892 -515.039933)
			(xy 29.54386 -514.954513) (xy 29.567641 -514.870931) (xy 29.599033 -514.789899) (xy 29.637767 -514.71211)
			(xy 29.683514 -514.638226) (xy 29.735883 -514.568879) (xy 29.794427 -514.504659) (xy 29.858647 -514.446115)
			(xy 29.927994 -514.393746) (xy 30.001878 -514.347999) (xy 30.079667 -514.309265) (xy 30.160699 -514.277873)
			(xy 30.244281 -514.254092) (xy 30.329701 -514.238124) (xy 30.41623 -514.230106) (xy 30.50313 -514.230106)
			(xy 30.589659 -514.238124) (xy 30.675079 -514.254092) (xy 30.758661 -514.277873) (xy 30.839693 -514.309265)
			(xy 30.917482 -514.347999) (xy 30.991366 -514.393746) (xy 31.060713 -514.446115) (xy 31.124933 -514.504659)
			(xy 31.183477 -514.568879) (xy 31.235846 -514.638226) (xy 31.281593 -514.71211) (xy 31.320327 -514.789899)
			(xy 31.351719 -514.870931) (xy 31.3755 -514.954513) (xy 31.391468 -515.039933) (xy 31.399486 -515.126462)
			(xy 31.399988 -515.169912) (xy 31.399486 -515.213362) (xy 34.599874 -515.213362) (xy 34.599874 -515.126462)
			(xy 34.607892 -515.039933) (xy 34.62386 -514.954513) (xy 34.647641 -514.870931) (xy 34.679033 -514.789899)
			(xy 34.717767 -514.71211) (xy 34.763514 -514.638226) (xy 34.815883 -514.568879) (xy 34.874427 -514.504659)
			(xy 34.938647 -514.446115) (xy 35.007994 -514.393746) (xy 35.081878 -514.347999) (xy 35.159667 -514.309265)
			(xy 35.240699 -514.277873) (xy 35.324281 -514.254092) (xy 35.409701 -514.238124) (xy 35.49623 -514.230106)
			(xy 35.58313 -514.230106) (xy 35.669659 -514.238124) (xy 35.755079 -514.254092) (xy 35.838661 -514.277873)
			(xy 35.919693 -514.309265) (xy 35.997482 -514.347999) (xy 36.071366 -514.393746) (xy 36.140713 -514.446115)
			(xy 36.204933 -514.504659) (xy 36.263477 -514.568879) (xy 36.315846 -514.638226) (xy 36.361593 -514.71211)
			(xy 36.400327 -514.789899) (xy 36.431719 -514.870931) (xy 36.4555 -514.954513) (xy 36.471468 -515.039933)
			(xy 36.479486 -515.126462) (xy 36.479988 -515.169912) (xy 36.479486 -515.213362) (xy 36.471468 -515.299891)
			(xy 36.4555 -515.385311) (xy 36.431719 -515.468893) (xy 36.400327 -515.549925) (xy 36.361593 -515.627714)
			(xy 36.315846 -515.701598) (xy 36.263477 -515.770945) (xy 36.204933 -515.835165) (xy 36.140713 -515.893709)
			(xy 36.071366 -515.946078) (xy 35.997482 -515.991825) (xy 35.989258 -515.99592) (xy 55.897524 -515.99592)
			(xy 55.901595 -515.940298) (xy 55.913721 -515.885861) (xy 55.933644 -515.83377) (xy 55.96094 -515.785135)
			(xy 55.995026 -515.740992) (xy 56.035175 -515.702283) (xy 56.080533 -515.669832) (xy 56.130133 -515.644331)
			(xy 56.182917 -515.626324) (xy 56.23776 -515.616194) (xy 56.293494 -515.614157) (xy 56.348931 -515.620257)
			(xy 56.402888 -515.634363) (xy 56.454217 -515.656175) (xy 56.501823 -515.685229) (xy 56.544691 -515.720904)
			(xy 56.581908 -515.762441) (xy 56.612681 -515.808954) (xy 56.636353 -515.859451) (xy 56.652421 -515.912858)
			(xy 56.660541 -515.968034) (xy 56.66105 -515.99592) (xy 57.167524 -515.99592) (xy 57.171595 -515.940298)
			(xy 57.183721 -515.885861) (xy 57.203644 -515.83377) (xy 57.23094 -515.785135) (xy 57.265026 -515.740992)
			(xy 57.305175 -515.702283) (xy 57.350533 -515.669832) (xy 57.400133 -515.644331) (xy 57.452917 -515.626324)
			(xy 57.50776 -515.616194) (xy 57.563494 -515.614157) (xy 57.618931 -515.620257) (xy 57.672888 -515.634363)
			(xy 57.724217 -515.656175) (xy 57.771823 -515.685229) (xy 57.814691 -515.720904) (xy 57.851908 -515.762441)
			(xy 57.882681 -515.808954) (xy 57.906353 -515.859451) (xy 57.922421 -515.912858) (xy 57.930541 -515.968034)
			(xy 57.93105 -515.99592) (xy 58.429396 -515.99592) (xy 58.433467 -515.940298) (xy 58.445593 -515.885861)
			(xy 58.465516 -515.83377) (xy 58.492812 -515.785135) (xy 58.526898 -515.740992) (xy 58.567047 -515.702283)
			(xy 58.612405 -515.669832) (xy 58.662005 -515.644331) (xy 58.714789 -515.626324) (xy 58.769632 -515.616194)
			(xy 58.825366 -515.614157) (xy 58.880803 -515.620257) (xy 58.93476 -515.634363) (xy 58.986089 -515.656175)
			(xy 59.033695 -515.685229) (xy 59.076563 -515.720904) (xy 59.11378 -515.762441) (xy 59.144553 -515.808954)
			(xy 59.168225 -515.859451) (xy 59.184293 -515.912858) (xy 59.192413 -515.968034) (xy 59.192922 -515.99592)
			(xy 59.699396 -515.99592) (xy 59.703467 -515.940298) (xy 59.715593 -515.885861) (xy 59.735516 -515.83377)
			(xy 59.762812 -515.785135) (xy 59.796898 -515.740992) (xy 59.837047 -515.702283) (xy 59.882405 -515.669832)
			(xy 59.932005 -515.644331) (xy 59.984789 -515.626324) (xy 60.039632 -515.616194) (xy 60.095366 -515.614157)
			(xy 60.150803 -515.620257) (xy 60.20476 -515.634363) (xy 60.256089 -515.656175) (xy 60.303695 -515.685229)
			(xy 60.346563 -515.720904) (xy 60.38378 -515.762441) (xy 60.414553 -515.808954) (xy 60.438225 -515.859451)
			(xy 60.454293 -515.912858) (xy 60.462413 -515.968034) (xy 60.462922 -515.99592) (xy 61.23381 -515.99592)
			(xy 61.237881 -515.940298) (xy 61.250007 -515.885861) (xy 61.26993 -515.83377) (xy 61.297226 -515.785135)
			(xy 61.331312 -515.740992) (xy 61.371461 -515.702283) (xy 61.416819 -515.669832) (xy 61.466419 -515.644331)
			(xy 61.519203 -515.626324) (xy 61.574046 -515.616194) (xy 61.62978 -515.614157) (xy 61.685217 -515.620257)
			(xy 61.739174 -515.634363) (xy 61.790503 -515.656175) (xy 61.838109 -515.685229) (xy 61.880977 -515.720904)
			(xy 61.918194 -515.762441) (xy 61.948967 -515.808954) (xy 61.972639 -515.859451) (xy 61.988707 -515.912858)
			(xy 61.996827 -515.968034) (xy 61.997336 -515.99592) (xy 62.50381 -515.99592) (xy 62.507881 -515.940298)
			(xy 62.520007 -515.885861) (xy 62.53993 -515.83377) (xy 62.567226 -515.785135) (xy 62.601312 -515.740992)
			(xy 62.641461 -515.702283) (xy 62.686819 -515.669832) (xy 62.736419 -515.644331) (xy 62.789203 -515.626324)
			(xy 62.844046 -515.616194) (xy 62.89978 -515.614157) (xy 62.955217 -515.620257) (xy 63.009174 -515.634363)
			(xy 63.060503 -515.656175) (xy 63.108109 -515.685229) (xy 63.150977 -515.720904) (xy 63.188194 -515.762441)
			(xy 63.218967 -515.808954) (xy 63.242639 -515.859451) (xy 63.258707 -515.912858) (xy 63.266827 -515.968034)
			(xy 63.267336 -515.99592) (xy 64.47358 -515.99592) (xy 64.477651 -515.940298) (xy 64.489777 -515.885861)
			(xy 64.5097 -515.83377) (xy 64.536996 -515.785135) (xy 64.571082 -515.740992) (xy 64.611231 -515.702283)
			(xy 64.656589 -515.669832) (xy 64.706189 -515.644331) (xy 64.758973 -515.626324) (xy 64.813816 -515.616194)
			(xy 64.86955 -515.614157) (xy 64.924987 -515.620257) (xy 64.978944 -515.634363) (xy 65.030273 -515.656175)
			(xy 65.077879 -515.685229) (xy 65.120747 -515.720904) (xy 65.157964 -515.762441) (xy 65.188737 -515.808954)
			(xy 65.212409 -515.859451) (xy 65.228477 -515.912858) (xy 65.236597 -515.968034) (xy 65.237106 -515.99592)
			(xy 65.74358 -515.99592) (xy 65.747651 -515.940298) (xy 65.759777 -515.885861) (xy 65.7797 -515.83377)
			(xy 65.806996 -515.785135) (xy 65.841082 -515.740992) (xy 65.881231 -515.702283) (xy 65.926589 -515.669832)
			(xy 65.976189 -515.644331) (xy 66.028973 -515.626324) (xy 66.083816 -515.616194) (xy 66.13955 -515.614157)
			(xy 66.194987 -515.620257) (xy 66.248944 -515.634363) (xy 66.300273 -515.656175) (xy 66.347879 -515.685229)
			(xy 66.390747 -515.720904) (xy 66.427964 -515.762441) (xy 66.458737 -515.808954) (xy 66.482409 -515.859451)
			(xy 66.498477 -515.912858) (xy 66.506597 -515.968034) (xy 66.507106 -515.99592) (xy 67.465192 -515.99592)
			(xy 67.469263 -515.940298) (xy 67.481389 -515.885861) (xy 67.501312 -515.83377) (xy 67.528608 -515.785135)
			(xy 67.562694 -515.740992) (xy 67.602843 -515.702283) (xy 67.648201 -515.669832) (xy 67.697801 -515.644331)
			(xy 67.750585 -515.626324) (xy 67.805428 -515.616194) (xy 67.861162 -515.614157) (xy 67.916599 -515.620257)
			(xy 67.970556 -515.634363) (xy 68.021885 -515.656175) (xy 68.069491 -515.685229) (xy 68.112359 -515.720904)
			(xy 68.149576 -515.762441) (xy 68.180349 -515.808954) (xy 68.204021 -515.859451) (xy 68.220089 -515.912858)
			(xy 68.228209 -515.968034) (xy 68.228718 -515.99592) (xy 68.735192 -515.99592) (xy 68.739263 -515.940298)
			(xy 68.751389 -515.885861) (xy 68.771312 -515.83377) (xy 68.798608 -515.785135) (xy 68.832694 -515.740992)
			(xy 68.872843 -515.702283) (xy 68.918201 -515.669832) (xy 68.967801 -515.644331) (xy 69.020585 -515.626324)
			(xy 69.075428 -515.616194) (xy 69.131162 -515.614157) (xy 69.186599 -515.620257) (xy 69.240556 -515.634363)
			(xy 69.291885 -515.656175) (xy 69.339491 -515.685229) (xy 69.382359 -515.720904) (xy 69.419576 -515.762441)
			(xy 69.450349 -515.808954) (xy 69.474021 -515.859451) (xy 69.490089 -515.912858) (xy 69.498209 -515.968034)
			(xy 69.498718 -515.99592) (xy 69.498209 -516.023806) (xy 69.490089 -516.078982) (xy 69.474021 -516.132389)
			(xy 69.450349 -516.182886) (xy 69.419576 -516.229399) (xy 69.382359 -516.270936) (xy 69.339491 -516.306611)
			(xy 69.291885 -516.335665) (xy 69.240556 -516.357477) (xy 69.186599 -516.371583) (xy 69.131162 -516.377683)
			(xy 69.075428 -516.375646) (xy 69.020585 -516.365516) (xy 68.967801 -516.347509) (xy 68.918201 -516.322008)
			(xy 68.872843 -516.289557) (xy 68.832694 -516.250848) (xy 68.798608 -516.206705) (xy 68.771312 -516.15807)
			(xy 68.751389 -516.105979) (xy 68.739263 -516.051542) (xy 68.735192 -515.99592) (xy 68.228718 -515.99592)
			(xy 68.228209 -516.023806) (xy 68.220089 -516.078982) (xy 68.204021 -516.132389) (xy 68.180349 -516.182886)
			(xy 68.149576 -516.229399) (xy 68.112359 -516.270936) (xy 68.069491 -516.306611) (xy 68.021885 -516.335665)
			(xy 67.970556 -516.357477) (xy 67.916599 -516.371583) (xy 67.861162 -516.377683) (xy 67.805428 -516.375646)
			(xy 67.750585 -516.365516) (xy 67.697801 -516.347509) (xy 67.648201 -516.322008) (xy 67.602843 -516.289557)
			(xy 67.562694 -516.250848) (xy 67.528608 -516.206705) (xy 67.501312 -516.15807) (xy 67.481389 -516.105979)
			(xy 67.469263 -516.051542) (xy 67.465192 -515.99592) (xy 66.507106 -515.99592) (xy 66.506597 -516.023806)
			(xy 66.498477 -516.078982) (xy 66.482409 -516.132389) (xy 66.458737 -516.182886) (xy 66.427964 -516.229399)
			(xy 66.390747 -516.270936) (xy 66.347879 -516.306611) (xy 66.300273 -516.335665) (xy 66.248944 -516.357477)
			(xy 66.194987 -516.371583) (xy 66.13955 -516.377683) (xy 66.083816 -516.375646) (xy 66.028973 -516.365516)
			(xy 65.976189 -516.347509) (xy 65.926589 -516.322008) (xy 65.881231 -516.289557) (xy 65.841082 -516.250848)
			(xy 65.806996 -516.206705) (xy 65.7797 -516.15807) (xy 65.759777 -516.105979) (xy 65.747651 -516.051542)
			(xy 65.74358 -515.99592) (xy 65.237106 -515.99592) (xy 65.236597 -516.023806) (xy 65.228477 -516.078982)
			(xy 65.212409 -516.132389) (xy 65.188737 -516.182886) (xy 65.157964 -516.229399) (xy 65.120747 -516.270936)
			(xy 65.077879 -516.306611) (xy 65.030273 -516.335665) (xy 64.978944 -516.357477) (xy 64.924987 -516.371583)
			(xy 64.86955 -516.377683) (xy 64.813816 -516.375646) (xy 64.758973 -516.365516) (xy 64.706189 -516.347509)
			(xy 64.656589 -516.322008) (xy 64.611231 -516.289557) (xy 64.571082 -516.250848) (xy 64.536996 -516.206705)
			(xy 64.5097 -516.15807) (xy 64.489777 -516.105979) (xy 64.477651 -516.051542) (xy 64.47358 -515.99592)
			(xy 63.267336 -515.99592) (xy 63.266827 -516.023806) (xy 63.258707 -516.078982) (xy 63.242639 -516.132389)
			(xy 63.218967 -516.182886) (xy 63.188194 -516.229399) (xy 63.150977 -516.270936) (xy 63.108109 -516.306611)
			(xy 63.060503 -516.335665) (xy 63.009174 -516.357477) (xy 62.955217 -516.371583) (xy 62.89978 -516.377683)
			(xy 62.844046 -516.375646) (xy 62.789203 -516.365516) (xy 62.736419 -516.347509) (xy 62.686819 -516.322008)
			(xy 62.641461 -516.289557) (xy 62.601312 -516.250848) (xy 62.567226 -516.206705) (xy 62.53993 -516.15807)
			(xy 62.520007 -516.105979) (xy 62.507881 -516.051542) (xy 62.50381 -515.99592) (xy 61.997336 -515.99592)
			(xy 61.996827 -516.023806) (xy 61.988707 -516.078982) (xy 61.972639 -516.132389) (xy 61.948967 -516.182886)
			(xy 61.918194 -516.229399) (xy 61.880977 -516.270936) (xy 61.838109 -516.306611) (xy 61.790503 -516.335665)
			(xy 61.739174 -516.357477) (xy 61.685217 -516.371583) (xy 61.62978 -516.377683) (xy 61.574046 -516.375646)
			(xy 61.519203 -516.365516) (xy 61.466419 -516.347509) (xy 61.416819 -516.322008) (xy 61.371461 -516.289557)
			(xy 61.331312 -516.250848) (xy 61.297226 -516.206705) (xy 61.26993 -516.15807) (xy 61.250007 -516.105979)
			(xy 61.237881 -516.051542) (xy 61.23381 -515.99592) (xy 60.462922 -515.99592) (xy 60.462413 -516.023806)
			(xy 60.454293 -516.078982) (xy 60.438225 -516.132389) (xy 60.414553 -516.182886) (xy 60.38378 -516.229399)
			(xy 60.346563 -516.270936) (xy 60.303695 -516.306611) (xy 60.256089 -516.335665) (xy 60.20476 -516.357477)
			(xy 60.150803 -516.371583) (xy 60.095366 -516.377683) (xy 60.039632 -516.375646) (xy 59.984789 -516.365516)
			(xy 59.932005 -516.347509) (xy 59.882405 -516.322008) (xy 59.837047 -516.289557) (xy 59.796898 -516.250848)
			(xy 59.762812 -516.206705) (xy 59.735516 -516.15807) (xy 59.715593 -516.105979) (xy 59.703467 -516.051542)
			(xy 59.699396 -515.99592) (xy 59.192922 -515.99592) (xy 59.192413 -516.023806) (xy 59.184293 -516.078982)
			(xy 59.168225 -516.132389) (xy 59.144553 -516.182886) (xy 59.11378 -516.229399) (xy 59.076563 -516.270936)
			(xy 59.033695 -516.306611) (xy 58.986089 -516.335665) (xy 58.93476 -516.357477) (xy 58.880803 -516.371583)
			(xy 58.825366 -516.377683) (xy 58.769632 -516.375646) (xy 58.714789 -516.365516) (xy 58.662005 -516.347509)
			(xy 58.612405 -516.322008) (xy 58.567047 -516.289557) (xy 58.526898 -516.250848) (xy 58.492812 -516.206705)
			(xy 58.465516 -516.15807) (xy 58.445593 -516.105979) (xy 58.433467 -516.051542) (xy 58.429396 -515.99592)
			(xy 57.93105 -515.99592) (xy 57.930541 -516.023806) (xy 57.922421 -516.078982) (xy 57.906353 -516.132389)
			(xy 57.882681 -516.182886) (xy 57.851908 -516.229399) (xy 57.814691 -516.270936) (xy 57.771823 -516.306611)
			(xy 57.724217 -516.335665) (xy 57.672888 -516.357477) (xy 57.618931 -516.371583) (xy 57.563494 -516.377683)
			(xy 57.50776 -516.375646) (xy 57.452917 -516.365516) (xy 57.400133 -516.347509) (xy 57.350533 -516.322008)
			(xy 57.305175 -516.289557) (xy 57.265026 -516.250848) (xy 57.23094 -516.206705) (xy 57.203644 -516.15807)
			(xy 57.183721 -516.105979) (xy 57.171595 -516.051542) (xy 57.167524 -515.99592) (xy 56.66105 -515.99592)
			(xy 56.660541 -516.023806) (xy 56.652421 -516.078982) (xy 56.636353 -516.132389) (xy 56.612681 -516.182886)
			(xy 56.581908 -516.229399) (xy 56.544691 -516.270936) (xy 56.501823 -516.306611) (xy 56.454217 -516.335665)
			(xy 56.402888 -516.357477) (xy 56.348931 -516.371583) (xy 56.293494 -516.377683) (xy 56.23776 -516.375646)
			(xy 56.182917 -516.365516) (xy 56.130133 -516.347509) (xy 56.080533 -516.322008) (xy 56.035175 -516.289557)
			(xy 55.995026 -516.250848) (xy 55.96094 -516.206705) (xy 55.933644 -516.15807) (xy 55.913721 -516.105979)
			(xy 55.901595 -516.051542) (xy 55.897524 -515.99592) (xy 35.989258 -515.99592) (xy 35.919693 -516.030559)
			(xy 35.838661 -516.061951) (xy 35.755079 -516.085732) (xy 35.669659 -516.1017) (xy 35.58313 -516.109718)
			(xy 35.49623 -516.109718) (xy 35.409701 -516.1017) (xy 35.324281 -516.085732) (xy 35.240699 -516.061951)
			(xy 35.159667 -516.030559) (xy 35.081878 -515.991825) (xy 35.007994 -515.946078) (xy 34.938647 -515.893709)
			(xy 34.874427 -515.835165) (xy 34.815883 -515.770945) (xy 34.763514 -515.701598) (xy 34.717767 -515.627714)
			(xy 34.679033 -515.549925) (xy 34.647641 -515.468893) (xy 34.62386 -515.385311) (xy 34.607892 -515.299891)
			(xy 34.599874 -515.213362) (xy 31.399486 -515.213362) (xy 31.391468 -515.299891) (xy 31.3755 -515.385311)
			(xy 31.351719 -515.468893) (xy 31.320327 -515.549925) (xy 31.281593 -515.627714) (xy 31.235846 -515.701598)
			(xy 31.183477 -515.770945) (xy 31.124933 -515.835165) (xy 31.060713 -515.893709) (xy 30.991366 -515.946078)
			(xy 30.917482 -515.991825) (xy 30.839693 -516.030559) (xy 30.758661 -516.061951) (xy 30.675079 -516.085732)
			(xy 30.589659 -516.1017) (xy 30.50313 -516.109718) (xy 30.41623 -516.109718) (xy 30.329701 -516.1017)
			(xy 30.244281 -516.085732) (xy 30.160699 -516.061951) (xy 30.079667 -516.030559) (xy 30.001878 -515.991825)
			(xy 29.927994 -515.946078) (xy 29.858647 -515.893709) (xy 29.794427 -515.835165) (xy 29.735883 -515.770945)
			(xy 29.683514 -515.701598) (xy 29.637767 -515.627714) (xy 29.599033 -515.549925) (xy 29.567641 -515.468893)
			(xy 29.54386 -515.385311) (xy 29.527892 -515.299891) (xy 29.519874 -515.213362) (xy 1.525016 -515.213362)
			(xy 1.525016 -517.092629) (xy 4.852911 -517.092629) (xy 4.852911 -517.006903) (xy 4.860821 -516.921543)
			(xy 4.876573 -516.837276) (xy 4.900033 -516.754823) (xy 4.931001 -516.674886) (xy 4.969212 -516.598147)
			(xy 5.014341 -516.525261) (xy 5.066002 -516.45685) (xy 5.123756 -516.393498) (xy 5.187108 -516.335744)
			(xy 5.255519 -516.284083) (xy 5.328405 -516.238954) (xy 5.405144 -516.200743) (xy 5.485081 -516.169775)
			(xy 5.567534 -516.146315) (xy 5.651801 -516.130563) (xy 5.737161 -516.122653) (xy 5.822887 -516.122653)
			(xy 5.908247 -516.130563) (xy 5.992514 -516.146315) (xy 6.074967 -516.169775) (xy 6.154904 -516.200743)
			(xy 6.231643 -516.238954) (xy 6.304529 -516.284083) (xy 6.37294 -516.335744) (xy 6.436292 -516.393498)
			(xy 6.494046 -516.45685) (xy 6.545707 -516.525261) (xy 6.590836 -516.598147) (xy 6.629047 -516.674886)
			(xy 6.660015 -516.754823) (xy 6.683475 -516.837276) (xy 6.699227 -516.921543) (xy 6.707137 -517.006903)
			(xy 6.707632 -517.049766) (xy 6.707137 -517.092629) (xy 6.699227 -517.177989) (xy 6.683475 -517.262256)
			(xy 6.660015 -517.344709) (xy 6.629047 -517.424646) (xy 6.590836 -517.501385) (xy 6.545707 -517.574271)
			(xy 6.494046 -517.642682) (xy 6.436292 -517.706034) (xy 6.384377 -517.753362) (xy 29.519874 -517.753362)
			(xy 29.519874 -517.666462) (xy 29.527892 -517.579933) (xy 29.54386 -517.494513) (xy 29.567641 -517.410931)
			(xy 29.599033 -517.329899) (xy 29.637767 -517.25211) (xy 29.683514 -517.178226) (xy 29.735883 -517.108879)
			(xy 29.794427 -517.044659) (xy 29.858647 -516.986115) (xy 29.927994 -516.933746) (xy 30.001878 -516.887999)
			(xy 30.079667 -516.849265) (xy 30.160699 -516.817873) (xy 30.244281 -516.794092) (xy 30.329701 -516.778124)
			(xy 30.41623 -516.770106) (xy 30.50313 -516.770106) (xy 30.589659 -516.778124) (xy 30.675079 -516.794092)
			(xy 30.758661 -516.817873) (xy 30.839693 -516.849265) (xy 30.917482 -516.887999) (xy 30.991366 -516.933746)
			(xy 31.060713 -516.986115) (xy 31.124933 -517.044659) (xy 31.183477 -517.108879) (xy 31.235846 -517.178226)
			(xy 31.281593 -517.25211) (xy 31.320327 -517.329899) (xy 31.351719 -517.410931) (xy 31.3755 -517.494513)
			(xy 31.391468 -517.579933) (xy 31.399486 -517.666462) (xy 31.399988 -517.709912) (xy 31.399486 -517.753362)
			(xy 34.599874 -517.753362) (xy 34.599874 -517.666462) (xy 34.607892 -517.579933) (xy 34.62386 -517.494513)
			(xy 34.647641 -517.410931) (xy 34.679033 -517.329899) (xy 34.717767 -517.25211) (xy 34.763514 -517.178226)
			(xy 34.815883 -517.108879) (xy 34.874427 -517.044659) (xy 34.938647 -516.986115) (xy 35.007994 -516.933746)
			(xy 35.081878 -516.887999) (xy 35.159667 -516.849265) (xy 35.240699 -516.817873) (xy 35.324281 -516.794092)
			(xy 35.409701 -516.778124) (xy 35.49623 -516.770106) (xy 35.58313 -516.770106) (xy 35.669659 -516.778124)
			(xy 35.755079 -516.794092) (xy 35.838661 -516.817873) (xy 35.919693 -516.849265) (xy 35.997482 -516.887999)
			(xy 36.071366 -516.933746) (xy 36.140713 -516.986115) (xy 36.204933 -517.044659) (xy 36.263477 -517.108879)
			(xy 36.315846 -517.178226) (xy 36.361593 -517.25211) (xy 36.400327 -517.329899) (xy 36.431719 -517.410931)
			(xy 36.4555 -517.494513) (xy 36.471468 -517.579933) (xy 36.479486 -517.666462) (xy 36.479988 -517.709912)
			(xy 36.479486 -517.753362) (xy 36.471468 -517.839891) (xy 36.4555 -517.925311) (xy 36.431719 -518.008893)
			(xy 36.400327 -518.089925) (xy 36.361593 -518.167714) (xy 36.315846 -518.241598) (xy 36.263477 -518.310945)
			(xy 36.204933 -518.375165) (xy 36.140713 -518.433709) (xy 36.071366 -518.486078) (xy 35.997482 -518.531825)
			(xy 35.919693 -518.570559) (xy 35.838661 -518.601951) (xy 35.755079 -518.625732) (xy 35.669659 -518.6417)
			(xy 35.58313 -518.649718) (xy 35.49623 -518.649718) (xy 35.409701 -518.6417) (xy 35.324281 -518.625732)
			(xy 35.240699 -518.601951) (xy 35.159667 -518.570559) (xy 35.081878 -518.531825) (xy 35.007994 -518.486078)
			(xy 34.938647 -518.433709) (xy 34.874427 -518.375165) (xy 34.815883 -518.310945) (xy 34.763514 -518.241598)
			(xy 34.717767 -518.167714) (xy 34.679033 -518.089925) (xy 34.647641 -518.008893) (xy 34.62386 -517.925311)
			(xy 34.607892 -517.839891) (xy 34.599874 -517.753362) (xy 31.399486 -517.753362) (xy 31.391468 -517.839891)
			(xy 31.3755 -517.925311) (xy 31.351719 -518.008893) (xy 31.320327 -518.089925) (xy 31.281593 -518.167714)
			(xy 31.235846 -518.241598) (xy 31.183477 -518.310945) (xy 31.124933 -518.375165) (xy 31.060713 -518.433709)
			(xy 30.991366 -518.486078) (xy 30.917482 -518.531825) (xy 30.839693 -518.570559) (xy 30.758661 -518.601951)
			(xy 30.675079 -518.625732) (xy 30.589659 -518.6417) (xy 30.50313 -518.649718) (xy 30.41623 -518.649718)
			(xy 30.329701 -518.6417) (xy 30.244281 -518.625732) (xy 30.160699 -518.601951) (xy 30.079667 -518.570559)
			(xy 30.001878 -518.531825) (xy 29.927994 -518.486078) (xy 29.858647 -518.433709) (xy 29.794427 -518.375165)
			(xy 29.735883 -518.310945) (xy 29.683514 -518.241598) (xy 29.637767 -518.167714) (xy 29.599033 -518.089925)
			(xy 29.567641 -518.008893) (xy 29.54386 -517.925311) (xy 29.527892 -517.839891) (xy 29.519874 -517.753362)
			(xy 6.384377 -517.753362) (xy 6.37294 -517.763788) (xy 6.304529 -517.815449) (xy 6.231643 -517.860578)
			(xy 6.154904 -517.898789) (xy 6.074967 -517.929757) (xy 5.992514 -517.953217) (xy 5.908247 -517.968969)
			(xy 5.822887 -517.976879) (xy 5.737161 -517.976879) (xy 5.651801 -517.968969) (xy 5.567534 -517.953217)
			(xy 5.485081 -517.929757) (xy 5.405144 -517.898789) (xy 5.328405 -517.860578) (xy 5.255519 -517.815449)
			(xy 5.187108 -517.763788) (xy 5.123756 -517.706034) (xy 5.066002 -517.642682) (xy 5.014341 -517.574271)
			(xy 4.969212 -517.501385) (xy 4.931001 -517.424646) (xy 4.900033 -517.344709) (xy 4.876573 -517.262256)
			(xy 4.860821 -517.177989) (xy 4.852911 -517.092629) (xy 1.525016 -517.092629) (xy 1.525016 -520.04976)
			(xy 6.671831 -520.04976) (xy 6.675786 -519.957923) (xy 6.687621 -519.866766) (xy 6.707248 -519.776963)
			(xy 6.734522 -519.689181) (xy 6.769242 -519.604067) (xy 6.81115 -519.522254) (xy 6.859936 -519.444346)
			(xy 6.915239 -519.370921) (xy 6.976649 -519.302521) (xy 7.043711 -519.239654) (xy 7.11593 -519.182784)
			(xy 7.19277 -519.132333) (xy 7.273663 -519.088674) (xy 7.358009 -519.052131) (xy 7.445185 -519.022974)
			(xy 7.534544 -519.00142) (xy 7.625425 -518.987626) (xy 7.717156 -518.981696) (xy 7.809057 -518.983674)
			(xy 7.900448 -518.993545) (xy 7.990652 -519.011235) (xy 8.079001 -519.036615) (xy 8.142942 -519.061107)
			(xy 47.82311 -519.061107) (xy 47.82311 -518.979997) (xy 47.83106 -518.899278) (xy 47.846883 -518.819727)
			(xy 47.870428 -518.742111) (xy 47.901467 -518.667175) (xy 47.939702 -518.595643) (xy 47.984764 -518.528203)
			(xy 48.036219 -518.465504) (xy 48.093572 -518.408151) (xy 48.156271 -518.356696) (xy 48.223711 -518.311634)
			(xy 48.295243 -518.273399) (xy 48.370179 -518.24236) (xy 48.447795 -518.218815) (xy 48.527346 -518.202992)
			(xy 48.608065 -518.195042) (xy 48.689175 -518.195042) (xy 48.769894 -518.202992) (xy 48.849445 -518.218815)
			(xy 48.927061 -518.24236) (xy 49.001997 -518.273399) (xy 49.073529 -518.311634) (xy 49.140969 -518.356696)
			(xy 49.203668 -518.408151) (xy 49.261021 -518.465504) (xy 49.312476 -518.528203) (xy 49.357538 -518.595643)
			(xy 49.395773 -518.667175) (xy 49.426812 -518.742111) (xy 49.450357 -518.819727) (xy 49.46618 -518.899278)
			(xy 49.47413 -518.979997) (xy 49.474628 -519.020552) (xy 49.47413 -519.061107) (xy 51.32323 -519.061107)
			(xy 51.32323 -518.979997) (xy 51.33118 -518.899278) (xy 51.347003 -518.819727) (xy 51.370548 -518.742111)
			(xy 51.401587 -518.667175) (xy 51.439822 -518.595643) (xy 51.484884 -518.528203) (xy 51.536339 -518.465504)
			(xy 51.593692 -518.408151) (xy 51.656391 -518.356696) (xy 51.723831 -518.311634) (xy 51.795363 -518.273399)
			(xy 51.870299 -518.24236) (xy 51.947915 -518.218815) (xy 52.027466 -518.202992) (xy 52.108185 -518.195042)
			(xy 52.189295 -518.195042) (xy 52.270014 -518.202992) (xy 52.349565 -518.218815) (xy 52.427181 -518.24236)
			(xy 52.502117 -518.273399) (xy 52.573649 -518.311634) (xy 52.641089 -518.356696) (xy 52.703788 -518.408151)
			(xy 52.761141 -518.465504) (xy 52.812596 -518.528203) (xy 52.857658 -518.595643) (xy 52.894297 -518.66419)
			(xy 55.897524 -518.66419) (xy 55.901595 -518.608568) (xy 55.913721 -518.554131) (xy 55.933644 -518.50204)
			(xy 55.96094 -518.453405) (xy 55.995026 -518.409262) (xy 56.035175 -518.370553) (xy 56.080533 -518.338102)
			(xy 56.130133 -518.312601) (xy 56.182917 -518.294594) (xy 56.23776 -518.284464) (xy 56.293494 -518.282427)
			(xy 56.348931 -518.288527) (xy 56.402888 -518.302633) (xy 56.454217 -518.324445) (xy 56.501823 -518.353499)
			(xy 56.544691 -518.389174) (xy 56.581908 -518.430711) (xy 56.612681 -518.477224) (xy 56.636353 -518.527721)
			(xy 56.652421 -518.581128) (xy 56.660541 -518.636304) (xy 56.66105 -518.66419) (xy 57.167524 -518.66419)
			(xy 57.171595 -518.608568) (xy 57.183721 -518.554131) (xy 57.203644 -518.50204) (xy 57.23094 -518.453405)
			(xy 57.265026 -518.409262) (xy 57.305175 -518.370553) (xy 57.350533 -518.338102) (xy 57.400133 -518.312601)
			(xy 57.452917 -518.294594) (xy 57.50776 -518.284464) (xy 57.563494 -518.282427) (xy 57.618931 -518.288527)
			(xy 57.672888 -518.302633) (xy 57.724217 -518.324445) (xy 57.771823 -518.353499) (xy 57.814691 -518.389174)
			(xy 57.851908 -518.430711) (xy 57.882681 -518.477224) (xy 57.906353 -518.527721) (xy 57.922421 -518.581128)
			(xy 57.930541 -518.636304) (xy 57.93105 -518.66419) (xy 58.429396 -518.66419) (xy 58.433467 -518.608568)
			(xy 58.445593 -518.554131) (xy 58.465516 -518.50204) (xy 58.492812 -518.453405) (xy 58.526898 -518.409262)
			(xy 58.567047 -518.370553) (xy 58.612405 -518.338102) (xy 58.662005 -518.312601) (xy 58.714789 -518.294594)
			(xy 58.769632 -518.284464) (xy 58.825366 -518.282427) (xy 58.880803 -518.288527) (xy 58.93476 -518.302633)
			(xy 58.986089 -518.324445) (xy 59.033695 -518.353499) (xy 59.076563 -518.389174) (xy 59.11378 -518.430711)
			(xy 59.144553 -518.477224) (xy 59.168225 -518.527721) (xy 59.184293 -518.581128) (xy 59.192413 -518.636304)
			(xy 59.192922 -518.66419) (xy 59.699396 -518.66419) (xy 59.703467 -518.608568) (xy 59.715593 -518.554131)
			(xy 59.735516 -518.50204) (xy 59.762812 -518.453405) (xy 59.796898 -518.409262) (xy 59.837047 -518.370553)
			(xy 59.882405 -518.338102) (xy 59.932005 -518.312601) (xy 59.984789 -518.294594) (xy 60.039632 -518.284464)
			(xy 60.095366 -518.282427) (xy 60.150803 -518.288527) (xy 60.20476 -518.302633) (xy 60.256089 -518.324445)
			(xy 60.303695 -518.353499) (xy 60.346563 -518.389174) (xy 60.38378 -518.430711) (xy 60.414553 -518.477224)
			(xy 60.438225 -518.527721) (xy 60.454293 -518.581128) (xy 60.462413 -518.636304) (xy 60.462922 -518.66419)
			(xy 61.23381 -518.66419) (xy 61.237881 -518.608568) (xy 61.250007 -518.554131) (xy 61.26993 -518.50204)
			(xy 61.297226 -518.453405) (xy 61.331312 -518.409262) (xy 61.371461 -518.370553) (xy 61.416819 -518.338102)
			(xy 61.466419 -518.312601) (xy 61.519203 -518.294594) (xy 61.574046 -518.284464) (xy 61.62978 -518.282427)
			(xy 61.685217 -518.288527) (xy 61.739174 -518.302633) (xy 61.790503 -518.324445) (xy 61.838109 -518.353499)
			(xy 61.880977 -518.389174) (xy 61.918194 -518.430711) (xy 61.948967 -518.477224) (xy 61.972639 -518.527721)
			(xy 61.988707 -518.581128) (xy 61.996827 -518.636304) (xy 61.997336 -518.66419) (xy 62.50381 -518.66419)
			(xy 62.507881 -518.608568) (xy 62.520007 -518.554131) (xy 62.53993 -518.50204) (xy 62.567226 -518.453405)
			(xy 62.601312 -518.409262) (xy 62.641461 -518.370553) (xy 62.686819 -518.338102) (xy 62.736419 -518.312601)
			(xy 62.789203 -518.294594) (xy 62.844046 -518.284464) (xy 62.89978 -518.282427) (xy 62.955217 -518.288527)
			(xy 63.009174 -518.302633) (xy 63.060503 -518.324445) (xy 63.108109 -518.353499) (xy 63.150977 -518.389174)
			(xy 63.188194 -518.430711) (xy 63.218967 -518.477224) (xy 63.242639 -518.527721) (xy 63.258707 -518.581128)
			(xy 63.266827 -518.636304) (xy 63.267336 -518.66419) (xy 64.47358 -518.66419) (xy 64.477651 -518.608568)
			(xy 64.489777 -518.554131) (xy 64.5097 -518.50204) (xy 64.536996 -518.453405) (xy 64.571082 -518.409262)
			(xy 64.611231 -518.370553) (xy 64.656589 -518.338102) (xy 64.706189 -518.312601) (xy 64.758973 -518.294594)
			(xy 64.813816 -518.284464) (xy 64.86955 -518.282427) (xy 64.924987 -518.288527) (xy 64.978944 -518.302633)
			(xy 65.030273 -518.324445) (xy 65.077879 -518.353499) (xy 65.120747 -518.389174) (xy 65.157964 -518.430711)
			(xy 65.188737 -518.477224) (xy 65.212409 -518.527721) (xy 65.228477 -518.581128) (xy 65.236597 -518.636304)
			(xy 65.237106 -518.66419) (xy 65.74358 -518.66419) (xy 65.747651 -518.608568) (xy 65.759777 -518.554131)
			(xy 65.7797 -518.50204) (xy 65.806996 -518.453405) (xy 65.841082 -518.409262) (xy 65.881231 -518.370553)
			(xy 65.926589 -518.338102) (xy 65.976189 -518.312601) (xy 66.028973 -518.294594) (xy 66.083816 -518.284464)
			(xy 66.13955 -518.282427) (xy 66.194987 -518.288527) (xy 66.248944 -518.302633) (xy 66.300273 -518.324445)
			(xy 66.347879 -518.353499) (xy 66.390747 -518.389174) (xy 66.427964 -518.430711) (xy 66.458737 -518.477224)
			(xy 66.482409 -518.527721) (xy 66.498477 -518.581128) (xy 66.506597 -518.636304) (xy 66.507106 -518.66419)
			(xy 67.465192 -518.66419) (xy 67.469263 -518.608568) (xy 67.481389 -518.554131) (xy 67.501312 -518.50204)
			(xy 67.528608 -518.453405) (xy 67.562694 -518.409262) (xy 67.602843 -518.370553) (xy 67.648201 -518.338102)
			(xy 67.697801 -518.312601) (xy 67.750585 -518.294594) (xy 67.805428 -518.284464) (xy 67.861162 -518.282427)
			(xy 67.916599 -518.288527) (xy 67.970556 -518.302633) (xy 68.021885 -518.324445) (xy 68.069491 -518.353499)
			(xy 68.112359 -518.389174) (xy 68.149576 -518.430711) (xy 68.180349 -518.477224) (xy 68.204021 -518.527721)
			(xy 68.220089 -518.581128) (xy 68.228209 -518.636304) (xy 68.228718 -518.66419) (xy 68.735192 -518.66419)
			(xy 68.739263 -518.608568) (xy 68.751389 -518.554131) (xy 68.771312 -518.50204) (xy 68.798608 -518.453405)
			(xy 68.832694 -518.409262) (xy 68.872843 -518.370553) (xy 68.918201 -518.338102) (xy 68.967801 -518.312601)
			(xy 69.020585 -518.294594) (xy 69.075428 -518.284464) (xy 69.131162 -518.282427) (xy 69.186599 -518.288527)
			(xy 69.240556 -518.302633) (xy 69.291885 -518.324445) (xy 69.339491 -518.353499) (xy 69.382359 -518.389174)
			(xy 69.419576 -518.430711) (xy 69.450349 -518.477224) (xy 69.474021 -518.527721) (xy 69.490089 -518.581128)
			(xy 69.498209 -518.636304) (xy 69.498718 -518.66419) (xy 69.498209 -518.692076) (xy 69.490089 -518.747252)
			(xy 69.474021 -518.800659) (xy 69.450349 -518.851156) (xy 69.419576 -518.897669) (xy 69.382359 -518.939206)
			(xy 69.339491 -518.974881) (xy 69.291885 -519.003935) (xy 69.240556 -519.025747) (xy 69.186599 -519.039853)
			(xy 69.131162 -519.045953) (xy 69.075428 -519.043916) (xy 69.020585 -519.033786) (xy 68.967801 -519.015779)
			(xy 68.918201 -518.990278) (xy 68.872843 -518.957827) (xy 68.832694 -518.919118) (xy 68.798608 -518.874975)
			(xy 68.771312 -518.82634) (xy 68.751389 -518.774249) (xy 68.739263 -518.719812) (xy 68.735192 -518.66419)
			(xy 68.228718 -518.66419) (xy 68.228209 -518.692076) (xy 68.220089 -518.747252) (xy 68.204021 -518.800659)
			(xy 68.180349 -518.851156) (xy 68.149576 -518.897669) (xy 68.112359 -518.939206) (xy 68.069491 -518.974881)
			(xy 68.021885 -519.003935) (xy 67.970556 -519.025747) (xy 67.916599 -519.039853) (xy 67.861162 -519.045953)
			(xy 67.805428 -519.043916) (xy 67.750585 -519.033786) (xy 67.697801 -519.015779) (xy 67.648201 -518.990278)
			(xy 67.602843 -518.957827) (xy 67.562694 -518.919118) (xy 67.528608 -518.874975) (xy 67.501312 -518.82634)
			(xy 67.481389 -518.774249) (xy 67.469263 -518.719812) (xy 67.465192 -518.66419) (xy 66.507106 -518.66419)
			(xy 66.506597 -518.692076) (xy 66.498477 -518.747252) (xy 66.482409 -518.800659) (xy 66.458737 -518.851156)
			(xy 66.427964 -518.897669) (xy 66.390747 -518.939206) (xy 66.347879 -518.974881) (xy 66.300273 -519.003935)
			(xy 66.248944 -519.025747) (xy 66.194987 -519.039853) (xy 66.13955 -519.045953) (xy 66.083816 -519.043916)
			(xy 66.028973 -519.033786) (xy 65.976189 -519.015779) (xy 65.926589 -518.990278) (xy 65.881231 -518.957827)
			(xy 65.841082 -518.919118) (xy 65.806996 -518.874975) (xy 65.7797 -518.82634) (xy 65.759777 -518.774249)
			(xy 65.747651 -518.719812) (xy 65.74358 -518.66419) (xy 65.237106 -518.66419) (xy 65.236597 -518.692076)
			(xy 65.228477 -518.747252) (xy 65.212409 -518.800659) (xy 65.188737 -518.851156) (xy 65.157964 -518.897669)
			(xy 65.120747 -518.939206) (xy 65.077879 -518.974881) (xy 65.030273 -519.003935) (xy 64.978944 -519.025747)
			(xy 64.924987 -519.039853) (xy 64.86955 -519.045953) (xy 64.813816 -519.043916) (xy 64.758973 -519.033786)
			(xy 64.706189 -519.015779) (xy 64.656589 -518.990278) (xy 64.611231 -518.957827) (xy 64.571082 -518.919118)
			(xy 64.536996 -518.874975) (xy 64.5097 -518.82634) (xy 64.489777 -518.774249) (xy 64.477651 -518.719812)
			(xy 64.47358 -518.66419) (xy 63.267336 -518.66419) (xy 63.266827 -518.692076) (xy 63.258707 -518.747252)
			(xy 63.242639 -518.800659) (xy 63.218967 -518.851156) (xy 63.188194 -518.897669) (xy 63.150977 -518.939206)
			(xy 63.108109 -518.974881) (xy 63.060503 -519.003935) (xy 63.009174 -519.025747) (xy 62.955217 -519.039853)
			(xy 62.89978 -519.045953) (xy 62.844046 -519.043916) (xy 62.789203 -519.033786) (xy 62.736419 -519.015779)
			(xy 62.686819 -518.990278) (xy 62.641461 -518.957827) (xy 62.601312 -518.919118) (xy 62.567226 -518.874975)
			(xy 62.53993 -518.82634) (xy 62.520007 -518.774249) (xy 62.507881 -518.719812) (xy 62.50381 -518.66419)
			(xy 61.997336 -518.66419) (xy 61.996827 -518.692076) (xy 61.988707 -518.747252) (xy 61.972639 -518.800659)
			(xy 61.948967 -518.851156) (xy 61.918194 -518.897669) (xy 61.880977 -518.939206) (xy 61.838109 -518.974881)
			(xy 61.790503 -519.003935) (xy 61.739174 -519.025747) (xy 61.685217 -519.039853) (xy 61.62978 -519.045953)
			(xy 61.574046 -519.043916) (xy 61.519203 -519.033786) (xy 61.466419 -519.015779) (xy 61.416819 -518.990278)
			(xy 61.371461 -518.957827) (xy 61.331312 -518.919118) (xy 61.297226 -518.874975) (xy 61.26993 -518.82634)
			(xy 61.250007 -518.774249) (xy 61.237881 -518.719812) (xy 61.23381 -518.66419) (xy 60.462922 -518.66419)
			(xy 60.462413 -518.692076) (xy 60.454293 -518.747252) (xy 60.438225 -518.800659) (xy 60.414553 -518.851156)
			(xy 60.38378 -518.897669) (xy 60.346563 -518.939206) (xy 60.303695 -518.974881) (xy 60.256089 -519.003935)
			(xy 60.20476 -519.025747) (xy 60.150803 -519.039853) (xy 60.095366 -519.045953) (xy 60.039632 -519.043916)
			(xy 59.984789 -519.033786) (xy 59.932005 -519.015779) (xy 59.882405 -518.990278) (xy 59.837047 -518.957827)
			(xy 59.796898 -518.919118) (xy 59.762812 -518.874975) (xy 59.735516 -518.82634) (xy 59.715593 -518.774249)
			(xy 59.703467 -518.719812) (xy 59.699396 -518.66419) (xy 59.192922 -518.66419) (xy 59.192413 -518.692076)
			(xy 59.184293 -518.747252) (xy 59.168225 -518.800659) (xy 59.144553 -518.851156) (xy 59.11378 -518.897669)
			(xy 59.076563 -518.939206) (xy 59.033695 -518.974881) (xy 58.986089 -519.003935) (xy 58.93476 -519.025747)
			(xy 58.880803 -519.039853) (xy 58.825366 -519.045953) (xy 58.769632 -519.043916) (xy 58.714789 -519.033786)
			(xy 58.662005 -519.015779) (xy 58.612405 -518.990278) (xy 58.567047 -518.957827) (xy 58.526898 -518.919118)
			(xy 58.492812 -518.874975) (xy 58.465516 -518.82634) (xy 58.445593 -518.774249) (xy 58.433467 -518.719812)
			(xy 58.429396 -518.66419) (xy 57.93105 -518.66419) (xy 57.930541 -518.692076) (xy 57.922421 -518.747252)
			(xy 57.906353 -518.800659) (xy 57.882681 -518.851156) (xy 57.851908 -518.897669) (xy 57.814691 -518.939206)
			(xy 57.771823 -518.974881) (xy 57.724217 -519.003935) (xy 57.672888 -519.025747) (xy 57.618931 -519.039853)
			(xy 57.563494 -519.045953) (xy 57.50776 -519.043916) (xy 57.452917 -519.033786) (xy 57.400133 -519.015779)
			(xy 57.350533 -518.990278) (xy 57.305175 -518.957827) (xy 57.265026 -518.919118) (xy 57.23094 -518.874975)
			(xy 57.203644 -518.82634) (xy 57.183721 -518.774249) (xy 57.171595 -518.719812) (xy 57.167524 -518.66419)
			(xy 56.66105 -518.66419) (xy 56.660541 -518.692076) (xy 56.652421 -518.747252) (xy 56.636353 -518.800659)
			(xy 56.612681 -518.851156) (xy 56.581908 -518.897669) (xy 56.544691 -518.939206) (xy 56.501823 -518.974881)
			(xy 56.454217 -519.003935) (xy 56.402888 -519.025747) (xy 56.348931 -519.039853) (xy 56.293494 -519.045953)
			(xy 56.23776 -519.043916) (xy 56.182917 -519.033786) (xy 56.130133 -519.015779) (xy 56.080533 -518.990278)
			(xy 56.035175 -518.957827) (xy 55.995026 -518.919118) (xy 55.96094 -518.874975) (xy 55.933644 -518.82634)
			(xy 55.913721 -518.774249) (xy 55.901595 -518.719812) (xy 55.897524 -518.66419) (xy 52.894297 -518.66419)
			(xy 52.895893 -518.667175) (xy 52.926932 -518.742111) (xy 52.950477 -518.819727) (xy 52.9663 -518.899278)
			(xy 52.97425 -518.979997) (xy 52.974748 -519.020552) (xy 52.974389 -519.049762) (xy 72.868035 -519.049762)
			(xy 72.872042 -518.847012) (xy 72.884055 -518.644578) (xy 72.904056 -518.442777) (xy 72.932015 -518.241923)
			(xy 72.967886 -518.042331) (xy 73.011615 -517.844312) (xy 73.063133 -517.648175) (xy 73.122359 -517.454227)
			(xy 73.189201 -517.262769) (xy 73.263555 -517.074102) (xy 73.345304 -516.88852) (xy 73.434322 -516.706312)
			(xy 73.530468 -516.527763) (xy 73.633593 -516.353152) (xy 73.743536 -516.182752) (xy 73.860125 -516.016828)
			(xy 73.983178 -515.855639) (xy 74.112503 -515.699438) (xy 74.247898 -515.548468) (xy 74.389151 -515.402964)
			(xy 74.536043 -515.263155) (xy 74.688343 -515.129258) (xy 74.845814 -515.001483) (xy 75.008211 -514.880028)
			(xy 75.175278 -514.765084) (xy 75.346757 -514.65683) (xy 75.522378 -514.555435) (xy 75.701868 -514.461057)
			(xy 75.884946 -514.373845) (xy 76.071327 -514.293933) (xy 76.26072 -514.221446) (xy 76.452828 -514.156499)
			(xy 76.647352 -514.099191) (xy 76.843988 -514.049614) (xy 77.04243 -514.007843) (xy 77.242367 -513.973945)
			(xy 77.443486 -513.947973) (xy 77.645475 -513.929966) (xy 77.848018 -513.919953) (xy 78.050798 -513.917949)
			(xy 78.253499 -513.923959) (xy 78.455804 -513.937971) (xy 78.657398 -513.959966) (xy 78.857965 -513.989907)
			(xy 79.057193 -514.027748) (xy 79.254771 -514.073431) (xy 79.450389 -514.126884) (xy 79.643743 -514.188023)
			(xy 79.834531 -514.256754) (xy 80.022454 -514.332968) (xy 80.20722 -514.416547) (xy 80.388539 -514.50736)
			(xy 80.56613 -514.605265) (xy 80.739713 -514.71011) (xy 80.909019 -514.821731) (xy 81.073784 -514.939953)
			(xy 81.233749 -515.064593) (xy 81.388665 -515.195454) (xy 81.53829 -515.332334) (xy 81.68239 -515.475018)
			(xy 81.820742 -515.623284) (xy 81.953127 -515.7769) (xy 82.079341 -515.935625) (xy 82.199185 -516.099214)
			(xy 82.312473 -516.267409) (xy 82.419028 -516.439948) (xy 82.518683 -516.616563) (xy 82.611283 -516.796976)
			(xy 82.696683 -516.980907) (xy 82.77475 -517.168068) (xy 82.845362 -517.358168) (xy 82.908408 -517.550908)
			(xy 82.963791 -517.745989) (xy 83.011423 -517.943106) (xy 83.051231 -518.14195) (xy 83.083153 -518.342212)
			(xy 83.107137 -518.543578) (xy 83.123148 -518.745735) (xy 83.131159 -518.948367) (xy 83.13166 -519.049762)
			(xy 83.131159 -519.151157) (xy 83.123148 -519.353789) (xy 83.107137 -519.555946) (xy 83.083153 -519.757312)
			(xy 83.051231 -519.957574) (xy 83.011423 -520.156418) (xy 82.963791 -520.353535) (xy 82.908408 -520.548616)
			(xy 82.845362 -520.741356) (xy 82.77475 -520.931456) (xy 82.696683 -521.118617) (xy 82.611283 -521.302548)
			(xy 82.518683 -521.482961) (xy 82.419028 -521.659576) (xy 82.312473 -521.832115) (xy 82.199185 -522.00031)
			(xy 82.079341 -522.163899) (xy 81.953127 -522.322624) (xy 81.820742 -522.47624) (xy 81.68239 -522.624506)
			(xy 81.53829 -522.76719) (xy 81.388665 -522.90407) (xy 81.233749 -523.034931) (xy 81.073784 -523.159571)
			(xy 80.909019 -523.277793) (xy 80.739713 -523.389414) (xy 80.56613 -523.494259) (xy 80.388539 -523.592164)
			(xy 80.20722 -523.682977) (xy 80.022454 -523.766556) (xy 79.834531 -523.84277) (xy 79.643743 -523.911501)
			(xy 79.450389 -523.97264) (xy 79.254771 -524.026093) (xy 79.057193 -524.071776) (xy 78.857965 -524.109617)
			(xy 78.657398 -524.139558) (xy 78.455804 -524.161553) (xy 78.253499 -524.175565) (xy 78.050798 -524.181575)
			(xy 77.848018 -524.179571) (xy 77.645475 -524.169558) (xy 77.443486 -524.151551) (xy 77.242367 -524.125579)
			(xy 77.04243 -524.091681) (xy 76.843988 -524.04991) (xy 76.647352 -524.000333) (xy 76.452828 -523.943025)
			(xy 76.26072 -523.878078) (xy 76.071327 -523.805591) (xy 75.884946 -523.725679) (xy 75.701868 -523.638467)
			(xy 75.522378 -523.544089) (xy 75.346757 -523.442694) (xy 75.175278 -523.33444) (xy 75.008211 -523.219496)
			(xy 74.845814 -523.098041) (xy 74.688343 -522.970266) (xy 74.536043 -522.836369) (xy 74.389151 -522.69656)
			(xy 74.247898 -522.551056) (xy 74.112503 -522.400086) (xy 73.983178 -522.243885) (xy 73.860125 -522.082696)
			(xy 73.743536 -521.916772) (xy 73.633593 -521.746372) (xy 73.530468 -521.571761) (xy 73.434322 -521.393212)
			(xy 73.345304 -521.211004) (xy 73.263555 -521.025422) (xy 73.189201 -520.836755) (xy 73.122359 -520.645297)
			(xy 73.063133 -520.451349) (xy 73.011615 -520.255212) (xy 72.967886 -520.057193) (xy 72.932015 -519.857601)
			(xy 72.904056 -519.656747) (xy 72.884055 -519.454946) (xy 72.872042 -519.252512) (xy 72.868035 -519.049762)
			(xy 52.974389 -519.049762) (xy 52.97425 -519.061107) (xy 52.9663 -519.141826) (xy 52.950477 -519.221377)
			(xy 52.926932 -519.298993) (xy 52.895893 -519.373929) (xy 52.857658 -519.445461) (xy 52.812596 -519.512901)
			(xy 52.761141 -519.5756) (xy 52.703788 -519.632953) (xy 52.641089 -519.684408) (xy 52.573649 -519.72947)
			(xy 52.502117 -519.767705) (xy 52.427181 -519.798744) (xy 52.349565 -519.822289) (xy 52.270014 -519.838112)
			(xy 52.189295 -519.846062) (xy 52.108185 -519.846062) (xy 52.027466 -519.838112) (xy 51.947915 -519.822289)
			(xy 51.870299 -519.798744) (xy 51.795363 -519.767705) (xy 51.723831 -519.72947) (xy 51.656391 -519.684408)
			(xy 51.593692 -519.632953) (xy 51.536339 -519.5756) (xy 51.484884 -519.512901) (xy 51.439822 -519.445461)
			(xy 51.401587 -519.373929) (xy 51.370548 -519.298993) (xy 51.347003 -519.221377) (xy 51.33118 -519.141826)
			(xy 51.32323 -519.061107) (xy 49.47413 -519.061107) (xy 49.46618 -519.141826) (xy 49.450357 -519.221377)
			(xy 49.426812 -519.298993) (xy 49.395773 -519.373929) (xy 49.357538 -519.445461) (xy 49.312476 -519.512901)
			(xy 49.261021 -519.5756) (xy 49.203668 -519.632953) (xy 49.140969 -519.684408) (xy 49.073529 -519.72947)
			(xy 49.001997 -519.767705) (xy 48.927061 -519.798744) (xy 48.849445 -519.822289) (xy 48.769894 -519.838112)
			(xy 48.689175 -519.846062) (xy 48.608065 -519.846062) (xy 48.527346 -519.838112) (xy 48.447795 -519.822289)
			(xy 48.370179 -519.798744) (xy 48.295243 -519.767705) (xy 48.223711 -519.72947) (xy 48.156271 -519.684408)
			(xy 48.093572 -519.632953) (xy 48.036219 -519.5756) (xy 47.984764 -519.512901) (xy 47.939702 -519.445461)
			(xy 47.901467 -519.373929) (xy 47.870428 -519.298993) (xy 47.846883 -519.221377) (xy 47.83106 -519.141826)
			(xy 47.82311 -519.061107) (xy 8.142942 -519.061107) (xy 8.164841 -519.069495) (xy 8.247537 -519.109633)
			(xy 8.326477 -519.156732) (xy 8.401075 -519.210442) (xy 8.470781 -519.270366) (xy 8.535076 -519.33606)
			(xy 8.593487 -519.407038) (xy 8.645579 -519.482775) (xy 8.690968 -519.56271) (xy 8.729318 -519.64625)
			(xy 8.760343 -519.732778) (xy 8.783816 -519.821653) (xy 8.799562 -519.912217) (xy 8.807464 -520.003799)
			(xy 8.807958 -520.04976) (xy 8.807464 -520.095721) (xy 8.799562 -520.187303) (xy 8.783816 -520.277867)
			(xy 8.779724 -520.293362) (xy 29.519874 -520.293362) (xy 29.519874 -520.206462) (xy 29.527892 -520.119933)
			(xy 29.54386 -520.034513) (xy 29.567641 -519.950931) (xy 29.599033 -519.869899) (xy 29.637767 -519.79211)
			(xy 29.683514 -519.718226) (xy 29.735883 -519.648879) (xy 29.794427 -519.584659) (xy 29.858647 -519.526115)
			(xy 29.927994 -519.473746) (xy 30.001878 -519.427999) (xy 30.079667 -519.389265) (xy 30.160699 -519.357873)
			(xy 30.244281 -519.334092) (xy 30.329701 -519.318124) (xy 30.41623 -519.310106) (xy 30.50313 -519.310106)
			(xy 30.589659 -519.318124) (xy 30.675079 -519.334092) (xy 30.758661 -519.357873) (xy 30.839693 -519.389265)
			(xy 30.917482 -519.427999) (xy 30.991366 -519.473746) (xy 31.060713 -519.526115) (xy 31.124933 -519.584659)
			(xy 31.183477 -519.648879) (xy 31.235846 -519.718226) (xy 31.281593 -519.79211) (xy 31.320327 -519.869899)
			(xy 31.351719 -519.950931) (xy 31.3755 -520.034513) (xy 31.391468 -520.119933) (xy 31.399486 -520.206462)
			(xy 31.399988 -520.249912) (xy 31.399486 -520.293362) (xy 34.599874 -520.293362) (xy 34.599874 -520.206462)
			(xy 34.607892 -520.119933) (xy 34.62386 -520.034513) (xy 34.647641 -519.950931) (xy 34.679033 -519.869899)
			(xy 34.717767 -519.79211) (xy 34.763514 -519.718226) (xy 34.815883 -519.648879) (xy 34.874427 -519.584659)
			(xy 34.938647 -519.526115) (xy 35.007994 -519.473746) (xy 35.081878 -519.427999) (xy 35.159667 -519.389265)
			(xy 35.240699 -519.357873) (xy 35.324281 -519.334092) (xy 35.409701 -519.318124) (xy 35.49623 -519.310106)
			(xy 35.58313 -519.310106) (xy 35.669659 -519.318124) (xy 35.755079 -519.334092) (xy 35.838661 -519.357873)
			(xy 35.919693 -519.389265) (xy 35.997482 -519.427999) (xy 36.071366 -519.473746) (xy 36.140713 -519.526115)
			(xy 36.204933 -519.584659) (xy 36.263477 -519.648879) (xy 36.315846 -519.718226) (xy 36.361593 -519.79211)
			(xy 36.400327 -519.869899) (xy 36.431719 -519.950931) (xy 36.4555 -520.034513) (xy 36.471468 -520.119933)
			(xy 36.479486 -520.206462) (xy 36.479988 -520.249912) (xy 36.479486 -520.293362) (xy 36.471468 -520.379891)
			(xy 36.4555 -520.465311) (xy 36.431719 -520.548893) (xy 36.400327 -520.629925) (xy 36.361593 -520.707714)
			(xy 36.315846 -520.781598) (xy 36.263477 -520.850945) (xy 36.204933 -520.915165) (xy 36.140713 -520.973709)
			(xy 36.071366 -521.026078) (xy 36.055684 -521.035788) (xy 55.897524 -521.035788) (xy 55.901595 -520.980166)
			(xy 55.913721 -520.925729) (xy 55.933644 -520.873638) (xy 55.96094 -520.825003) (xy 55.995026 -520.78086)
			(xy 56.035175 -520.742151) (xy 56.080533 -520.7097) (xy 56.130133 -520.684199) (xy 56.182917 -520.666192)
			(xy 56.23776 -520.656062) (xy 56.293494 -520.654025) (xy 56.348931 -520.660125) (xy 56.402888 -520.674231)
			(xy 56.454217 -520.696043) (xy 56.501823 -520.725097) (xy 56.544691 -520.760772) (xy 56.581908 -520.802309)
			(xy 56.612681 -520.848822) (xy 56.636353 -520.899319) (xy 56.652421 -520.952726) (xy 56.660541 -521.007902)
			(xy 56.66105 -521.035788) (xy 57.167524 -521.035788) (xy 57.171595 -520.980166) (xy 57.183721 -520.925729)
			(xy 57.203644 -520.873638) (xy 57.23094 -520.825003) (xy 57.265026 -520.78086) (xy 57.305175 -520.742151)
			(xy 57.350533 -520.7097) (xy 57.400133 -520.684199) (xy 57.452917 -520.666192) (xy 57.50776 -520.656062)
			(xy 57.563494 -520.654025) (xy 57.618931 -520.660125) (xy 57.672888 -520.674231) (xy 57.724217 -520.696043)
			(xy 57.771823 -520.725097) (xy 57.814691 -520.760772) (xy 57.851908 -520.802309) (xy 57.882681 -520.848822)
			(xy 57.906353 -520.899319) (xy 57.922421 -520.952726) (xy 57.930541 -521.007902) (xy 57.93105 -521.035788)
			(xy 58.429396 -521.035788) (xy 58.433467 -520.980166) (xy 58.445593 -520.925729) (xy 58.465516 -520.873638)
			(xy 58.492812 -520.825003) (xy 58.526898 -520.78086) (xy 58.567047 -520.742151) (xy 58.612405 -520.7097)
			(xy 58.662005 -520.684199) (xy 58.714789 -520.666192) (xy 58.769632 -520.656062) (xy 58.825366 -520.654025)
			(xy 58.880803 -520.660125) (xy 58.93476 -520.674231) (xy 58.986089 -520.696043) (xy 59.033695 -520.725097)
			(xy 59.076563 -520.760772) (xy 59.11378 -520.802309) (xy 59.144553 -520.848822) (xy 59.168225 -520.899319)
			(xy 59.184293 -520.952726) (xy 59.192413 -521.007902) (xy 59.192922 -521.035788) (xy 59.699396 -521.035788)
			(xy 59.703467 -520.980166) (xy 59.715593 -520.925729) (xy 59.735516 -520.873638) (xy 59.762812 -520.825003)
			(xy 59.796898 -520.78086) (xy 59.837047 -520.742151) (xy 59.882405 -520.7097) (xy 59.932005 -520.684199)
			(xy 59.984789 -520.666192) (xy 60.039632 -520.656062) (xy 60.095366 -520.654025) (xy 60.150803 -520.660125)
			(xy 60.20476 -520.674231) (xy 60.256089 -520.696043) (xy 60.303695 -520.725097) (xy 60.346563 -520.760772)
			(xy 60.38378 -520.802309) (xy 60.414553 -520.848822) (xy 60.438225 -520.899319) (xy 60.454293 -520.952726)
			(xy 60.462413 -521.007902) (xy 60.462922 -521.035788) (xy 61.23381 -521.035788) (xy 61.237881 -520.980166)
			(xy 61.250007 -520.925729) (xy 61.26993 -520.873638) (xy 61.297226 -520.825003) (xy 61.331312 -520.78086)
			(xy 61.371461 -520.742151) (xy 61.416819 -520.7097) (xy 61.466419 -520.684199) (xy 61.519203 -520.666192)
			(xy 61.574046 -520.656062) (xy 61.62978 -520.654025) (xy 61.685217 -520.660125) (xy 61.739174 -520.674231)
			(xy 61.790503 -520.696043) (xy 61.838109 -520.725097) (xy 61.880977 -520.760772) (xy 61.918194 -520.802309)
			(xy 61.948967 -520.848822) (xy 61.972639 -520.899319) (xy 61.988707 -520.952726) (xy 61.996827 -521.007902)
			(xy 61.997336 -521.035788) (xy 62.50381 -521.035788) (xy 62.507881 -520.980166) (xy 62.520007 -520.925729)
			(xy 62.53993 -520.873638) (xy 62.567226 -520.825003) (xy 62.601312 -520.78086) (xy 62.641461 -520.742151)
			(xy 62.686819 -520.7097) (xy 62.736419 -520.684199) (xy 62.789203 -520.666192) (xy 62.844046 -520.656062)
			(xy 62.89978 -520.654025) (xy 62.955217 -520.660125) (xy 63.009174 -520.674231) (xy 63.060503 -520.696043)
			(xy 63.108109 -520.725097) (xy 63.150977 -520.760772) (xy 63.188194 -520.802309) (xy 63.218967 -520.848822)
			(xy 63.242639 -520.899319) (xy 63.258707 -520.952726) (xy 63.266827 -521.007902) (xy 63.267336 -521.035788)
			(xy 64.47358 -521.035788) (xy 64.477651 -520.980166) (xy 64.489777 -520.925729) (xy 64.5097 -520.873638)
			(xy 64.536996 -520.825003) (xy 64.571082 -520.78086) (xy 64.611231 -520.742151) (xy 64.656589 -520.7097)
			(xy 64.706189 -520.684199) (xy 64.758973 -520.666192) (xy 64.813816 -520.656062) (xy 64.86955 -520.654025)
			(xy 64.924987 -520.660125) (xy 64.978944 -520.674231) (xy 65.030273 -520.696043) (xy 65.077879 -520.725097)
			(xy 65.120747 -520.760772) (xy 65.157964 -520.802309) (xy 65.188737 -520.848822) (xy 65.212409 -520.899319)
			(xy 65.228477 -520.952726) (xy 65.236597 -521.007902) (xy 65.237106 -521.035788) (xy 65.74358 -521.035788)
			(xy 65.747651 -520.980166) (xy 65.759777 -520.925729) (xy 65.7797 -520.873638) (xy 65.806996 -520.825003)
			(xy 65.841082 -520.78086) (xy 65.881231 -520.742151) (xy 65.926589 -520.7097) (xy 65.976189 -520.684199)
			(xy 66.028973 -520.666192) (xy 66.083816 -520.656062) (xy 66.13955 -520.654025) (xy 66.194987 -520.660125)
			(xy 66.248944 -520.674231) (xy 66.300273 -520.696043) (xy 66.347879 -520.725097) (xy 66.390747 -520.760772)
			(xy 66.427964 -520.802309) (xy 66.458737 -520.848822) (xy 66.482409 -520.899319) (xy 66.498477 -520.952726)
			(xy 66.506597 -521.007902) (xy 66.507106 -521.035788) (xy 67.465192 -521.035788) (xy 67.469263 -520.980166)
			(xy 67.481389 -520.925729) (xy 67.501312 -520.873638) (xy 67.528608 -520.825003) (xy 67.562694 -520.78086)
			(xy 67.602843 -520.742151) (xy 67.648201 -520.7097) (xy 67.697801 -520.684199) (xy 67.750585 -520.666192)
			(xy 67.805428 -520.656062) (xy 67.861162 -520.654025) (xy 67.916599 -520.660125) (xy 67.970556 -520.674231)
			(xy 68.021885 -520.696043) (xy 68.069491 -520.725097) (xy 68.112359 -520.760772) (xy 68.149576 -520.802309)
			(xy 68.180349 -520.848822) (xy 68.204021 -520.899319) (xy 68.220089 -520.952726) (xy 68.228209 -521.007902)
			(xy 68.228718 -521.035788) (xy 68.735192 -521.035788) (xy 68.739263 -520.980166) (xy 68.751389 -520.925729)
			(xy 68.771312 -520.873638) (xy 68.798608 -520.825003) (xy 68.832694 -520.78086) (xy 68.872843 -520.742151)
			(xy 68.918201 -520.7097) (xy 68.967801 -520.684199) (xy 69.020585 -520.666192) (xy 69.075428 -520.656062)
			(xy 69.131162 -520.654025) (xy 69.186599 -520.660125) (xy 69.240556 -520.674231) (xy 69.291885 -520.696043)
			(xy 69.339491 -520.725097) (xy 69.382359 -520.760772) (xy 69.419576 -520.802309) (xy 69.450349 -520.848822)
			(xy 69.474021 -520.899319) (xy 69.490089 -520.952726) (xy 69.498209 -521.007902) (xy 69.498718 -521.035788)
			(xy 69.498209 -521.063674) (xy 69.490089 -521.11885) (xy 69.474021 -521.172257) (xy 69.450349 -521.222754)
			(xy 69.419576 -521.269267) (xy 69.382359 -521.310804) (xy 69.339491 -521.346479) (xy 69.291885 -521.375533)
			(xy 69.240556 -521.397345) (xy 69.186599 -521.411451) (xy 69.131162 -521.417551) (xy 69.075428 -521.415514)
			(xy 69.020585 -521.405384) (xy 68.967801 -521.387377) (xy 68.918201 -521.361876) (xy 68.872843 -521.329425)
			(xy 68.832694 -521.290716) (xy 68.798608 -521.246573) (xy 68.771312 -521.197938) (xy 68.751389 -521.145847)
			(xy 68.739263 -521.09141) (xy 68.735192 -521.035788) (xy 68.228718 -521.035788) (xy 68.228209 -521.063674)
			(xy 68.220089 -521.11885) (xy 68.204021 -521.172257) (xy 68.180349 -521.222754) (xy 68.149576 -521.269267)
			(xy 68.112359 -521.310804) (xy 68.069491 -521.346479) (xy 68.021885 -521.375533) (xy 67.970556 -521.397345)
			(xy 67.916599 -521.411451) (xy 67.861162 -521.417551) (xy 67.805428 -521.415514) (xy 67.750585 -521.405384)
			(xy 67.697801 -521.387377) (xy 67.648201 -521.361876) (xy 67.602843 -521.329425) (xy 67.562694 -521.290716)
			(xy 67.528608 -521.246573) (xy 67.501312 -521.197938) (xy 67.481389 -521.145847) (xy 67.469263 -521.09141)
			(xy 67.465192 -521.035788) (xy 66.507106 -521.035788) (xy 66.506597 -521.063674) (xy 66.498477 -521.11885)
			(xy 66.482409 -521.172257) (xy 66.458737 -521.222754) (xy 66.427964 -521.269267) (xy 66.390747 -521.310804)
			(xy 66.347879 -521.346479) (xy 66.300273 -521.375533) (xy 66.248944 -521.397345) (xy 66.194987 -521.411451)
			(xy 66.13955 -521.417551) (xy 66.083816 -521.415514) (xy 66.028973 -521.405384) (xy 65.976189 -521.387377)
			(xy 65.926589 -521.361876) (xy 65.881231 -521.329425) (xy 65.841082 -521.290716) (xy 65.806996 -521.246573)
			(xy 65.7797 -521.197938) (xy 65.759777 -521.145847) (xy 65.747651 -521.09141) (xy 65.74358 -521.035788)
			(xy 65.237106 -521.035788) (xy 65.236597 -521.063674) (xy 65.228477 -521.11885) (xy 65.212409 -521.172257)
			(xy 65.188737 -521.222754) (xy 65.157964 -521.269267) (xy 65.120747 -521.310804) (xy 65.077879 -521.346479)
			(xy 65.030273 -521.375533) (xy 64.978944 -521.397345) (xy 64.924987 -521.411451) (xy 64.86955 -521.417551)
			(xy 64.813816 -521.415514) (xy 64.758973 -521.405384) (xy 64.706189 -521.387377) (xy 64.656589 -521.361876)
			(xy 64.611231 -521.329425) (xy 64.571082 -521.290716) (xy 64.536996 -521.246573) (xy 64.5097 -521.197938)
			(xy 64.489777 -521.145847) (xy 64.477651 -521.09141) (xy 64.47358 -521.035788) (xy 63.267336 -521.035788)
			(xy 63.266827 -521.063674) (xy 63.258707 -521.11885) (xy 63.242639 -521.172257) (xy 63.218967 -521.222754)
			(xy 63.188194 -521.269267) (xy 63.150977 -521.310804) (xy 63.108109 -521.346479) (xy 63.060503 -521.375533)
			(xy 63.009174 -521.397345) (xy 62.955217 -521.411451) (xy 62.89978 -521.417551) (xy 62.844046 -521.415514)
			(xy 62.789203 -521.405384) (xy 62.736419 -521.387377) (xy 62.686819 -521.361876) (xy 62.641461 -521.329425)
			(xy 62.601312 -521.290716) (xy 62.567226 -521.246573) (xy 62.53993 -521.197938) (xy 62.520007 -521.145847)
			(xy 62.507881 -521.09141) (xy 62.50381 -521.035788) (xy 61.997336 -521.035788) (xy 61.996827 -521.063674)
			(xy 61.988707 -521.11885) (xy 61.972639 -521.172257) (xy 61.948967 -521.222754) (xy 61.918194 -521.269267)
			(xy 61.880977 -521.310804) (xy 61.838109 -521.346479) (xy 61.790503 -521.375533) (xy 61.739174 -521.397345)
			(xy 61.685217 -521.411451) (xy 61.62978 -521.417551) (xy 61.574046 -521.415514) (xy 61.519203 -521.405384)
			(xy 61.466419 -521.387377) (xy 61.416819 -521.361876) (xy 61.371461 -521.329425) (xy 61.331312 -521.290716)
			(xy 61.297226 -521.246573) (xy 61.26993 -521.197938) (xy 61.250007 -521.145847) (xy 61.237881 -521.09141)
			(xy 61.23381 -521.035788) (xy 60.462922 -521.035788) (xy 60.462413 -521.063674) (xy 60.454293 -521.11885)
			(xy 60.438225 -521.172257) (xy 60.414553 -521.222754) (xy 60.38378 -521.269267) (xy 60.346563 -521.310804)
			(xy 60.303695 -521.346479) (xy 60.256089 -521.375533) (xy 60.20476 -521.397345) (xy 60.150803 -521.411451)
			(xy 60.095366 -521.417551) (xy 60.039632 -521.415514) (xy 59.984789 -521.405384) (xy 59.932005 -521.387377)
			(xy 59.882405 -521.361876) (xy 59.837047 -521.329425) (xy 59.796898 -521.290716) (xy 59.762812 -521.246573)
			(xy 59.735516 -521.197938) (xy 59.715593 -521.145847) (xy 59.703467 -521.09141) (xy 59.699396 -521.035788)
			(xy 59.192922 -521.035788) (xy 59.192413 -521.063674) (xy 59.184293 -521.11885) (xy 59.168225 -521.172257)
			(xy 59.144553 -521.222754) (xy 59.11378 -521.269267) (xy 59.076563 -521.310804) (xy 59.033695 -521.346479)
			(xy 58.986089 -521.375533) (xy 58.93476 -521.397345) (xy 58.880803 -521.411451) (xy 58.825366 -521.417551)
			(xy 58.769632 -521.415514) (xy 58.714789 -521.405384) (xy 58.662005 -521.387377) (xy 58.612405 -521.361876)
			(xy 58.567047 -521.329425) (xy 58.526898 -521.290716) (xy 58.492812 -521.246573) (xy 58.465516 -521.197938)
			(xy 58.445593 -521.145847) (xy 58.433467 -521.09141) (xy 58.429396 -521.035788) (xy 57.93105 -521.035788)
			(xy 57.930541 -521.063674) (xy 57.922421 -521.11885) (xy 57.906353 -521.172257) (xy 57.882681 -521.222754)
			(xy 57.851908 -521.269267) (xy 57.814691 -521.310804) (xy 57.771823 -521.346479) (xy 57.724217 -521.375533)
			(xy 57.672888 -521.397345) (xy 57.618931 -521.411451) (xy 57.563494 -521.417551) (xy 57.50776 -521.415514)
			(xy 57.452917 -521.405384) (xy 57.400133 -521.387377) (xy 57.350533 -521.361876) (xy 57.305175 -521.329425)
			(xy 57.265026 -521.290716) (xy 57.23094 -521.246573) (xy 57.203644 -521.197938) (xy 57.183721 -521.145847)
			(xy 57.171595 -521.09141) (xy 57.167524 -521.035788) (xy 56.66105 -521.035788) (xy 56.660541 -521.063674)
			(xy 56.652421 -521.11885) (xy 56.636353 -521.172257) (xy 56.612681 -521.222754) (xy 56.581908 -521.269267)
			(xy 56.544691 -521.310804) (xy 56.501823 -521.346479) (xy 56.454217 -521.375533) (xy 56.402888 -521.397345)
			(xy 56.348931 -521.411451) (xy 56.293494 -521.417551) (xy 56.23776 -521.415514) (xy 56.182917 -521.405384)
			(xy 56.130133 -521.387377) (xy 56.080533 -521.361876) (xy 56.035175 -521.329425) (xy 55.995026 -521.290716)
			(xy 55.96094 -521.246573) (xy 55.933644 -521.197938) (xy 55.913721 -521.145847) (xy 55.901595 -521.09141)
			(xy 55.897524 -521.035788) (xy 36.055684 -521.035788) (xy 35.997482 -521.071825) (xy 35.919693 -521.110559)
			(xy 35.838661 -521.141951) (xy 35.755079 -521.165732) (xy 35.669659 -521.1817) (xy 35.58313 -521.189718)
			(xy 35.49623 -521.189718) (xy 35.409701 -521.1817) (xy 35.324281 -521.165732) (xy 35.240699 -521.141951)
			(xy 35.159667 -521.110559) (xy 35.081878 -521.071825) (xy 35.007994 -521.026078) (xy 34.938647 -520.973709)
			(xy 34.874427 -520.915165) (xy 34.815883 -520.850945) (xy 34.763514 -520.781598) (xy 34.717767 -520.707714)
			(xy 34.679033 -520.629925) (xy 34.647641 -520.548893) (xy 34.62386 -520.465311) (xy 34.607892 -520.379891)
			(xy 34.599874 -520.293362) (xy 31.399486 -520.293362) (xy 31.391468 -520.379891) (xy 31.3755 -520.465311)
			(xy 31.351719 -520.548893) (xy 31.320327 -520.629925) (xy 31.281593 -520.707714) (xy 31.235846 -520.781598)
			(xy 31.183477 -520.850945) (xy 31.124933 -520.915165) (xy 31.060713 -520.973709) (xy 30.991366 -521.026078)
			(xy 30.917482 -521.071825) (xy 30.839693 -521.110559) (xy 30.758661 -521.141951) (xy 30.675079 -521.165732)
			(xy 30.589659 -521.1817) (xy 30.50313 -521.189718) (xy 30.41623 -521.189718) (xy 30.329701 -521.1817)
			(xy 30.244281 -521.165732) (xy 30.160699 -521.141951) (xy 30.079667 -521.110559) (xy 30.001878 -521.071825)
			(xy 29.927994 -521.026078) (xy 29.858647 -520.973709) (xy 29.794427 -520.915165) (xy 29.735883 -520.850945)
			(xy 29.683514 -520.781598) (xy 29.637767 -520.707714) (xy 29.599033 -520.629925) (xy 29.567641 -520.548893)
			(xy 29.54386 -520.465311) (xy 29.527892 -520.379891) (xy 29.519874 -520.293362) (xy 8.779724 -520.293362)
			(xy 8.760343 -520.366742) (xy 8.729318 -520.45327) (xy 8.690968 -520.53681) (xy 8.645579 -520.616745)
			(xy 8.593487 -520.692482) (xy 8.535076 -520.76346) (xy 8.470781 -520.829154) (xy 8.401075 -520.889078)
			(xy 8.326477 -520.942788) (xy 8.247537 -520.989887) (xy 8.164841 -521.030025) (xy 8.079001 -521.062905)
			(xy 7.990652 -521.088285) (xy 7.900448 -521.105975) (xy 7.809057 -521.115846) (xy 7.717156 -521.117824)
			(xy 7.625425 -521.111894) (xy 7.534544 -521.0981) (xy 7.445185 -521.076546) (xy 7.358009 -521.047389)
			(xy 7.273663 -521.010846) (xy 7.19277 -520.967187) (xy 7.11593 -520.916736) (xy 7.043711 -520.859866)
			(xy 6.976649 -520.796999) (xy 6.915239 -520.728599) (xy 6.859936 -520.655174) (xy 6.81115 -520.577266)
			(xy 6.769242 -520.495453) (xy 6.734522 -520.410339) (xy 6.707248 -520.322557) (xy 6.687621 -520.232754)
			(xy 6.675786 -520.141597) (xy 6.671831 -520.04976) (xy 1.525016 -520.04976) (xy 1.525016 -522.833362)
			(xy 29.519874 -522.833362) (xy 29.519874 -522.746462) (xy 29.527892 -522.659933) (xy 29.54386 -522.574513)
			(xy 29.567641 -522.490931) (xy 29.599033 -522.409899) (xy 29.637767 -522.33211) (xy 29.683514 -522.258226)
			(xy 29.735883 -522.188879) (xy 29.794427 -522.124659) (xy 29.858647 -522.066115) (xy 29.927994 -522.013746)
			(xy 30.001878 -521.967999) (xy 30.079667 -521.929265) (xy 30.160699 -521.897873) (xy 30.244281 -521.874092)
			(xy 30.329701 -521.858124) (xy 30.41623 -521.850106) (xy 30.50313 -521.850106) (xy 30.589659 -521.858124)
			(xy 30.675079 -521.874092) (xy 30.758661 -521.897873) (xy 30.839693 -521.929265) (xy 30.917482 -521.967999)
			(xy 30.991366 -522.013746) (xy 31.060713 -522.066115) (xy 31.124933 -522.124659) (xy 31.183477 -522.188879)
			(xy 31.235846 -522.258226) (xy 31.281593 -522.33211) (xy 31.320327 -522.409899) (xy 31.351719 -522.490931)
			(xy 31.3755 -522.574513) (xy 31.391468 -522.659933) (xy 31.399486 -522.746462) (xy 31.399988 -522.789912)
			(xy 31.399486 -522.833362) (xy 34.599874 -522.833362) (xy 34.599874 -522.746462) (xy 34.607892 -522.659933)
			(xy 34.62386 -522.574513) (xy 34.647641 -522.490931) (xy 34.679033 -522.409899) (xy 34.717767 -522.33211)
			(xy 34.763514 -522.258226) (xy 34.815883 -522.188879) (xy 34.874427 -522.124659) (xy 34.938647 -522.066115)
			(xy 35.007994 -522.013746) (xy 35.081878 -521.967999) (xy 35.159667 -521.929265) (xy 35.240699 -521.897873)
			(xy 35.324281 -521.874092) (xy 35.409701 -521.858124) (xy 35.49623 -521.850106) (xy 35.58313 -521.850106)
			(xy 35.669659 -521.858124) (xy 35.755079 -521.874092) (xy 35.838661 -521.897873) (xy 35.919693 -521.929265)
			(xy 35.997482 -521.967999) (xy 36.071366 -522.013746) (xy 36.140713 -522.066115) (xy 36.204933 -522.124659)
			(xy 36.263477 -522.188879) (xy 36.315846 -522.258226) (xy 36.361593 -522.33211) (xy 36.400327 -522.409899)
			(xy 36.431719 -522.490931) (xy 36.4555 -522.574513) (xy 36.471468 -522.659933) (xy 36.479486 -522.746462)
			(xy 36.479988 -522.789912) (xy 36.479486 -522.833362) (xy 36.471468 -522.919891) (xy 36.456736 -522.9987)
			(xy 55.897524 -522.9987) (xy 55.901595 -522.943078) (xy 55.913721 -522.888641) (xy 55.933644 -522.83655)
			(xy 55.96094 -522.787915) (xy 55.995026 -522.743772) (xy 56.035175 -522.705063) (xy 56.080533 -522.672612)
			(xy 56.130133 -522.647111) (xy 56.182917 -522.629104) (xy 56.23776 -522.618974) (xy 56.293494 -522.616937)
			(xy 56.348931 -522.623037) (xy 56.402888 -522.637143) (xy 56.454217 -522.658955) (xy 56.501823 -522.688009)
			(xy 56.544691 -522.723684) (xy 56.581908 -522.765221) (xy 56.612681 -522.811734) (xy 56.636353 -522.862231)
			(xy 56.652421 -522.915638) (xy 56.660541 -522.970814) (xy 56.66105 -522.9987) (xy 57.167524 -522.9987)
			(xy 57.171595 -522.943078) (xy 57.183721 -522.888641) (xy 57.203644 -522.83655) (xy 57.23094 -522.787915)
			(xy 57.265026 -522.743772) (xy 57.305175 -522.705063) (xy 57.350533 -522.672612) (xy 57.400133 -522.647111)
			(xy 57.452917 -522.629104) (xy 57.50776 -522.618974) (xy 57.563494 -522.616937) (xy 57.618931 -522.623037)
			(xy 57.672888 -522.637143) (xy 57.724217 -522.658955) (xy 57.771823 -522.688009) (xy 57.814691 -522.723684)
			(xy 57.851908 -522.765221) (xy 57.882681 -522.811734) (xy 57.906353 -522.862231) (xy 57.922421 -522.915638)
			(xy 57.930541 -522.970814) (xy 57.93105 -522.9987) (xy 58.429396 -522.9987) (xy 58.433467 -522.943078)
			(xy 58.445593 -522.888641) (xy 58.465516 -522.83655) (xy 58.492812 -522.787915) (xy 58.526898 -522.743772)
			(xy 58.567047 -522.705063) (xy 58.612405 -522.672612) (xy 58.662005 -522.647111) (xy 58.714789 -522.629104)
			(xy 58.769632 -522.618974) (xy 58.825366 -522.616937) (xy 58.880803 -522.623037) (xy 58.93476 -522.637143)
			(xy 58.986089 -522.658955) (xy 59.033695 -522.688009) (xy 59.076563 -522.723684) (xy 59.11378 -522.765221)
			(xy 59.144553 -522.811734) (xy 59.168225 -522.862231) (xy 59.184293 -522.915638) (xy 59.192413 -522.970814)
			(xy 59.192922 -522.9987) (xy 59.699396 -522.9987) (xy 59.703467 -522.943078) (xy 59.715593 -522.888641)
			(xy 59.735516 -522.83655) (xy 59.762812 -522.787915) (xy 59.796898 -522.743772) (xy 59.837047 -522.705063)
			(xy 59.882405 -522.672612) (xy 59.932005 -522.647111) (xy 59.984789 -522.629104) (xy 60.039632 -522.618974)
			(xy 60.095366 -522.616937) (xy 60.150803 -522.623037) (xy 60.20476 -522.637143) (xy 60.256089 -522.658955)
			(xy 60.303695 -522.688009) (xy 60.346563 -522.723684) (xy 60.38378 -522.765221) (xy 60.414553 -522.811734)
			(xy 60.438225 -522.862231) (xy 60.454293 -522.915638) (xy 60.462413 -522.970814) (xy 60.462922 -522.9987)
			(xy 61.23381 -522.9987) (xy 61.237881 -522.943078) (xy 61.250007 -522.888641) (xy 61.26993 -522.83655)
			(xy 61.297226 -522.787915) (xy 61.331312 -522.743772) (xy 61.371461 -522.705063) (xy 61.416819 -522.672612)
			(xy 61.466419 -522.647111) (xy 61.519203 -522.629104) (xy 61.574046 -522.618974) (xy 61.62978 -522.616937)
			(xy 61.685217 -522.623037) (xy 61.739174 -522.637143) (xy 61.790503 -522.658955) (xy 61.838109 -522.688009)
			(xy 61.880977 -522.723684) (xy 61.918194 -522.765221) (xy 61.948967 -522.811734) (xy 61.972639 -522.862231)
			(xy 61.988707 -522.915638) (xy 61.996827 -522.970814) (xy 61.997336 -522.9987) (xy 62.50381 -522.9987)
			(xy 62.507881 -522.943078) (xy 62.520007 -522.888641) (xy 62.53993 -522.83655) (xy 62.567226 -522.787915)
			(xy 62.601312 -522.743772) (xy 62.641461 -522.705063) (xy 62.686819 -522.672612) (xy 62.736419 -522.647111)
			(xy 62.789203 -522.629104) (xy 62.844046 -522.618974) (xy 62.89978 -522.616937) (xy 62.955217 -522.623037)
			(xy 63.009174 -522.637143) (xy 63.060503 -522.658955) (xy 63.108109 -522.688009) (xy 63.150977 -522.723684)
			(xy 63.188194 -522.765221) (xy 63.218967 -522.811734) (xy 63.242639 -522.862231) (xy 63.258707 -522.915638)
			(xy 63.266827 -522.970814) (xy 63.267336 -522.9987) (xy 64.47358 -522.9987) (xy 64.477651 -522.943078)
			(xy 64.489777 -522.888641) (xy 64.5097 -522.83655) (xy 64.536996 -522.787915) (xy 64.571082 -522.743772)
			(xy 64.611231 -522.705063) (xy 64.656589 -522.672612) (xy 64.706189 -522.647111) (xy 64.758973 -522.629104)
			(xy 64.813816 -522.618974) (xy 64.86955 -522.616937) (xy 64.924987 -522.623037) (xy 64.978944 -522.637143)
			(xy 65.030273 -522.658955) (xy 65.077879 -522.688009) (xy 65.120747 -522.723684) (xy 65.157964 -522.765221)
			(xy 65.188737 -522.811734) (xy 65.212409 -522.862231) (xy 65.228477 -522.915638) (xy 65.236597 -522.970814)
			(xy 65.237106 -522.9987) (xy 65.74358 -522.9987) (xy 65.747651 -522.943078) (xy 65.759777 -522.888641)
			(xy 65.7797 -522.83655) (xy 65.806996 -522.787915) (xy 65.841082 -522.743772) (xy 65.881231 -522.705063)
			(xy 65.926589 -522.672612) (xy 65.976189 -522.647111) (xy 66.028973 -522.629104) (xy 66.083816 -522.618974)
			(xy 66.13955 -522.616937) (xy 66.194987 -522.623037) (xy 66.248944 -522.637143) (xy 66.300273 -522.658955)
			(xy 66.347879 -522.688009) (xy 66.390747 -522.723684) (xy 66.427964 -522.765221) (xy 66.458737 -522.811734)
			(xy 66.482409 -522.862231) (xy 66.498477 -522.915638) (xy 66.506597 -522.970814) (xy 66.507106 -522.9987)
			(xy 67.465192 -522.9987) (xy 67.469263 -522.943078) (xy 67.481389 -522.888641) (xy 67.501312 -522.83655)
			(xy 67.528608 -522.787915) (xy 67.562694 -522.743772) (xy 67.602843 -522.705063) (xy 67.648201 -522.672612)
			(xy 67.697801 -522.647111) (xy 67.750585 -522.629104) (xy 67.805428 -522.618974) (xy 67.861162 -522.616937)
			(xy 67.916599 -522.623037) (xy 67.970556 -522.637143) (xy 68.021885 -522.658955) (xy 68.069491 -522.688009)
			(xy 68.112359 -522.723684) (xy 68.149576 -522.765221) (xy 68.180349 -522.811734) (xy 68.204021 -522.862231)
			(xy 68.220089 -522.915638) (xy 68.228209 -522.970814) (xy 68.228718 -522.9987) (xy 68.735192 -522.9987)
			(xy 68.739263 -522.943078) (xy 68.751389 -522.888641) (xy 68.771312 -522.83655) (xy 68.798608 -522.787915)
			(xy 68.832694 -522.743772) (xy 68.872843 -522.705063) (xy 68.918201 -522.672612) (xy 68.967801 -522.647111)
			(xy 69.020585 -522.629104) (xy 69.075428 -522.618974) (xy 69.131162 -522.616937) (xy 69.186599 -522.623037)
			(xy 69.240556 -522.637143) (xy 69.291885 -522.658955) (xy 69.339491 -522.688009) (xy 69.382359 -522.723684)
			(xy 69.419576 -522.765221) (xy 69.450349 -522.811734) (xy 69.474021 -522.862231) (xy 69.490089 -522.915638)
			(xy 69.498209 -522.970814) (xy 69.498718 -522.9987) (xy 69.498209 -523.026586) (xy 69.490089 -523.081762)
			(xy 69.474021 -523.135169) (xy 69.450349 -523.185666) (xy 69.419576 -523.232179) (xy 69.382359 -523.273716)
			(xy 69.339491 -523.309391) (xy 69.291885 -523.338445) (xy 69.240556 -523.360257) (xy 69.186599 -523.374363)
			(xy 69.131162 -523.380463) (xy 69.075428 -523.378426) (xy 69.020585 -523.368296) (xy 68.967801 -523.350289)
			(xy 68.918201 -523.324788) (xy 68.872843 -523.292337) (xy 68.832694 -523.253628) (xy 68.798608 -523.209485)
			(xy 68.771312 -523.16085) (xy 68.751389 -523.108759) (xy 68.739263 -523.054322) (xy 68.735192 -522.9987)
			(xy 68.228718 -522.9987) (xy 68.228209 -523.026586) (xy 68.220089 -523.081762) (xy 68.204021 -523.135169)
			(xy 68.180349 -523.185666) (xy 68.149576 -523.232179) (xy 68.112359 -523.273716) (xy 68.069491 -523.309391)
			(xy 68.021885 -523.338445) (xy 67.970556 -523.360257) (xy 67.916599 -523.374363) (xy 67.861162 -523.380463)
			(xy 67.805428 -523.378426) (xy 67.750585 -523.368296) (xy 67.697801 -523.350289) (xy 67.648201 -523.324788)
			(xy 67.602843 -523.292337) (xy 67.562694 -523.253628) (xy 67.528608 -523.209485) (xy 67.501312 -523.16085)
			(xy 67.481389 -523.108759) (xy 67.469263 -523.054322) (xy 67.465192 -522.9987) (xy 66.507106 -522.9987)
			(xy 66.506597 -523.026586) (xy 66.498477 -523.081762) (xy 66.482409 -523.135169) (xy 66.458737 -523.185666)
			(xy 66.427964 -523.232179) (xy 66.390747 -523.273716) (xy 66.347879 -523.309391) (xy 66.300273 -523.338445)
			(xy 66.248944 -523.360257) (xy 66.194987 -523.374363) (xy 66.13955 -523.380463) (xy 66.083816 -523.378426)
			(xy 66.028973 -523.368296) (xy 65.976189 -523.350289) (xy 65.926589 -523.324788) (xy 65.881231 -523.292337)
			(xy 65.841082 -523.253628) (xy 65.806996 -523.209485) (xy 65.7797 -523.16085) (xy 65.759777 -523.108759)
			(xy 65.747651 -523.054322) (xy 65.74358 -522.9987) (xy 65.237106 -522.9987) (xy 65.236597 -523.026586)
			(xy 65.228477 -523.081762) (xy 65.212409 -523.135169) (xy 65.188737 -523.185666) (xy 65.157964 -523.232179)
			(xy 65.120747 -523.273716) (xy 65.077879 -523.309391) (xy 65.030273 -523.338445) (xy 64.978944 -523.360257)
			(xy 64.924987 -523.374363) (xy 64.86955 -523.380463) (xy 64.813816 -523.378426) (xy 64.758973 -523.368296)
			(xy 64.706189 -523.350289) (xy 64.656589 -523.324788) (xy 64.611231 -523.292337) (xy 64.571082 -523.253628)
			(xy 64.536996 -523.209485) (xy 64.5097 -523.16085) (xy 64.489777 -523.108759) (xy 64.477651 -523.054322)
			(xy 64.47358 -522.9987) (xy 63.267336 -522.9987) (xy 63.266827 -523.026586) (xy 63.258707 -523.081762)
			(xy 63.242639 -523.135169) (xy 63.218967 -523.185666) (xy 63.188194 -523.232179) (xy 63.150977 -523.273716)
			(xy 63.108109 -523.309391) (xy 63.060503 -523.338445) (xy 63.009174 -523.360257) (xy 62.955217 -523.374363)
			(xy 62.89978 -523.380463) (xy 62.844046 -523.378426) (xy 62.789203 -523.368296) (xy 62.736419 -523.350289)
			(xy 62.686819 -523.324788) (xy 62.641461 -523.292337) (xy 62.601312 -523.253628) (xy 62.567226 -523.209485)
			(xy 62.53993 -523.16085) (xy 62.520007 -523.108759) (xy 62.507881 -523.054322) (xy 62.50381 -522.9987)
			(xy 61.997336 -522.9987) (xy 61.996827 -523.026586) (xy 61.988707 -523.081762) (xy 61.972639 -523.135169)
			(xy 61.948967 -523.185666) (xy 61.918194 -523.232179) (xy 61.880977 -523.273716) (xy 61.838109 -523.309391)
			(xy 61.790503 -523.338445) (xy 61.739174 -523.360257) (xy 61.685217 -523.374363) (xy 61.62978 -523.380463)
			(xy 61.574046 -523.378426) (xy 61.519203 -523.368296) (xy 61.466419 -523.350289) (xy 61.416819 -523.324788)
			(xy 61.371461 -523.292337) (xy 61.331312 -523.253628) (xy 61.297226 -523.209485) (xy 61.26993 -523.16085)
			(xy 61.250007 -523.108759) (xy 61.237881 -523.054322) (xy 61.23381 -522.9987) (xy 60.462922 -522.9987)
			(xy 60.462413 -523.026586) (xy 60.454293 -523.081762) (xy 60.438225 -523.135169) (xy 60.414553 -523.185666)
			(xy 60.38378 -523.232179) (xy 60.346563 -523.273716) (xy 60.303695 -523.309391) (xy 60.256089 -523.338445)
			(xy 60.20476 -523.360257) (xy 60.150803 -523.374363) (xy 60.095366 -523.380463) (xy 60.039632 -523.378426)
			(xy 59.984789 -523.368296) (xy 59.932005 -523.350289) (xy 59.882405 -523.324788) (xy 59.837047 -523.292337)
			(xy 59.796898 -523.253628) (xy 59.762812 -523.209485) (xy 59.735516 -523.16085) (xy 59.715593 -523.108759)
			(xy 59.703467 -523.054322) (xy 59.699396 -522.9987) (xy 59.192922 -522.9987) (xy 59.192413 -523.026586)
			(xy 59.184293 -523.081762) (xy 59.168225 -523.135169) (xy 59.144553 -523.185666) (xy 59.11378 -523.232179)
			(xy 59.076563 -523.273716) (xy 59.033695 -523.309391) (xy 58.986089 -523.338445) (xy 58.93476 -523.360257)
			(xy 58.880803 -523.374363) (xy 58.825366 -523.380463) (xy 58.769632 -523.378426) (xy 58.714789 -523.368296)
			(xy 58.662005 -523.350289) (xy 58.612405 -523.324788) (xy 58.567047 -523.292337) (xy 58.526898 -523.253628)
			(xy 58.492812 -523.209485) (xy 58.465516 -523.16085) (xy 58.445593 -523.108759) (xy 58.433467 -523.054322)
			(xy 58.429396 -522.9987) (xy 57.93105 -522.9987) (xy 57.930541 -523.026586) (xy 57.922421 -523.081762)
			(xy 57.906353 -523.135169) (xy 57.882681 -523.185666) (xy 57.851908 -523.232179) (xy 57.814691 -523.273716)
			(xy 57.771823 -523.309391) (xy 57.724217 -523.338445) (xy 57.672888 -523.360257) (xy 57.618931 -523.374363)
			(xy 57.563494 -523.380463) (xy 57.50776 -523.378426) (xy 57.452917 -523.368296) (xy 57.400133 -523.350289)
			(xy 57.350533 -523.324788) (xy 57.305175 -523.292337) (xy 57.265026 -523.253628) (xy 57.23094 -523.209485)
			(xy 57.203644 -523.16085) (xy 57.183721 -523.108759) (xy 57.171595 -523.054322) (xy 57.167524 -522.9987)
			(xy 56.66105 -522.9987) (xy 56.660541 -523.026586) (xy 56.652421 -523.081762) (xy 56.636353 -523.135169)
			(xy 56.612681 -523.185666) (xy 56.581908 -523.232179) (xy 56.544691 -523.273716) (xy 56.501823 -523.309391)
			(xy 56.454217 -523.338445) (xy 56.402888 -523.360257) (xy 56.348931 -523.374363) (xy 56.293494 -523.380463)
			(xy 56.23776 -523.378426) (xy 56.182917 -523.368296) (xy 56.130133 -523.350289) (xy 56.080533 -523.324788)
			(xy 56.035175 -523.292337) (xy 55.995026 -523.253628) (xy 55.96094 -523.209485) (xy 55.933644 -523.16085)
			(xy 55.913721 -523.108759) (xy 55.901595 -523.054322) (xy 55.897524 -522.9987) (xy 36.456736 -522.9987)
			(xy 36.4555 -523.005311) (xy 36.431719 -523.088893) (xy 36.400327 -523.169925) (xy 36.361593 -523.247714)
			(xy 36.315846 -523.321598) (xy 36.263477 -523.390945) (xy 36.204933 -523.455165) (xy 36.140713 -523.513709)
			(xy 36.071366 -523.566078) (xy 35.997482 -523.611825) (xy 35.919693 -523.650559) (xy 35.838661 -523.681951)
			(xy 35.755079 -523.705732) (xy 35.669659 -523.7217) (xy 35.58313 -523.729718) (xy 35.49623 -523.729718)
			(xy 35.409701 -523.7217) (xy 35.324281 -523.705732) (xy 35.240699 -523.681951) (xy 35.159667 -523.650559)
			(xy 35.081878 -523.611825) (xy 35.007994 -523.566078) (xy 34.938647 -523.513709) (xy 34.874427 -523.455165)
			(xy 34.815883 -523.390945) (xy 34.763514 -523.321598) (xy 34.717767 -523.247714) (xy 34.679033 -523.169925)
			(xy 34.647641 -523.088893) (xy 34.62386 -523.005311) (xy 34.607892 -522.919891) (xy 34.599874 -522.833362)
			(xy 31.399486 -522.833362) (xy 31.391468 -522.919891) (xy 31.3755 -523.005311) (xy 31.351719 -523.088893)
			(xy 31.320327 -523.169925) (xy 31.281593 -523.247714) (xy 31.235846 -523.321598) (xy 31.183477 -523.390945)
			(xy 31.124933 -523.455165) (xy 31.060713 -523.513709) (xy 30.991366 -523.566078) (xy 30.917482 -523.611825)
			(xy 30.839693 -523.650559) (xy 30.758661 -523.681951) (xy 30.675079 -523.705732) (xy 30.589659 -523.7217)
			(xy 30.50313 -523.729718) (xy 30.41623 -523.729718) (xy 30.329701 -523.7217) (xy 30.244281 -523.705732)
			(xy 30.160699 -523.681951) (xy 30.079667 -523.650559) (xy 30.001878 -523.611825) (xy 29.927994 -523.566078)
			(xy 29.858647 -523.513709) (xy 29.794427 -523.455165) (xy 29.735883 -523.390945) (xy 29.683514 -523.321598)
			(xy 29.637767 -523.247714) (xy 29.599033 -523.169925) (xy 29.567641 -523.088893) (xy 29.54386 -523.005311)
			(xy 29.527892 -522.919891) (xy 29.519874 -522.833362) (xy 1.525016 -522.833362) (xy 1.525016 -524.347948)
			(xy 1.52551 -524.364603) (xy 1.534131 -524.396777) (xy 1.550786 -524.425624) (xy 1.57434 -524.449176)
			(xy 1.603187 -524.46583) (xy 1.635361 -524.47445) (xy 1.652016 -524.474948) (xy 23.50008 -524.474948)
			(xy 23.576725 -524.475425) (xy 23.729819 -524.483189) (xy 23.882323 -524.498697) (xy 24.033845 -524.52191)
			(xy 24.183998 -524.552768) (xy 24.332394 -524.591192) (xy 24.478654 -524.637083) (xy 24.622401 -524.690324)
			(xy 24.763268 -524.750778) (xy 24.900891 -524.818289) (xy 25.034918 -524.892685) (xy 25.165004 -524.973774)
			(xy 25.290817 -525.061348) (xy 25.412031 -525.155182) (xy 25.528338 -525.255036) (xy 25.639437 -525.360652)
			(xy 25.651518 -525.373362) (xy 29.519874 -525.373362) (xy 29.519874 -525.286462) (xy 29.527892 -525.199933)
			(xy 29.54386 -525.114513) (xy 29.567641 -525.030931) (xy 29.599033 -524.949899) (xy 29.637767 -524.87211)
			(xy 29.683514 -524.798226) (xy 29.735883 -524.728879) (xy 29.794427 -524.664659) (xy 29.858647 -524.606115)
			(xy 29.927994 -524.553746) (xy 30.001878 -524.507999) (xy 30.079667 -524.469265) (xy 30.160699 -524.437873)
			(xy 30.244281 -524.414092) (xy 30.329701 -524.398124) (xy 30.41623 -524.390106) (xy 30.50313 -524.390106)
			(xy 30.589659 -524.398124) (xy 30.675079 -524.414092) (xy 30.758661 -524.437873) (xy 30.839693 -524.469265)
			(xy 30.917482 -524.507999) (xy 30.991366 -524.553746) (xy 31.060713 -524.606115) (xy 31.124933 -524.664659)
			(xy 31.183477 -524.728879) (xy 31.235846 -524.798226) (xy 31.281593 -524.87211) (xy 31.320327 -524.949899)
			(xy 31.351719 -525.030931) (xy 31.3755 -525.114513) (xy 31.391468 -525.199933) (xy 31.399486 -525.286462)
			(xy 31.399988 -525.329912) (xy 31.399486 -525.373362) (xy 34.599874 -525.373362) (xy 34.599874 -525.286462)
			(xy 34.607892 -525.199933) (xy 34.62386 -525.114513) (xy 34.647641 -525.030931) (xy 34.679033 -524.949899)
			(xy 34.717767 -524.87211) (xy 34.763514 -524.798226) (xy 34.815883 -524.728879) (xy 34.874427 -524.664659)
			(xy 34.938647 -524.606115) (xy 35.007994 -524.553746) (xy 35.081878 -524.507999) (xy 35.159667 -524.469265)
			(xy 35.240699 -524.437873) (xy 35.324281 -524.414092) (xy 35.409701 -524.398124) (xy 35.49623 -524.390106)
			(xy 35.58313 -524.390106) (xy 35.669659 -524.398124) (xy 35.755079 -524.414092) (xy 35.838661 -524.437873)
			(xy 35.919693 -524.469265) (xy 35.997482 -524.507999) (xy 36.071366 -524.553746) (xy 36.140713 -524.606115)
			(xy 36.204933 -524.664659) (xy 36.263477 -524.728879) (xy 36.315846 -524.798226) (xy 36.361593 -524.87211)
			(xy 36.400327 -524.949899) (xy 36.431719 -525.030931) (xy 36.4555 -525.114513) (xy 36.460677 -525.142206)
			(xy 55.897524 -525.142206) (xy 55.901595 -525.086584) (xy 55.913721 -525.032147) (xy 55.933644 -524.980056)
			(xy 55.96094 -524.931421) (xy 55.995026 -524.887278) (xy 56.035175 -524.848569) (xy 56.080533 -524.816118)
			(xy 56.130133 -524.790617) (xy 56.182917 -524.77261) (xy 56.23776 -524.76248) (xy 56.293494 -524.760443)
			(xy 56.348931 -524.766543) (xy 56.402888 -524.780649) (xy 56.454217 -524.802461) (xy 56.501823 -524.831515)
			(xy 56.544691 -524.86719) (xy 56.581908 -524.908727) (xy 56.612681 -524.95524) (xy 56.636353 -525.005737)
			(xy 56.652421 -525.059144) (xy 56.660541 -525.11432) (xy 56.66105 -525.142206) (xy 57.167524 -525.142206)
			(xy 57.171595 -525.086584) (xy 57.183721 -525.032147) (xy 57.203644 -524.980056) (xy 57.23094 -524.931421)
			(xy 57.265026 -524.887278) (xy 57.305175 -524.848569) (xy 57.350533 -524.816118) (xy 57.400133 -524.790617)
			(xy 57.452917 -524.77261) (xy 57.50776 -524.76248) (xy 57.563494 -524.760443) (xy 57.618931 -524.766543)
			(xy 57.672888 -524.780649) (xy 57.724217 -524.802461) (xy 57.771823 -524.831515) (xy 57.814691 -524.86719)
			(xy 57.851908 -524.908727) (xy 57.882681 -524.95524) (xy 57.906353 -525.005737) (xy 57.922421 -525.059144)
			(xy 57.930541 -525.11432) (xy 57.93105 -525.142206) (xy 58.429396 -525.142206) (xy 58.433467 -525.086584)
			(xy 58.445593 -525.032147) (xy 58.465516 -524.980056) (xy 58.492812 -524.931421) (xy 58.526898 -524.887278)
			(xy 58.567047 -524.848569) (xy 58.612405 -524.816118) (xy 58.662005 -524.790617) (xy 58.714789 -524.77261)
			(xy 58.769632 -524.76248) (xy 58.825366 -524.760443) (xy 58.880803 -524.766543) (xy 58.93476 -524.780649)
			(xy 58.986089 -524.802461) (xy 59.033695 -524.831515) (xy 59.076563 -524.86719) (xy 59.11378 -524.908727)
			(xy 59.144553 -524.95524) (xy 59.168225 -525.005737) (xy 59.184293 -525.059144) (xy 59.192413 -525.11432)
			(xy 59.192922 -525.142206) (xy 59.699396 -525.142206) (xy 59.703467 -525.086584) (xy 59.715593 -525.032147)
			(xy 59.735516 -524.980056) (xy 59.762812 -524.931421) (xy 59.796898 -524.887278) (xy 59.837047 -524.848569)
			(xy 59.882405 -524.816118) (xy 59.932005 -524.790617) (xy 59.984789 -524.77261) (xy 60.039632 -524.76248)
			(xy 60.095366 -524.760443) (xy 60.150803 -524.766543) (xy 60.20476 -524.780649) (xy 60.256089 -524.802461)
			(xy 60.303695 -524.831515) (xy 60.346563 -524.86719) (xy 60.38378 -524.908727) (xy 60.414553 -524.95524)
			(xy 60.438225 -525.005737) (xy 60.454293 -525.059144) (xy 60.462413 -525.11432) (xy 60.462922 -525.142206)
			(xy 61.23381 -525.142206) (xy 61.237881 -525.086584) (xy 61.250007 -525.032147) (xy 61.26993 -524.980056)
			(xy 61.297226 -524.931421) (xy 61.331312 -524.887278) (xy 61.371461 -524.848569) (xy 61.416819 -524.816118)
			(xy 61.466419 -524.790617) (xy 61.519203 -524.77261) (xy 61.574046 -524.76248) (xy 61.62978 -524.760443)
			(xy 61.685217 -524.766543) (xy 61.739174 -524.780649) (xy 61.790503 -524.802461) (xy 61.838109 -524.831515)
			(xy 61.880977 -524.86719) (xy 61.918194 -524.908727) (xy 61.948967 -524.95524) (xy 61.972639 -525.005737)
			(xy 61.988707 -525.059144) (xy 61.996827 -525.11432) (xy 61.997336 -525.142206) (xy 62.50381 -525.142206)
			(xy 62.507881 -525.086584) (xy 62.520007 -525.032147) (xy 62.53993 -524.980056) (xy 62.567226 -524.931421)
			(xy 62.601312 -524.887278) (xy 62.641461 -524.848569) (xy 62.686819 -524.816118) (xy 62.736419 -524.790617)
			(xy 62.789203 -524.77261) (xy 62.844046 -524.76248) (xy 62.89978 -524.760443) (xy 62.955217 -524.766543)
			(xy 63.009174 -524.780649) (xy 63.060503 -524.802461) (xy 63.108109 -524.831515) (xy 63.150977 -524.86719)
			(xy 63.188194 -524.908727) (xy 63.218967 -524.95524) (xy 63.242639 -525.005737) (xy 63.258707 -525.059144)
			(xy 63.266827 -525.11432) (xy 63.267336 -525.142206) (xy 64.47358 -525.142206) (xy 64.477651 -525.086584)
			(xy 64.489777 -525.032147) (xy 64.5097 -524.980056) (xy 64.536996 -524.931421) (xy 64.571082 -524.887278)
			(xy 64.611231 -524.848569) (xy 64.656589 -524.816118) (xy 64.706189 -524.790617) (xy 64.758973 -524.77261)
			(xy 64.813816 -524.76248) (xy 64.86955 -524.760443) (xy 64.924987 -524.766543) (xy 64.978944 -524.780649)
			(xy 65.030273 -524.802461) (xy 65.077879 -524.831515) (xy 65.120747 -524.86719) (xy 65.157964 -524.908727)
			(xy 65.188737 -524.95524) (xy 65.212409 -525.005737) (xy 65.228477 -525.059144) (xy 65.236597 -525.11432)
			(xy 65.237106 -525.142206) (xy 65.74358 -525.142206) (xy 65.747651 -525.086584) (xy 65.759777 -525.032147)
			(xy 65.7797 -524.980056) (xy 65.806996 -524.931421) (xy 65.841082 -524.887278) (xy 65.881231 -524.848569)
			(xy 65.926589 -524.816118) (xy 65.976189 -524.790617) (xy 66.028973 -524.77261) (xy 66.083816 -524.76248)
			(xy 66.13955 -524.760443) (xy 66.194987 -524.766543) (xy 66.248944 -524.780649) (xy 66.300273 -524.802461)
			(xy 66.347879 -524.831515) (xy 66.390747 -524.86719) (xy 66.427964 -524.908727) (xy 66.458737 -524.95524)
			(xy 66.482409 -525.005737) (xy 66.498477 -525.059144) (xy 66.506597 -525.11432) (xy 66.507106 -525.142206)
			(xy 67.465192 -525.142206) (xy 67.469263 -525.086584) (xy 67.481389 -525.032147) (xy 67.501312 -524.980056)
			(xy 67.528608 -524.931421) (xy 67.562694 -524.887278) (xy 67.602843 -524.848569) (xy 67.648201 -524.816118)
			(xy 67.697801 -524.790617) (xy 67.750585 -524.77261) (xy 67.805428 -524.76248) (xy 67.861162 -524.760443)
			(xy 67.916599 -524.766543) (xy 67.970556 -524.780649) (xy 68.021885 -524.802461) (xy 68.069491 -524.831515)
			(xy 68.112359 -524.86719) (xy 68.149576 -524.908727) (xy 68.180349 -524.95524) (xy 68.204021 -525.005737)
			(xy 68.220089 -525.059144) (xy 68.228209 -525.11432) (xy 68.228718 -525.142206) (xy 68.735192 -525.142206)
			(xy 68.739263 -525.086584) (xy 68.751389 -525.032147) (xy 68.771312 -524.980056) (xy 68.798608 -524.931421)
			(xy 68.832694 -524.887278) (xy 68.872843 -524.848569) (xy 68.918201 -524.816118) (xy 68.967801 -524.790617)
			(xy 69.020585 -524.77261) (xy 69.075428 -524.76248) (xy 69.131162 -524.760443) (xy 69.186599 -524.766543)
			(xy 69.240556 -524.780649) (xy 69.291885 -524.802461) (xy 69.339491 -524.831515) (xy 69.382359 -524.86719)
			(xy 69.419576 -524.908727) (xy 69.450349 -524.95524) (xy 69.474021 -525.005737) (xy 69.490089 -525.059144)
			(xy 69.498209 -525.11432) (xy 69.498718 -525.142206) (xy 69.498209 -525.170092) (xy 69.490089 -525.225268)
			(xy 69.474021 -525.278675) (xy 69.450349 -525.329172) (xy 69.419576 -525.375685) (xy 69.382359 -525.417222)
			(xy 69.339491 -525.452897) (xy 69.291885 -525.481951) (xy 69.240556 -525.503763) (xy 69.186599 -525.517869)
			(xy 69.131162 -525.523969) (xy 69.075428 -525.521932) (xy 69.020585 -525.511802) (xy 68.967801 -525.493795)
			(xy 68.918201 -525.468294) (xy 68.872843 -525.435843) (xy 68.832694 -525.397134) (xy 68.798608 -525.352991)
			(xy 68.771312 -525.304356) (xy 68.751389 -525.252265) (xy 68.739263 -525.197828) (xy 68.735192 -525.142206)
			(xy 68.228718 -525.142206) (xy 68.228209 -525.170092) (xy 68.220089 -525.225268) (xy 68.204021 -525.278675)
			(xy 68.180349 -525.329172) (xy 68.149576 -525.375685) (xy 68.112359 -525.417222) (xy 68.069491 -525.452897)
			(xy 68.021885 -525.481951) (xy 67.970556 -525.503763) (xy 67.916599 -525.517869) (xy 67.861162 -525.523969)
			(xy 67.805428 -525.521932) (xy 67.750585 -525.511802) (xy 67.697801 -525.493795) (xy 67.648201 -525.468294)
			(xy 67.602843 -525.435843) (xy 67.562694 -525.397134) (xy 67.528608 -525.352991) (xy 67.501312 -525.304356)
			(xy 67.481389 -525.252265) (xy 67.469263 -525.197828) (xy 67.465192 -525.142206) (xy 66.507106 -525.142206)
			(xy 66.506597 -525.170092) (xy 66.498477 -525.225268) (xy 66.482409 -525.278675) (xy 66.458737 -525.329172)
			(xy 66.427964 -525.375685) (xy 66.390747 -525.417222) (xy 66.347879 -525.452897) (xy 66.300273 -525.481951)
			(xy 66.248944 -525.503763) (xy 66.194987 -525.517869) (xy 66.13955 -525.523969) (xy 66.083816 -525.521932)
			(xy 66.028973 -525.511802) (xy 65.976189 -525.493795) (xy 65.926589 -525.468294) (xy 65.881231 -525.435843)
			(xy 65.841082 -525.397134) (xy 65.806996 -525.352991) (xy 65.7797 -525.304356) (xy 65.759777 -525.252265)
			(xy 65.747651 -525.197828) (xy 65.74358 -525.142206) (xy 65.237106 -525.142206) (xy 65.236597 -525.170092)
			(xy 65.228477 -525.225268) (xy 65.212409 -525.278675) (xy 65.188737 -525.329172) (xy 65.157964 -525.375685)
			(xy 65.120747 -525.417222) (xy 65.077879 -525.452897) (xy 65.030273 -525.481951) (xy 64.978944 -525.503763)
			(xy 64.924987 -525.517869) (xy 64.86955 -525.523969) (xy 64.813816 -525.521932) (xy 64.758973 -525.511802)
			(xy 64.706189 -525.493795) (xy 64.656589 -525.468294) (xy 64.611231 -525.435843) (xy 64.571082 -525.397134)
			(xy 64.536996 -525.352991) (xy 64.5097 -525.304356) (xy 64.489777 -525.252265) (xy 64.477651 -525.197828)
			(xy 64.47358 -525.142206) (xy 63.267336 -525.142206) (xy 63.266827 -525.170092) (xy 63.258707 -525.225268)
			(xy 63.242639 -525.278675) (xy 63.218967 -525.329172) (xy 63.188194 -525.375685) (xy 63.150977 -525.417222)
			(xy 63.108109 -525.452897) (xy 63.060503 -525.481951) (xy 63.009174 -525.503763) (xy 62.955217 -525.517869)
			(xy 62.89978 -525.523969) (xy 62.844046 -525.521932) (xy 62.789203 -525.511802) (xy 62.736419 -525.493795)
			(xy 62.686819 -525.468294) (xy 62.641461 -525.435843) (xy 62.601312 -525.397134) (xy 62.567226 -525.352991)
			(xy 62.53993 -525.304356) (xy 62.520007 -525.252265) (xy 62.507881 -525.197828) (xy 62.50381 -525.142206)
			(xy 61.997336 -525.142206) (xy 61.996827 -525.170092) (xy 61.988707 -525.225268) (xy 61.972639 -525.278675)
			(xy 61.948967 -525.329172) (xy 61.918194 -525.375685) (xy 61.880977 -525.417222) (xy 61.838109 -525.452897)
			(xy 61.790503 -525.481951) (xy 61.739174 -525.503763) (xy 61.685217 -525.517869) (xy 61.62978 -525.523969)
			(xy 61.574046 -525.521932) (xy 61.519203 -525.511802) (xy 61.466419 -525.493795) (xy 61.416819 -525.468294)
			(xy 61.371461 -525.435843) (xy 61.331312 -525.397134) (xy 61.297226 -525.352991) (xy 61.26993 -525.304356)
			(xy 61.250007 -525.252265) (xy 61.237881 -525.197828) (xy 61.23381 -525.142206) (xy 60.462922 -525.142206)
			(xy 60.462413 -525.170092) (xy 60.454293 -525.225268) (xy 60.438225 -525.278675) (xy 60.414553 -525.329172)
			(xy 60.38378 -525.375685) (xy 60.346563 -525.417222) (xy 60.303695 -525.452897) (xy 60.256089 -525.481951)
			(xy 60.20476 -525.503763) (xy 60.150803 -525.517869) (xy 60.095366 -525.523969) (xy 60.039632 -525.521932)
			(xy 59.984789 -525.511802) (xy 59.932005 -525.493795) (xy 59.882405 -525.468294) (xy 59.837047 -525.435843)
			(xy 59.796898 -525.397134) (xy 59.762812 -525.352991) (xy 59.735516 -525.304356) (xy 59.715593 -525.252265)
			(xy 59.703467 -525.197828) (xy 59.699396 -525.142206) (xy 59.192922 -525.142206) (xy 59.192413 -525.170092)
			(xy 59.184293 -525.225268) (xy 59.168225 -525.278675) (xy 59.144553 -525.329172) (xy 59.11378 -525.375685)
			(xy 59.076563 -525.417222) (xy 59.033695 -525.452897) (xy 58.986089 -525.481951) (xy 58.93476 -525.503763)
			(xy 58.880803 -525.517869) (xy 58.825366 -525.523969) (xy 58.769632 -525.521932) (xy 58.714789 -525.511802)
			(xy 58.662005 -525.493795) (xy 58.612405 -525.468294) (xy 58.567047 -525.435843) (xy 58.526898 -525.397134)
			(xy 58.492812 -525.352991) (xy 58.465516 -525.304356) (xy 58.445593 -525.252265) (xy 58.433467 -525.197828)
			(xy 58.429396 -525.142206) (xy 57.93105 -525.142206) (xy 57.930541 -525.170092) (xy 57.922421 -525.225268)
			(xy 57.906353 -525.278675) (xy 57.882681 -525.329172) (xy 57.851908 -525.375685) (xy 57.814691 -525.417222)
			(xy 57.771823 -525.452897) (xy 57.724217 -525.481951) (xy 57.672888 -525.503763) (xy 57.618931 -525.517869)
			(xy 57.563494 -525.523969) (xy 57.50776 -525.521932) (xy 57.452917 -525.511802) (xy 57.400133 -525.493795)
			(xy 57.350533 -525.468294) (xy 57.305175 -525.435843) (xy 57.265026 -525.397134) (xy 57.23094 -525.352991)
			(xy 57.203644 -525.304356) (xy 57.183721 -525.252265) (xy 57.171595 -525.197828) (xy 57.167524 -525.142206)
			(xy 56.66105 -525.142206) (xy 56.660541 -525.170092) (xy 56.652421 -525.225268) (xy 56.636353 -525.278675)
			(xy 56.612681 -525.329172) (xy 56.581908 -525.375685) (xy 56.544691 -525.417222) (xy 56.501823 -525.452897)
			(xy 56.454217 -525.481951) (xy 56.402888 -525.503763) (xy 56.348931 -525.517869) (xy 56.293494 -525.523969)
			(xy 56.23776 -525.521932) (xy 56.182917 -525.511802) (xy 56.130133 -525.493795) (xy 56.080533 -525.468294)
			(xy 56.035175 -525.435843) (xy 55.995026 -525.397134) (xy 55.96094 -525.352991) (xy 55.933644 -525.304356)
			(xy 55.913721 -525.252265) (xy 55.901595 -525.197828) (xy 55.897524 -525.142206) (xy 36.460677 -525.142206)
			(xy 36.471468 -525.199933) (xy 36.479486 -525.286462) (xy 36.479988 -525.329912) (xy 36.479486 -525.373362)
			(xy 36.471468 -525.459891) (xy 36.4555 -525.545311) (xy 36.431719 -525.628893) (xy 36.400327 -525.709925)
			(xy 36.361593 -525.787714) (xy 36.315846 -525.861598) (xy 36.263477 -525.930945) (xy 36.204933 -525.995165)
			(xy 36.140713 -526.053709) (xy 36.071366 -526.106078) (xy 35.997482 -526.151825) (xy 35.919693 -526.190559)
			(xy 35.838661 -526.221951) (xy 35.755079 -526.245732) (xy 35.669659 -526.2617) (xy 35.58313 -526.269718)
			(xy 35.49623 -526.269718) (xy 35.409701 -526.2617) (xy 35.324281 -526.245732) (xy 35.240699 -526.221951)
			(xy 35.159667 -526.190559) (xy 35.081878 -526.151825) (xy 35.007994 -526.106078) (xy 34.938647 -526.053709)
			(xy 34.874427 -525.995165) (xy 34.815883 -525.930945) (xy 34.763514 -525.861598) (xy 34.717767 -525.787714)
			(xy 34.679033 -525.709925) (xy 34.647641 -525.628893) (xy 34.62386 -525.545311) (xy 34.607892 -525.459891)
			(xy 34.599874 -525.373362) (xy 31.399486 -525.373362) (xy 31.391468 -525.459891) (xy 31.3755 -525.545311)
			(xy 31.351719 -525.628893) (xy 31.320327 -525.709925) (xy 31.281593 -525.787714) (xy 31.235846 -525.861598)
			(xy 31.183477 -525.930945) (xy 31.124933 -525.995165) (xy 31.060713 -526.053709) (xy 30.991366 -526.106078)
			(xy 30.917482 -526.151825) (xy 30.839693 -526.190559) (xy 30.758661 -526.221951) (xy 30.675079 -526.245732)
			(xy 30.589659 -526.2617) (xy 30.50313 -526.269718) (xy 30.41623 -526.269718) (xy 30.329701 -526.2617)
			(xy 30.244281 -526.245732) (xy 30.160699 -526.221951) (xy 30.079667 -526.190559) (xy 30.001878 -526.151825)
			(xy 29.927994 -526.106078) (xy 29.858647 -526.053709) (xy 29.794427 -525.995165) (xy 29.735883 -525.930945)
			(xy 29.683514 -525.861598) (xy 29.637767 -525.787714) (xy 29.599033 -525.709925) (xy 29.567641 -525.628893)
			(xy 29.54386 -525.545311) (xy 29.527892 -525.459891) (xy 29.519874 -525.373362) (xy 25.651518 -525.373362)
			(xy 25.745044 -525.471761) (xy 25.844887 -525.588076) (xy 25.938711 -525.709299) (xy 26.026274 -525.83512)
			(xy 26.107351 -525.965213) (xy 26.181735 -526.099247) (xy 26.249234 -526.236876) (xy 26.309675 -526.377748)
			(xy 26.362904 -526.5215) (xy 26.408782 -526.667764) (xy 26.447193 -526.816164) (xy 26.478038 -526.966319)
			(xy 26.501237 -527.117843) (xy 26.516732 -527.270348) (xy 26.524482 -527.423443) (xy 26.524966 -527.500088)
			(xy 26.524966 -528.34794) (xy 26.525514 -528.364586) (xy 26.534138 -528.396743) (xy 26.550788 -528.425574)
			(xy 26.57433 -528.449116) (xy 26.603162 -528.465764) (xy 26.635319 -528.474387) (xy 26.651966 -528.47494)
		)
		(stroke
			(width 0)
			(type solid)
		)
		(fill yes)
		(layer "In5.Cu")
		(net "GND")
	)
	(gr_line
		(start 0 -524.500094)
		(end 0 -5.500116)
		(stroke
			(width 1.016)
			(type default)
		)
		(layer "In6.Cu")
	)
	(gr_arc
		(start 0 -524.500094)
		(mid 0.439393 -525.560749)
		(end 1.500124 -525.999964)
		(stroke
			(width 1.016)
			(type default)
		)
		(layer "In6.Cu")
	)
	(gr_poly
		(pts
			(xy 101.000052 -529.49094) (xy 101.055822 -529.490433) (xy 101.167051 -529.482101) (xy 101.277346 -529.46548)
			(xy 101.38609 -529.440662) (xy 101.492675 -529.407788) (xy 101.596506 -529.367039) (xy 101.697001 -529.318645)
			(xy 101.793598 -529.262876) (xy 101.885758 -529.200044) (xy 101.972964 -529.130501) (xy 102.054729 -529.054635)
			(xy 102.130596 -528.97287) (xy 102.20014 -528.885664) (xy 102.262972 -528.793505) (xy 102.318742 -528.696908)
			(xy 102.367136 -528.596413) (xy 102.407885 -528.492583) (xy 102.44076 -528.385998) (xy 102.465578 -528.277253)
			(xy 102.4822 -528.166959) (xy 102.490533 -528.05573) (xy 102.491032 -527.99996) (xy 102.491032 -1.999996)
			(xy 102.490523 -1.944227) (xy 102.482188 -1.833002) (xy 102.465563 -1.72271) (xy 102.440743 -1.613969)
			(xy 102.407866 -1.507387) (xy 102.367116 -1.40356) (xy 102.31872 -1.303069) (xy 102.26295 -1.206475)
			(xy 102.200118 -1.11432) (xy 102.130574 -1.027117) (xy 102.054708 -0.945356) (xy 101.972944 -0.869492)
			(xy 101.885739 -0.799951) (xy 101.793581 -0.737122) (xy 101.696985 -0.681355) (xy 101.596492 -0.632964)
			(xy 101.492664 -0.592217) (xy 101.386081 -0.559343) (xy 101.277339 -0.534527) (xy 101.167047 -0.517907)
			(xy 101.055821 -0.509575) (xy 101.000052 -0.509016) (xy 26.500074 -0.509016) (xy 26.454278 -0.509546)
			(xy 26.363077 -0.517999) (xy 26.273045 -0.534832) (xy 26.184949 -0.559899) (xy 26.099543 -0.592988)
			(xy 26.017554 -0.633817) (xy 25.939682 -0.682036) (xy 25.866592 -0.737234) (xy 25.798906 -0.798941)
			(xy 25.737202 -0.86663) (xy 25.682007 -0.939724) (xy 25.633792 -1.017598) (xy 25.592968 -1.099589)
			(xy 25.559883 -1.184997) (xy 25.53482 -1.273093) (xy 25.517992 -1.363126) (xy 25.509543 -1.454328)
			(xy 25.508966 -1.500124) (xy 25.508966 -2.500122) (xy 25.50847 -2.563238) (xy 25.500544 -2.689221)
			(xy 25.484723 -2.814458) (xy 25.461069 -2.938455) (xy 25.429676 -3.060721) (xy 25.390668 -3.180775)
			(xy 25.344199 -3.298143) (xy 25.290452 -3.412362) (xy 25.229639 -3.52298) (xy 25.162 -3.629561) (xy 25.087803 -3.731685)
			(xy 25.007339 -3.828949) (xy 24.920927 -3.920968) (xy 24.828907 -4.00738) (xy 24.731644 -4.087844)
			(xy 24.62952 -4.162041) (xy 24.522938 -4.22968) (xy 24.41232 -4.290493) (xy 24.298101 -4.34424) (xy 24.180733 -4.390709)
			(xy 24.060679 -4.429717) (xy 23.938413 -4.46111) (xy 23.814416 -4.484763) (xy 23.689179 -4.500584)
			(xy 23.563196 -4.50851) (xy 23.50008 -4.509008) (xy 1.500124 -4.509008) (xy 1.454327 -4.509537) (xy 1.363123 -4.517988)
			(xy 1.273088 -4.534819) (xy 1.18499 -4.559885) (xy 1.099581 -4.592972) (xy 1.017589 -4.6338) (xy 0.939714 -4.682018)
			(xy 0.86662 -4.737216) (xy 0.798931 -4.798923) (xy 0.737224 -4.866612) (xy 0.682026 -4.939706) (xy 0.633808 -5.017581)
			(xy 0.59298 -5.099573) (xy 0.559893 -5.184982) (xy 0.534827 -5.27308) (xy 0.517996 -5.363115) (xy 0.509545 -5.454319)
			(xy 0.509016 -5.500116) (xy 0.509016 -7.747) (xy 5.5306 -7.747) (xy 5.534631 -7.617434) (xy 5.54671 -7.48837)
			(xy 5.566789 -7.360306) (xy 5.594791 -7.233739) (xy 5.630608 -7.109156) (xy 5.6741 -6.987042) (xy 5.7251 -6.867868)
			(xy 5.783411 -6.752095) (xy 5.848806 -6.640171) (xy 5.921033 -6.532529) (xy 5.999813 -6.429586) (xy 6.08484 -6.33174)
			(xy 6.175785 -6.239368) (xy 6.272297 -6.15283) (xy 6.374003 -6.072459) (xy 6.480509 -5.998567) (xy 6.591402 -5.931439)
			(xy 6.706254 -5.871335) (xy 6.824621 -5.818488) (xy 6.946044 -5.773101) (xy 7.070054 -5.735352) (xy 7.196171 -5.705385)
			(xy 7.323907 -5.683316) (xy 7.452768 -5.669232) (xy 7.582255 -5.663186) (xy 7.711868 -5.665202) (xy 7.841104 -5.675272)
			(xy 7.969465 -5.693357) (xy 8.096453 -5.719387) (xy 8.221577 -5.753262) (xy 8.344353 -5.79485) (xy 8.464306 -5.843991)
			(xy 8.580971 -5.900494) (xy 8.693899 -5.964141) (xy 8.802651 -6.034685) (xy 8.906807 -6.111854) (xy 9.005964 -6.195349)
			(xy 9.099738 -6.284847) (xy 9.187767 -6.380002) (xy 9.26971 -6.480445) (xy 9.345249 -6.585788) (xy 9.414094 -6.695624)
			(xy 9.475977 -6.809528) (xy 9.522754 -6.91007) (xy 39.818564 -6.91007) (xy 39.819054 -6.852663) (xy 39.826889 -6.738117)
			(xy 39.842523 -6.624372) (xy 39.865882 -6.51196) (xy 39.896859 -6.401403) (xy 39.935308 -6.293218)
			(xy 39.98105 -6.18791) (xy 40.033872 -6.085968) (xy 40.093527 -5.987869) (xy 40.159738 -5.894069)
			(xy 40.232196 -5.805007) (xy 40.310562 -5.721096) (xy 40.394473 -5.64273) (xy 40.483535 -5.570272)
			(xy 40.577335 -5.504061) (xy 40.675434 -5.444406) (xy 40.777376 -5.391584) (xy 40.882684 -5.345842)
			(xy 40.990869 -5.307393) (xy 41.101426 -5.276416) (xy 41.213838 -5.253057) (xy 41.327583 -5.237423)
			(xy 41.442129 -5.229588) (xy 41.556943 -5.229588) (xy 41.671489 -5.237423) (xy 41.785234 -5.253057)
			(xy 41.897646 -5.276416) (xy 42.008203 -5.307393) (xy 42.116388 -5.345842) (xy 42.221696 -5.391584)
			(xy 42.323638 -5.444406) (xy 42.421737 -5.504061) (xy 42.515537 -5.570272) (xy 42.604599 -5.64273)
			(xy 42.68851 -5.721096) (xy 42.766876 -5.805007) (xy 42.839334 -5.894069) (xy 42.905545 -5.987869)
			(xy 42.9652 -6.085968) (xy 43.018022 -6.18791) (xy 43.063764 -6.293218) (xy 43.102213 -6.401403)
			(xy 43.13319 -6.51196) (xy 43.156549 -6.624372) (xy 43.172183 -6.738117) (xy 43.180018 -6.852663)
			(xy 43.180508 -6.91007) (xy 43.180381 -6.943251) (xy 43.177842 -7.009565) (xy 43.175428 -7.042658)
			(xy 43.170272 -7.100942) (xy 43.152948 -7.216671) (xy 43.127616 -7.330914) (xy 43.094401 -7.443119)
			(xy 43.053462 -7.552742) (xy 43.004999 -7.659253) (xy 42.949245 -7.762135) (xy 42.886471 -7.860891)
			(xy 42.816981 -7.955042) (xy 42.741111 -8.044132) (xy 42.659229 -8.127729) (xy 42.571732 -8.20543)
			(xy 42.500813 -8.26008) (xy 93.154506 -8.26008) (xy 93.158522 -8.14381) (xy 93.170549 -8.028095)
			(xy 93.190531 -7.913485) (xy 93.218373 -7.800526) (xy 93.253942 -7.689758) (xy 93.297068 -7.581707)
			(xy 93.347545 -7.476889) (xy 93.405134 -7.375804) (xy 93.46956 -7.278932) (xy 93.540515 -7.186736)
			(xy 93.617662 -7.099655) (xy 93.700633 -7.018104) (xy 93.789033 -6.942472) (xy 93.88244 -6.873118)
			(xy 93.980409 -6.810375) (xy 94.082473 -6.754539) (xy 94.188147 -6.705878) (xy 94.296926 -6.664624)
			(xy 94.408291 -6.630973) (xy 94.521714 -6.605085) (xy 94.636651 -6.587084) (xy 94.752557 -6.577055)
			(xy 94.868879 -6.575047) (xy 94.985062 -6.581069) (xy 95.100553 -6.595092) (xy 95.214801 -6.61705)
			(xy 95.327262 -6.646837) (xy 95.4374 -6.684312) (xy 95.54469 -6.729297) (xy 95.648621 -6.781576)
			(xy 95.748697 -6.840901) (xy 95.844443 -6.906989) (xy 95.9354 -6.979525) (xy 96.021136 -7.058164)
			(xy 96.101243 -7.14253) (xy 96.175339 -7.232222) (xy 96.243069 -7.326812) (xy 96.304113 -7.42585)
			(xy 96.358178 -7.528863) (xy 96.405008 -7.63536) (xy 96.444379 -7.744835) (xy 96.476103 -7.856765)
			(xy 96.500029 -7.970617) (xy 96.516043 -8.085849) (xy 96.52407 -8.201911) (xy 96.524572 -8.26008)
			(xy 96.52407 -8.318249) (xy 96.516043 -8.434311) (xy 96.500029 -8.549543) (xy 96.476103 -8.663395)
			(xy 96.444379 -8.775325) (xy 96.405008 -8.8848) (xy 96.358178 -8.991297) (xy 96.304113 -9.09431)
			(xy 96.243069 -9.193348) (xy 96.175339 -9.287938) (xy 96.101243 -9.37763) (xy 96.021136 -9.461996)
			(xy 95.9354 -9.540635) (xy 95.844443 -9.613171) (xy 95.748697 -9.679259) (xy 95.648621 -9.738584)
			(xy 95.54469 -9.790863) (xy 95.4374 -9.835848) (xy 95.327262 -9.873323) (xy 95.214801 -9.90311) (xy 95.100553 -9.925068)
			(xy 94.985062 -9.939091) (xy 94.868879 -9.945113) (xy 94.752557 -9.943105) (xy 94.636651 -9.933076)
			(xy 94.521714 -9.915075) (xy 94.408291 -9.889187) (xy 94.296926 -9.855536) (xy 94.188147 -9.814282)
			(xy 94.082473 -9.765621) (xy 93.980409 -9.709785) (xy 93.88244 -9.647042) (xy 93.789033 -9.577688)
			(xy 93.700633 -9.502056) (xy 93.617662 -9.420505) (xy 93.540515 -9.333424) (xy 93.46956 -9.241228)
			(xy 93.405134 -9.144356) (xy 93.347545 -9.043271) (xy 93.297068 -8.938453) (xy 93.253942 -8.830402)
			(xy 93.218373 -8.719634) (xy 93.190531 -8.606675) (xy 93.170549 -8.492065) (xy 93.158522 -8.37635)
			(xy 93.154506 -8.26008) (xy 42.500813 -8.26008) (xy 42.479042 -8.276857) (xy 42.381609 -8.341665)
			(xy 42.279905 -8.39954) (xy 42.174422 -8.450202) (xy 42.065671 -8.493404) (xy 41.954179 -8.528939)
			(xy 41.840485 -8.556634) (xy 41.725141 -8.576354) (xy 41.608704 -8.588005) (xy 41.491739 -8.59153)
			(xy 41.374812 -8.586912) (xy 41.258489 -8.574173) (xy 41.143334 -8.553375) (xy 41.029905 -8.524618)
			(xy 40.91875 -8.488042) (xy 40.810407 -8.443825) (xy 40.705403 -8.392179) (xy 40.604244 -8.333356)
			(xy 40.507421 -8.26764) (xy 40.415403 -8.195349) (xy 40.328636 -8.116834) (xy 40.247539 -8.032474)
			(xy 40.172506 -7.942679) (xy 40.103899 -7.847883) (xy 40.042051 -7.748544) (xy 39.987262 -7.645145)
			(xy 39.939796 -7.538186) (xy 39.899884 -7.428185) (xy 39.86772 -7.315674) (xy 39.843457 -7.201199)
			(xy 39.827215 -7.085313) (xy 39.819072 -6.968579) (xy 39.818564 -6.91007) (xy 9.522754 -6.91007)
			(xy 9.530658 -6.927058) (xy 9.577928 -7.047761) (xy 9.617601 -7.171169) (xy 9.649526 -7.296805) (xy 9.673578 -7.424182)
			(xy 9.689665 -7.552808) (xy 9.697724 -7.682186) (xy 9.698228 -7.747) (xy 9.697724 -7.811814) (xy 9.689665 -7.941192)
			(xy 9.673578 -8.069818) (xy 9.649526 -8.197195) (xy 9.617601 -8.322831) (xy 9.577928 -8.446239) (xy 9.530658 -8.566942)
			(xy 9.475977 -8.684472) (xy 9.414094 -8.798376) (xy 9.345249 -8.908212) (xy 9.26971 -9.013555) (xy 9.187767 -9.113998)
			(xy 9.099738 -9.209153) (xy 9.005964 -9.298651) (xy 8.906807 -9.382146) (xy 8.802651 -9.459315) (xy 8.693899 -9.529859)
			(xy 8.580971 -9.593506) (xy 8.464306 -9.650009) (xy 8.344353 -9.69915) (xy 8.221577 -9.740738) (xy 8.096453 -9.774613)
			(xy 7.969465 -9.800643) (xy 7.841104 -9.818728) (xy 7.711868 -9.828798) (xy 7.582255 -9.830814) (xy 7.452768 -9.824768)
			(xy 7.323907 -9.810684) (xy 7.196171 -9.788615) (xy 7.070054 -9.758648) (xy 6.946044 -9.720899) (xy 6.824621 -9.675512)
			(xy 6.706254 -9.622665) (xy 6.591402 -9.562561) (xy 6.480509 -9.495433) (xy 6.374003 -9.421541) (xy 6.272297 -9.34117)
			(xy 6.175785 -9.254632) (xy 6.08484 -9.16226) (xy 5.999813 -9.064414) (xy 5.921033 -8.961471) (xy 5.848806 -8.853829)
			(xy 5.783411 -8.741905) (xy 5.7251 -8.626132) (xy 5.6741 -8.506958) (xy 5.630608 -8.384844) (xy 5.594791 -8.260261)
			(xy 5.566789 -8.133694) (xy 5.54671 -8.00563) (xy 5.534631 -7.876566) (xy 5.5306 -7.747) (xy 0.509016 -7.747)
			(xy 0.509016 -19.177) (xy 5.5306 -19.177) (xy 5.534631 -19.047434) (xy 5.54671 -18.91837) (xy 5.566789 -18.790306)
			(xy 5.594791 -18.663739) (xy 5.630608 -18.539156) (xy 5.6741 -18.417042) (xy 5.7251 -18.297868) (xy 5.783411 -18.182095)
			(xy 5.848806 -18.070171) (xy 5.921033 -17.962529) (xy 5.999813 -17.859586) (xy 6.08484 -17.76174)
			(xy 6.175785 -17.669368) (xy 6.272297 -17.58283) (xy 6.374003 -17.502459) (xy 6.480509 -17.428567)
			(xy 6.591402 -17.361439) (xy 6.706254 -17.301335) (xy 6.824621 -17.248488) (xy 6.946044 -17.203101)
			(xy 7.070054 -17.165352) (xy 7.196171 -17.135385) (xy 7.323907 -17.113316) (xy 7.452768 -17.099232)
			(xy 7.582255 -17.093186) (xy 7.711868 -17.095202) (xy 7.841104 -17.105272) (xy 7.969465 -17.123357)
			(xy 8.096453 -17.149387) (xy 8.221577 -17.183262) (xy 8.344353 -17.22485) (xy 8.464306 -17.273991)
			(xy 8.580971 -17.330494) (xy 8.693899 -17.394141) (xy 8.802651 -17.464685) (xy 8.906807 -17.541854)
			(xy 9.005964 -17.625349) (xy 9.099738 -17.714847) (xy 9.187767 -17.810002) (xy 9.26971 -17.910445)
			(xy 9.345249 -18.015788) (xy 9.414094 -18.125624) (xy 9.475977 -18.239528) (xy 9.530658 -18.357058)
			(xy 9.577928 -18.477761) (xy 9.617601 -18.601169) (xy 9.649526 -18.726805) (xy 9.673578 -18.854182)
			(xy 9.689665 -18.982808) (xy 9.697724 -19.112186) (xy 9.698228 -19.177) (xy 9.697724 -19.241814)
			(xy 9.689665 -19.371192) (xy 9.673578 -19.499818) (xy 9.649526 -19.627195) (xy 9.617601 -19.752831)
			(xy 9.577928 -19.876239) (xy 9.530658 -19.996942) (xy 9.524527 -20.01012) (xy 86.877404 -20.01012)
			(xy 86.881424 -19.819469) (xy 86.893478 -19.629156) (xy 86.913544 -19.439521) (xy 86.941587 -19.2509)
			(xy 86.977556 -19.06363) (xy 87.021388 -18.878042) (xy 87.073005 -18.694467) (xy 87.132315 -18.513231)
			(xy 87.199213 -18.334656) (xy 87.273579 -18.159061) (xy 87.355281 -17.986756) (xy 87.444175 -17.818049)
			(xy 87.540101 -17.653239) (xy 87.64289 -17.49262) (xy 87.752359 -17.336477) (xy 87.868313 -17.185088)
			(xy 87.990547 -17.038721) (xy 88.118841 -16.897637) (xy 88.252969 -16.762088) (xy 88.392693 -16.632313)
			(xy 88.537763 -16.508543) (xy 88.687921 -16.391) (xy 88.842902 -16.279891) (xy 89.002429 -16.175414)
			(xy 89.166218 -16.077755) (xy 89.333978 -15.987088) (xy 89.505412 -15.903574) (xy 89.680214 -15.827361)
			(xy 89.858073 -15.758585) (xy 90.038674 -15.697367) (xy 90.221694 -15.643818) (xy 90.40681 -15.598032)
			(xy 90.593691 -15.56009) (xy 90.782006 -15.530061) (xy 90.971419 -15.507996) (xy 91.161593 -15.493937)
			(xy 91.352192 -15.487907) (xy 91.542875 -15.489917) (xy 91.733304 -15.499964) (xy 91.92314 -15.51803)
			(xy 92.112046 -15.544083) (xy 92.299685 -15.578076) (xy 92.485725 -15.619949) (xy 92.669834 -15.669628)
			(xy 92.851685 -15.727024) (xy 93.030955 -15.792035) (xy 93.207325 -15.864546) (xy 93.380481 -15.944427)
			(xy 93.550116 -16.031537) (xy 93.715928 -16.125721) (xy 93.877622 -16.226812) (xy 94.03491 -16.334628)
			(xy 94.187513 -16.44898) (xy 94.335161 -16.569663) (xy 94.477589 -16.696464) (xy 94.614545 -16.829155)
			(xy 94.745786 -16.967503) (xy 94.871078 -17.11126) (xy 94.990198 -17.260171) (xy 95.102934 -17.413972)
			(xy 95.209087 -17.572388) (xy 95.308467 -17.735139) (xy 95.400897 -17.901934) (xy 95.486214 -18.072478)
			(xy 95.564266 -18.246466) (xy 95.634913 -18.423591) (xy 95.698031 -18.603536) (xy 95.753507 -18.785982)
			(xy 95.801242 -18.970605) (xy 95.841152 -19.157075) (xy 95.873165 -19.345063) (xy 95.897225 -19.534233)
			(xy 95.913288 -19.724249) (xy 95.921327 -19.914773) (xy 95.92183 -20.01012) (xy 95.921327 -20.105467)
			(xy 95.913288 -20.295991) (xy 95.897225 -20.486007) (xy 95.873165 -20.675177) (xy 95.841152 -20.863165)
			(xy 95.801242 -21.049635) (xy 95.753507 -21.234258) (xy 95.698031 -21.416704) (xy 95.634913 -21.596649)
			(xy 95.564266 -21.773774) (xy 95.486214 -21.947762) (xy 95.400897 -22.118306) (xy 95.308467 -22.285101)
			(xy 95.209087 -22.447852) (xy 95.102934 -22.606268) (xy 94.990198 -22.760069) (xy 94.871078 -22.90898)
			(xy 94.745786 -23.052737) (xy 94.614545 -23.191085) (xy 94.477589 -23.323776) (xy 94.335161 -23.450577)
			(xy 94.187513 -23.57126) (xy 94.03491 -23.685612) (xy 93.877622 -23.793428) (xy 93.715928 -23.894519)
			(xy 93.550116 -23.988703) (xy 93.380481 -24.075813) (xy 93.207325 -24.155694) (xy 93.030955 -24.228205)
			(xy 92.851685 -24.293216) (xy 92.669834 -24.350612) (xy 92.485725 -24.400291) (xy 92.299685 -24.442164)
			(xy 92.112046 -24.476157) (xy 91.92314 -24.50221) (xy 91.733304 -24.520276) (xy 91.542875 -24.530323)
			(xy 91.352192 -24.532333) (xy 91.161593 -24.526303) (xy 90.971419 -24.512244) (xy 90.782006 -24.490179)
			(xy 90.593691 -24.46015) (xy 90.40681 -24.422208) (xy 90.221694 -24.376422) (xy 90.038674 -24.322873)
			(xy 89.858073 -24.261655) (xy 89.680214 -24.192879) (xy 89.505412 -24.116666) (xy 89.333978 -24.033152)
			(xy 89.166218 -23.942485) (xy 89.002429 -23.844826) (xy 88.842902 -23.740349) (xy 88.687921 -23.62924)
			(xy 88.537763 -23.511697) (xy 88.392693 -23.387927) (xy 88.252969 -23.258152) (xy 88.118841 -23.122603)
			(xy 87.990547 -22.981519) (xy 87.868313 -22.835152) (xy 87.752359 -22.683763) (xy 87.64289 -22.52762)
			(xy 87.540101 -22.367001) (xy 87.444175 -22.202191) (xy 87.355281 -22.033484) (xy 87.273579 -21.861179)
			(xy 87.199213 -21.685584) (xy 87.132315 -21.507009) (xy 87.073005 -21.325773) (xy 87.021388 -21.142198)
			(xy 86.977556 -20.95661) (xy 86.941587 -20.76934) (xy 86.913544 -20.580719) (xy 86.893478 -20.391084)
			(xy 86.881424 -20.200771) (xy 86.877404 -20.01012) (xy 9.524527 -20.01012) (xy 9.475977 -20.114472)
			(xy 9.414094 -20.228376) (xy 9.345249 -20.338212) (xy 9.26971 -20.443555) (xy 9.187767 -20.543998)
			(xy 9.099738 -20.639153) (xy 9.005964 -20.728651) (xy 8.906807 -20.812146) (xy 8.802651 -20.889315)
			(xy 8.693899 -20.959859) (xy 8.580971 -21.023506) (xy 8.464306 -21.080009) (xy 8.344353 -21.12915)
			(xy 8.221577 -21.170738) (xy 8.096453 -21.204613) (xy 7.969465 -21.230643) (xy 7.841104 -21.248728)
			(xy 7.711868 -21.258798) (xy 7.582255 -21.260814) (xy 7.452768 -21.254768) (xy 7.323907 -21.240684)
			(xy 7.196171 -21.218615) (xy 7.070054 -21.188648) (xy 6.946044 -21.150899) (xy 6.824621 -21.105512)
			(xy 6.706254 -21.052665) (xy 6.591402 -20.992561) (xy 6.480509 -20.925433) (xy 6.374003 -20.851541)
			(xy 6.272297 -20.77117) (xy 6.175785 -20.684632) (xy 6.08484 -20.59226) (xy 5.999813 -20.494414)
			(xy 5.921033 -20.391471) (xy 5.848806 -20.283829) (xy 5.783411 -20.171905) (xy 5.7251 -20.056132)
			(xy 5.6741 -19.936958) (xy 5.630608 -19.814844) (xy 5.594791 -19.690261) (xy 5.566789 -19.563694)
			(xy 5.54671 -19.43563) (xy 5.534631 -19.306566) (xy 5.5306 -19.177) (xy 0.509016 -19.177) (xy 0.509016 -25.909778)
			(xy 6.671831 -25.909778) (xy 6.675786 -25.817941) (xy 6.687621 -25.726784) (xy 6.707248 -25.636981)
			(xy 6.734522 -25.549199) (xy 6.769242 -25.464085) (xy 6.81115 -25.382272) (xy 6.859936 -25.304364)
			(xy 6.915239 -25.230939) (xy 6.976649 -25.162539) (xy 7.043711 -25.099672) (xy 7.11593 -25.042802)
			(xy 7.19277 -24.992351) (xy 7.273663 -24.948692) (xy 7.358009 -24.912149) (xy 7.445185 -24.882992)
			(xy 7.534544 -24.861438) (xy 7.625425 -24.847644) (xy 7.717156 -24.841714) (xy 7.809057 -24.843692)
			(xy 7.900448 -24.853563) (xy 7.990652 -24.871253) (xy 8.079001 -24.896633) (xy 8.164841 -24.929513)
			(xy 8.247537 -24.969651) (xy 8.326477 -25.01675) (xy 8.401075 -25.07046) (xy 8.470781 -25.130384)
			(xy 8.535076 -25.196078) (xy 8.593487 -25.267056) (xy 8.645579 -25.342793) (xy 8.690968 -25.422728)
			(xy 8.729318 -25.506268) (xy 8.760343 -25.592796) (xy 8.783816 -25.681671) (xy 8.799562 -25.772235)
			(xy 8.807464 -25.863817) (xy 8.807958 -25.909778) (xy 8.807464 -25.955739) (xy 8.799562 -26.047321)
			(xy 8.783816 -26.137885) (xy 8.760343 -26.22676) (xy 8.729318 -26.313288) (xy 8.690968 -26.396828)
			(xy 8.645579 -26.476763) (xy 8.593487 -26.5525) (xy 8.535076 -26.623478) (xy 8.470781 -26.689172)
			(xy 8.401075 -26.749096) (xy 8.326477 -26.802806) (xy 8.247537 -26.849905) (xy 8.164841 -26.890043)
			(xy 8.079001 -26.922923) (xy 7.990652 -26.948303) (xy 7.900448 -26.965993) (xy 7.809057 -26.975864)
			(xy 7.717156 -26.977842) (xy 7.625425 -26.971912) (xy 7.534544 -26.958118) (xy 7.445185 -26.936564)
			(xy 7.358009 -26.907407) (xy 7.273663 -26.870864) (xy 7.19277 -26.827205) (xy 7.11593 -26.776754)
			(xy 7.043711 -26.719884) (xy 6.976649 -26.657017) (xy 6.915239 -26.588617) (xy 6.859936 -26.515192)
			(xy 6.81115 -26.437284) (xy 6.769242 -26.355471) (xy 6.734522 -26.270357) (xy 6.707248 -26.182575)
			(xy 6.687621 -26.092772) (xy 6.675786 -26.001615) (xy 6.671831 -25.909778) (xy 0.509016 -25.909778)
			(xy 0.509016 -29.19984) (xy 14.086591 -29.19984) (xy 14.090616 -29.057648) (xy 14.102679 -28.915912)
			(xy 14.122742 -28.775086) (xy 14.15074 -28.63562) (xy 14.186584 -28.497961) (xy 14.230158 -28.362551)
			(xy 14.281323 -28.229823) (xy 14.339916 -28.100202) (xy 14.405747 -27.974104) (xy 14.478608 -27.851932)
			(xy 14.558263 -27.734078) (xy 14.644459 -27.620919) (xy 14.736918 -27.512817) (xy 14.835346 -27.41012)
			(xy 14.939425 -27.313156) (xy 15.048824 -27.222236) (xy 15.163192 -27.13765) (xy 15.282161 -27.05967)
			(xy 15.405352 -26.988546) (xy 15.532369 -26.924505) (xy 15.662806 -26.867753) (xy 15.796245 -26.818471)
			(xy 15.932258 -26.776817) (xy 16.07041 -26.742925) (xy 16.210259 -26.716904) (xy 16.351355 -26.698836)
			(xy 16.493247 -26.688779) (xy 16.635482 -26.686766) (xy 16.777602 -26.692803) (xy 16.919153 -26.706871)
			(xy 17.059682 -26.728925) (xy 17.198737 -26.758894) (xy 17.335875 -26.796682) (xy 17.470655 -26.842168)
			(xy 17.602646 -26.895206) (xy 17.731425 -26.955627) (xy 17.856579 -27.023236) (xy 17.977707 -27.097818)
			(xy 18.094423 -27.179134) (xy 18.206351 -27.266922) (xy 18.313133 -27.360902) (xy 18.414427 -27.460772)
			(xy 18.509908 -27.566214) (xy 18.599272 -27.676888) (xy 18.68223 -27.792441) (xy 18.758519 -27.912502)
			(xy 18.827893 -28.036687) (xy 18.89013 -28.164598) (xy 18.945031 -28.295825) (xy 18.992419 -28.429948)
			(xy 19.032144 -28.566537) (xy 19.064077 -28.705155) (xy 19.088118 -28.845357) (xy 19.104187 -28.986695)
			(xy 19.112235 -29.128716) (xy 19.112738 -29.19984) (xy 19.112235 -29.270964) (xy 19.104187 -29.412985)
			(xy 19.088118 -29.554323) (xy 19.064077 -29.694525) (xy 19.032144 -29.833143) (xy 18.992419 -29.969732)
			(xy 18.945031 -30.103855) (xy 18.89013 -30.235082) (xy 18.827893 -30.362993) (xy 18.758519 -30.487178)
			(xy 18.68223 -30.607239) (xy 18.599272 -30.722792) (xy 18.509908 -30.833466) (xy 18.414427 -30.938908)
			(xy 18.313133 -31.038778) (xy 18.206351 -31.132758) (xy 18.094423 -31.220546) (xy 17.977707 -31.301862)
			(xy 17.856579 -31.376444) (xy 17.731425 -31.444053) (xy 17.602646 -31.504474) (xy 17.470655 -31.557512)
			(xy 17.335875 -31.602998) (xy 17.198737 -31.640786) (xy 17.059682 -31.670755) (xy 16.919153 -31.692809)
			(xy 16.777602 -31.706877) (xy 16.635482 -31.712914) (xy 16.493247 -31.710901) (xy 16.351355 -31.700844)
			(xy 16.210259 -31.682776) (xy 16.07041 -31.656755) (xy 15.932258 -31.622863) (xy 15.796245 -31.581209)
			(xy 15.662806 -31.531927) (xy 15.532369 -31.475175) (xy 15.405352 -31.411134) (xy 15.282161 -31.34001)
			(xy 15.163192 -31.26203) (xy 15.048824 -31.177444) (xy 14.939425 -31.086524) (xy 14.835346 -30.98956)
			(xy 14.736918 -30.886863) (xy 14.644459 -30.778761) (xy 14.558263 -30.665602) (xy 14.478608 -30.547748)
			(xy 14.405747 -30.425576) (xy 14.339916 -30.299478) (xy 14.281323 -30.169857) (xy 14.230158 -30.037129)
			(xy 14.186584 -29.901719) (xy 14.15074 -29.76406) (xy 14.122742 -29.624594) (xy 14.102679 -29.483768)
			(xy 14.090616 -29.342032) (xy 14.086591 -29.19984) (xy 0.509016 -29.19984) (xy 0.509016 -32.29991)
			(xy 75.486519 -32.29991) (xy 75.490544 -32.157718) (xy 75.502607 -32.015982) (xy 75.52267 -31.875156)
			(xy 75.550668 -31.73569) (xy 75.586512 -31.598031) (xy 75.630086 -31.462621) (xy 75.681251 -31.329893)
			(xy 75.739844 -31.200272) (xy 75.805675 -31.074174) (xy 75.878536 -30.952002) (xy 75.958191 -30.834148)
			(xy 76.044387 -30.720989) (xy 76.136846 -30.612887) (xy 76.235274 -30.51019) (xy 76.339353 -30.413226)
			(xy 76.448752 -30.322306) (xy 76.56312 -30.23772) (xy 76.682089 -30.15974) (xy 76.80528 -30.088616)
			(xy 76.932297 -30.024575) (xy 77.062734 -29.967823) (xy 77.196173 -29.918541) (xy 77.332186 -29.876887)
			(xy 77.470338 -29.842995) (xy 77.610187 -29.816974) (xy 77.751283 -29.798906) (xy 77.893175 -29.788849)
			(xy 78.03541 -29.786836) (xy 78.17753 -29.792873) (xy 78.319081 -29.806941) (xy 78.45961 -29.828995)
			(xy 78.598665 -29.858964) (xy 78.735803 -29.896752) (xy 78.870583 -29.942238) (xy 79.002574 -29.995276)
			(xy 79.131353 -30.055697) (xy 79.256507 -30.123306) (xy 79.377635 -30.197888) (xy 79.494351 -30.279204)
			(xy 79.606279 -30.366992) (xy 79.713061 -30.460972) (xy 79.814355 -30.560842) (xy 79.909836 -30.666284)
			(xy 79.9992 -30.776958) (xy 80.082158 -30.892511) (xy 80.158447 -31.012572) (xy 80.227821 -31.136757)
			(xy 80.290058 -31.264668) (xy 80.344959 -31.395895) (xy 80.392347 -31.530018) (xy 80.432072 -31.666607)
			(xy 80.464005 -31.805225) (xy 80.488046 -31.945427) (xy 80.504115 -32.086765) (xy 80.512163 -32.228786)
			(xy 80.512666 -32.29991) (xy 80.512163 -32.371034) (xy 80.504115 -32.513055) (xy 80.488046 -32.654393)
			(xy 80.464005 -32.794595) (xy 80.432072 -32.933213) (xy 80.392347 -33.069802) (xy 80.344959 -33.203925)
			(xy 80.290058 -33.335152) (xy 80.227821 -33.463063) (xy 80.158447 -33.587248) (xy 80.082158 -33.707309)
			(xy 79.9992 -33.822862) (xy 79.909836 -33.933536) (xy 79.814355 -34.038978) (xy 79.713061 -34.138848)
			(xy 79.606279 -34.232828) (xy 79.494351 -34.320616) (xy 79.377635 -34.401932) (xy 79.256507 -34.476514)
			(xy 79.131353 -34.544123) (xy 79.002574 -34.604544) (xy 78.870583 -34.657582) (xy 78.735803 -34.703068)
			(xy 78.598665 -34.740856) (xy 78.45961 -34.770825) (xy 78.319081 -34.792879) (xy 78.17753 -34.806947)
			(xy 78.03541 -34.812984) (xy 77.893175 -34.810971) (xy 77.751283 -34.800914) (xy 77.610187 -34.782846)
			(xy 77.470338 -34.756825) (xy 77.332186 -34.722933) (xy 77.196173 -34.681279) (xy 77.062734 -34.631997)
			(xy 76.932297 -34.575245) (xy 76.80528 -34.511204) (xy 76.682089 -34.44008) (xy 76.56312 -34.3621)
			(xy 76.448752 -34.277514) (xy 76.339353 -34.186594) (xy 76.235274 -34.08963) (xy 76.136846 -33.986933)
			(xy 76.044387 -33.878831) (xy 75.958191 -33.765672) (xy 75.878536 -33.647818) (xy 75.805675 -33.525646)
			(xy 75.739844 -33.399548) (xy 75.681251 -33.269927) (xy 75.630086 -33.137199) (xy 75.586512 -33.001789)
			(xy 75.550668 -32.86413) (xy 75.52267 -32.724664) (xy 75.502607 -32.583838) (xy 75.490544 -32.442102)
			(xy 75.486519 -32.29991) (xy 0.509016 -32.29991) (xy 0.509016 -34.90976) (xy 6.671831 -34.90976)
			(xy 6.675786 -34.817923) (xy 6.687621 -34.726766) (xy 6.707248 -34.636963) (xy 6.734522 -34.549181)
			(xy 6.769242 -34.464067) (xy 6.81115 -34.382254) (xy 6.859936 -34.304346) (xy 6.915239 -34.230921)
			(xy 6.976649 -34.162521) (xy 7.043711 -34.099654) (xy 7.11593 -34.042784) (xy 7.19277 -33.992333)
			(xy 7.273663 -33.948674) (xy 7.358009 -33.912131) (xy 7.445185 -33.882974) (xy 7.534544 -33.86142)
			(xy 7.625425 -33.847626) (xy 7.717156 -33.841696) (xy 7.809057 -33.843674) (xy 7.900448 -33.853545)
			(xy 7.990652 -33.871235) (xy 8.079001 -33.896615) (xy 8.164841 -33.929495) (xy 8.247537 -33.969633)
			(xy 8.326477 -34.016732) (xy 8.401075 -34.070442) (xy 8.470781 -34.130366) (xy 8.535076 -34.19606)
			(xy 8.593487 -34.267038) (xy 8.645579 -34.342775) (xy 8.690968 -34.42271) (xy 8.729318 -34.50625)
			(xy 8.760343 -34.592778) (xy 8.783816 -34.681653) (xy 8.799562 -34.772217) (xy 8.807464 -34.863799)
			(xy 8.807958 -34.90976) (xy 8.807464 -34.955721) (xy 8.799562 -35.047303) (xy 8.783816 -35.137867)
			(xy 8.760343 -35.226742) (xy 8.729318 -35.31327) (xy 8.690968 -35.39681) (xy 8.645579 -35.476745)
			(xy 8.593487 -35.552482) (xy 8.535076 -35.62346) (xy 8.470781 -35.689154) (xy 8.401075 -35.749078)
			(xy 8.326477 -35.802788) (xy 8.247537 -35.849887) (xy 8.164841 -35.890025) (xy 8.079001 -35.922905)
			(xy 7.990652 -35.948285) (xy 7.900448 -35.965975) (xy 7.809057 -35.975846) (xy 7.717156 -35.977824)
			(xy 7.625425 -35.971894) (xy 7.534544 -35.9581) (xy 7.445185 -35.936546) (xy 7.358009 -35.907389)
			(xy 7.273663 -35.870846) (xy 7.19277 -35.827187) (xy 7.11593 -35.776736) (xy 7.043711 -35.719866)
			(xy 6.976649 -35.656999) (xy 6.915239 -35.588599) (xy 6.859936 -35.515174) (xy 6.81115 -35.437266)
			(xy 6.769242 -35.355453) (xy 6.734522 -35.270339) (xy 6.707248 -35.182557) (xy 6.687621 -35.092754)
			(xy 6.675786 -35.001597) (xy 6.671831 -34.90976) (xy 0.509016 -34.90976) (xy 0.509016 -42.291) (xy 5.5306 -42.291)
			(xy 5.534631 -42.161434) (xy 5.54671 -42.03237) (xy 5.566789 -41.904306) (xy 5.594791 -41.777739)
			(xy 5.630608 -41.653156) (xy 5.6741 -41.531042) (xy 5.7251 -41.411868) (xy 5.783411 -41.296095) (xy 5.848806 -41.184171)
			(xy 5.921033 -41.076529) (xy 5.999813 -40.973586) (xy 6.08484 -40.87574) (xy 6.175785 -40.783368)
			(xy 6.272297 -40.69683) (xy 6.374003 -40.616459) (xy 6.480509 -40.542567) (xy 6.591402 -40.475439)
			(xy 6.706254 -40.415335) (xy 6.824621 -40.362488) (xy 6.946044 -40.317101) (xy 7.070054 -40.279352)
			(xy 7.196171 -40.249385) (xy 7.323907 -40.227316) (xy 7.452768 -40.213232) (xy 7.582255 -40.207186)
			(xy 7.711868 -40.209202) (xy 7.841104 -40.219272) (xy 7.969465 -40.237357) (xy 8.096453 -40.263387)
			(xy 8.221577 -40.297262) (xy 8.344353 -40.33885) (xy 8.464306 -40.387991) (xy 8.580971 -40.444494)
			(xy 8.693899 -40.508141) (xy 8.802651 -40.578685) (xy 8.906807 -40.655854) (xy 9.005964 -40.739349)
			(xy 9.099738 -40.828847) (xy 9.187767 -40.924002) (xy 9.26971 -41.024445) (xy 9.345249 -41.129788)
			(xy 9.414094 -41.239624) (xy 9.475977 -41.353528) (xy 9.530658 -41.471058) (xy 9.577928 -41.591761)
			(xy 9.617601 -41.715169) (xy 9.649526 -41.840805) (xy 9.673578 -41.968182) (xy 9.689665 -42.096808)
			(xy 9.697724 -42.226186) (xy 9.698228 -42.291) (xy 9.697724 -42.355814) (xy 9.689665 -42.485192)
			(xy 9.673578 -42.613818) (xy 9.649526 -42.741195) (xy 9.617601 -42.866831) (xy 9.577928 -42.990239)
			(xy 9.530658 -43.110942) (xy 9.475977 -43.228472) (xy 9.414094 -43.342376) (xy 9.345249 -43.452212)
			(xy 9.26971 -43.557555) (xy 9.187767 -43.657998) (xy 9.099738 -43.753153) (xy 9.005964 -43.842651)
			(xy 8.906807 -43.926146) (xy 8.802651 -44.003315) (xy 8.693899 -44.073859) (xy 8.580971 -44.137506)
			(xy 8.464306 -44.194009) (xy 8.344353 -44.24315) (xy 8.221577 -44.284738) (xy 8.096453 -44.318613)
			(xy 7.969465 -44.344643) (xy 7.841104 -44.362728) (xy 7.711868 -44.372798) (xy 7.582255 -44.374814)
			(xy 7.452768 -44.368768) (xy 7.323907 -44.354684) (xy 7.196171 -44.332615) (xy 7.070054 -44.302648)
			(xy 6.946044 -44.264899) (xy 6.824621 -44.219512) (xy 6.706254 -44.166665) (xy 6.591402 -44.106561)
			(xy 6.480509 -44.039433) (xy 6.374003 -43.965541) (xy 6.272297 -43.88517) (xy 6.175785 -43.798632)
			(xy 6.08484 -43.70626) (xy 5.999813 -43.608414) (xy 5.921033 -43.505471) (xy 5.848806 -43.397829)
			(xy 5.783411 -43.285905) (xy 5.7251 -43.170132) (xy 5.6741 -43.050958) (xy 5.630608 -42.928844) (xy 5.594791 -42.804261)
			(xy 5.566789 -42.677694) (xy 5.54671 -42.54963) (xy 5.534631 -42.420566) (xy 5.5306 -42.291) (xy 0.509016 -42.291)
			(xy 0.509016 -51.36007) (xy 39.818564 -51.36007) (xy 39.819054 -51.302663) (xy 39.826889 -51.188117)
			(xy 39.842523 -51.074372) (xy 39.865882 -50.96196) (xy 39.896859 -50.851403) (xy 39.935308 -50.743218)
			(xy 39.98105 -50.63791) (xy 40.033872 -50.535968) (xy 40.093527 -50.437869) (xy 40.159738 -50.344069)
			(xy 40.232196 -50.255007) (xy 40.310562 -50.171096) (xy 40.394473 -50.09273) (xy 40.483535 -50.020272)
			(xy 40.577335 -49.954061) (xy 40.675434 -49.894406) (xy 40.777376 -49.841584) (xy 40.882684 -49.795842)
			(xy 40.990869 -49.757393) (xy 41.101426 -49.726416) (xy 41.213838 -49.703057) (xy 41.327583 -49.687423)
			(xy 41.442129 -49.679588) (xy 41.556943 -49.679588) (xy 41.671489 -49.687423) (xy 41.785234 -49.703057)
			(xy 41.897646 -49.726416) (xy 42.008203 -49.757393) (xy 42.116388 -49.795842) (xy 42.221696 -49.841584)
			(xy 42.323638 -49.894406) (xy 42.421737 -49.954061) (xy 42.515537 -50.020272) (xy 42.604599 -50.09273)
			(xy 42.68851 -50.171096) (xy 42.766876 -50.255007) (xy 42.839334 -50.344069) (xy 42.905545 -50.437869)
			(xy 42.9652 -50.535968) (xy 43.018022 -50.63791) (xy 43.063764 -50.743218) (xy 43.102213 -50.851403)
			(xy 43.13319 -50.96196) (xy 43.156549 -51.074372) (xy 43.172183 -51.188117) (xy 43.180018 -51.302663)
			(xy 43.180508 -51.36007) (xy 43.180381 -51.393251) (xy 43.177842 -51.459565) (xy 43.175428 -51.492658)
			(xy 43.170272 -51.550942) (xy 43.152948 -51.666671) (xy 43.127616 -51.780914) (xy 43.094401 -51.893119)
			(xy 43.053462 -52.002742) (xy 43.004999 -52.109253) (xy 42.949245 -52.212135) (xy 42.886471 -52.310891)
			(xy 42.816981 -52.405042) (xy 42.741111 -52.494132) (xy 42.659229 -52.577729) (xy 42.571732 -52.65543)
			(xy 42.500813 -52.71008) (xy 93.154506 -52.71008) (xy 93.158522 -52.59381) (xy 93.170549 -52.478095)
			(xy 93.190531 -52.363485) (xy 93.218373 -52.250526) (xy 93.253942 -52.139758) (xy 93.297068 -52.031707)
			(xy 93.347545 -51.926889) (xy 93.405134 -51.825804) (xy 93.46956 -51.728932) (xy 93.540515 -51.636736)
			(xy 93.617662 -51.549655) (xy 93.700633 -51.468104) (xy 93.789033 -51.392472) (xy 93.88244 -51.323118)
			(xy 93.980409 -51.260375) (xy 94.082473 -51.204539) (xy 94.188147 -51.155878) (xy 94.296926 -51.114624)
			(xy 94.408291 -51.080973) (xy 94.521714 -51.055085) (xy 94.636651 -51.037084) (xy 94.752557 -51.027055)
			(xy 94.868879 -51.025047) (xy 94.985062 -51.031069) (xy 95.100553 -51.045092) (xy 95.214801 -51.06705)
			(xy 95.327262 -51.096837) (xy 95.4374 -51.134312) (xy 95.54469 -51.179297) (xy 95.648621 -51.231576)
			(xy 95.748697 -51.290901) (xy 95.844443 -51.356989) (xy 95.9354 -51.429525) (xy 96.021136 -51.508164)
			(xy 96.101243 -51.59253) (xy 96.175339 -51.682222) (xy 96.243069 -51.776812) (xy 96.304113 -51.87585)
			(xy 96.358178 -51.978863) (xy 96.405008 -52.08536) (xy 96.444379 -52.194835) (xy 96.476103 -52.306765)
			(xy 96.500029 -52.420617) (xy 96.516043 -52.535849) (xy 96.52407 -52.651911) (xy 96.524572 -52.71008)
			(xy 96.52407 -52.768249) (xy 96.516043 -52.884311) (xy 96.500029 -52.999543) (xy 96.476103 -53.113395)
			(xy 96.444379 -53.225325) (xy 96.405008 -53.3348) (xy 96.358178 -53.441297) (xy 96.304113 -53.54431)
			(xy 96.243069 -53.643348) (xy 96.175339 -53.737938) (xy 96.101243 -53.82763) (xy 96.021136 -53.911996)
			(xy 95.9354 -53.990635) (xy 95.844443 -54.063171) (xy 95.748697 -54.129259) (xy 95.648621 -54.188584)
			(xy 95.54469 -54.240863) (xy 95.4374 -54.285848) (xy 95.327262 -54.323323) (xy 95.214801 -54.35311)
			(xy 95.100553 -54.375068) (xy 94.985062 -54.389091) (xy 94.868879 -54.395113) (xy 94.752557 -54.393105)
			(xy 94.636651 -54.383076) (xy 94.521714 -54.365075) (xy 94.408291 -54.339187) (xy 94.296926 -54.305536)
			(xy 94.188147 -54.264282) (xy 94.082473 -54.215621) (xy 93.980409 -54.159785) (xy 93.88244 -54.097042)
			(xy 93.789033 -54.027688) (xy 93.700633 -53.952056) (xy 93.617662 -53.870505) (xy 93.540515 -53.783424)
			(xy 93.46956 -53.691228) (xy 93.405134 -53.594356) (xy 93.347545 -53.493271) (xy 93.297068 -53.388453)
			(xy 93.253942 -53.280402) (xy 93.218373 -53.169634) (xy 93.190531 -53.056675) (xy 93.170549 -52.942065)
			(xy 93.158522 -52.82635) (xy 93.154506 -52.71008) (xy 42.500813 -52.71008) (xy 42.479042 -52.726857)
			(xy 42.381609 -52.791665) (xy 42.279905 -52.84954) (xy 42.174422 -52.900202) (xy 42.065671 -52.943404)
			(xy 41.954179 -52.978939) (xy 41.840485 -53.006634) (xy 41.725141 -53.026354) (xy 41.608704 -53.038005)
			(xy 41.491739 -53.04153) (xy 41.374812 -53.036912) (xy 41.258489 -53.024173) (xy 41.143334 -53.003375)
			(xy 41.029905 -52.974618) (xy 40.91875 -52.938042) (xy 40.810407 -52.893825) (xy 40.705403 -52.842179)
			(xy 40.604244 -52.783356) (xy 40.507421 -52.71764) (xy 40.415403 -52.645349) (xy 40.328636 -52.566834)
			(xy 40.247539 -52.482474) (xy 40.172506 -52.392679) (xy 40.103899 -52.297883) (xy 40.042051 -52.198544)
			(xy 39.987262 -52.095145) (xy 39.939796 -51.988186) (xy 39.899884 -51.878185) (xy 39.86772 -51.765674)
			(xy 39.843457 -51.651199) (xy 39.827215 -51.535313) (xy 39.819072 -51.418579) (xy 39.818564 -51.36007)
			(xy 0.509016 -51.36007) (xy 0.509016 -53.721) (xy 5.5306 -53.721) (xy 5.534631 -53.591434) (xy 5.54671 -53.46237)
			(xy 5.566789 -53.334306) (xy 5.594791 -53.207739) (xy 5.630608 -53.083156) (xy 5.6741 -52.961042)
			(xy 5.7251 -52.841868) (xy 5.783411 -52.726095) (xy 5.848806 -52.614171) (xy 5.921033 -52.506529)
			(xy 5.999813 -52.403586) (xy 6.08484 -52.30574) (xy 6.175785 -52.213368) (xy 6.272297 -52.12683)
			(xy 6.374003 -52.046459) (xy 6.480509 -51.972567) (xy 6.591402 -51.905439) (xy 6.706254 -51.845335)
			(xy 6.824621 -51.792488) (xy 6.946044 -51.747101) (xy 7.070054 -51.709352) (xy 7.196171 -51.679385)
			(xy 7.323907 -51.657316) (xy 7.452768 -51.643232) (xy 7.582255 -51.637186) (xy 7.711868 -51.639202)
			(xy 7.841104 -51.649272) (xy 7.969465 -51.667357) (xy 8.096453 -51.693387) (xy 8.221577 -51.727262)
			(xy 8.344353 -51.76885) (xy 8.464306 -51.817991) (xy 8.580971 -51.874494) (xy 8.693899 -51.938141)
			(xy 8.802651 -52.008685) (xy 8.906807 -52.085854) (xy 9.005964 -52.169349) (xy 9.099738 -52.258847)
			(xy 9.187767 -52.354002) (xy 9.26971 -52.454445) (xy 9.345249 -52.559788) (xy 9.414094 -52.669624)
			(xy 9.475977 -52.783528) (xy 9.530658 -52.901058) (xy 9.577928 -53.021761) (xy 9.617601 -53.145169)
			(xy 9.649526 -53.270805) (xy 9.673578 -53.398182) (xy 9.689665 -53.526808) (xy 9.697724 -53.656186)
			(xy 9.698228 -53.721) (xy 9.697724 -53.785814) (xy 9.689665 -53.915192) (xy 9.673578 -54.043818)
			(xy 9.649526 -54.171195) (xy 9.617601 -54.296831) (xy 9.577928 -54.420239) (xy 9.530658 -54.540942)
			(xy 9.475977 -54.658472) (xy 9.414094 -54.772376) (xy 9.345249 -54.882212) (xy 9.26971 -54.987555)
			(xy 9.187767 -55.087998) (xy 9.099738 -55.183153) (xy 9.005964 -55.272651) (xy 8.906807 -55.356146)
			(xy 8.802651 -55.433315) (xy 8.693899 -55.503859) (xy 8.580971 -55.567506) (xy 8.464306 -55.624009)
			(xy 8.344353 -55.67315) (xy 8.221577 -55.714738) (xy 8.096453 -55.748613) (xy 7.969465 -55.774643)
			(xy 7.841104 -55.792728) (xy 7.711868 -55.802798) (xy 7.582255 -55.804814) (xy 7.452768 -55.798768)
			(xy 7.323907 -55.784684) (xy 7.196171 -55.762615) (xy 7.070054 -55.732648) (xy 6.946044 -55.694899)
			(xy 6.824621 -55.649512) (xy 6.706254 -55.596665) (xy 6.591402 -55.536561) (xy 6.480509 -55.469433)
			(xy 6.374003 -55.395541) (xy 6.272297 -55.31517) (xy 6.175785 -55.228632) (xy 6.08484 -55.13626)
			(xy 5.999813 -55.038414) (xy 5.921033 -54.935471) (xy 5.848806 -54.827829) (xy 5.783411 -54.715905)
			(xy 5.7251 -54.600132) (xy 5.6741 -54.480958) (xy 5.630608 -54.358844) (xy 5.594791 -54.234261) (xy 5.566789 -54.107694)
			(xy 5.54671 -53.97963) (xy 5.534631 -53.850566) (xy 5.5306 -53.721) (xy 0.509016 -53.721) (xy 0.509016 -60.833)
			(xy 5.5306 -60.833) (xy 5.534631 -60.703434) (xy 5.54671 -60.57437) (xy 5.566789 -60.446306) (xy 5.594791 -60.319739)
			(xy 5.630608 -60.195156) (xy 5.6741 -60.073042) (xy 5.7251 -59.953868) (xy 5.783411 -59.838095) (xy 5.848806 -59.726171)
			(xy 5.921033 -59.618529) (xy 5.999813 -59.515586) (xy 6.08484 -59.41774) (xy 6.175785 -59.325368)
			(xy 6.272297 -59.23883) (xy 6.374003 -59.158459) (xy 6.480509 -59.084567) (xy 6.591402 -59.017439)
			(xy 6.706254 -58.957335) (xy 6.824621 -58.904488) (xy 6.946044 -58.859101) (xy 7.070054 -58.821352)
			(xy 7.196171 -58.791385) (xy 7.323907 -58.769316) (xy 7.452768 -58.755232) (xy 7.582255 -58.749186)
			(xy 7.711868 -58.751202) (xy 7.841104 -58.761272) (xy 7.969465 -58.779357) (xy 8.096453 -58.805387)
			(xy 8.221577 -58.839262) (xy 8.344353 -58.88085) (xy 8.464306 -58.929991) (xy 8.580971 -58.986494)
			(xy 8.693899 -59.050141) (xy 8.802651 -59.120685) (xy 8.906807 -59.197854) (xy 9.005964 -59.281349)
			(xy 9.099738 -59.370847) (xy 9.187767 -59.466002) (xy 9.26971 -59.566445) (xy 9.345249 -59.671788)
			(xy 9.414094 -59.781624) (xy 9.475977 -59.895528) (xy 9.530658 -60.013058) (xy 9.577928 -60.133761)
			(xy 9.617601 -60.257169) (xy 9.649526 -60.382805) (xy 9.673578 -60.510182) (xy 9.689665 -60.638808)
			(xy 9.697724 -60.768186) (xy 9.698228 -60.833) (xy 9.697724 -60.897814) (xy 9.689665 -61.027192)
			(xy 9.673578 -61.155818) (xy 9.649526 -61.283195) (xy 9.617601 -61.408831) (xy 9.577928 -61.532239)
			(xy 9.530658 -61.652942) (xy 9.475977 -61.770472) (xy 9.414094 -61.884376) (xy 9.345249 -61.994212)
			(xy 9.26971 -62.099555) (xy 9.187767 -62.199998) (xy 9.099738 -62.295153) (xy 9.005964 -62.384651)
			(xy 8.906807 -62.468146) (xy 8.802651 -62.545315) (xy 8.693899 -62.615859) (xy 8.580971 -62.679506)
			(xy 8.464306 -62.736009) (xy 8.344353 -62.78515) (xy 8.221577 -62.826738) (xy 8.096453 -62.860613)
			(xy 7.969465 -62.886643) (xy 7.841104 -62.904728) (xy 7.711868 -62.914798) (xy 7.582255 -62.916814)
			(xy 7.452768 -62.910768) (xy 7.323907 -62.896684) (xy 7.196171 -62.874615) (xy 7.070054 -62.844648)
			(xy 6.946044 -62.806899) (xy 6.824621 -62.761512) (xy 6.706254 -62.708665) (xy 6.591402 -62.648561)
			(xy 6.480509 -62.581433) (xy 6.374003 -62.507541) (xy 6.272297 -62.42717) (xy 6.175785 -62.340632)
			(xy 6.08484 -62.24826) (xy 5.999813 -62.150414) (xy 5.921033 -62.047471) (xy 5.848806 -61.939829)
			(xy 5.783411 -61.827905) (xy 5.7251 -61.712132) (xy 5.6741 -61.592958) (xy 5.630608 -61.470844) (xy 5.594791 -61.346261)
			(xy 5.566789 -61.219694) (xy 5.54671 -61.09163) (xy 5.534631 -60.962566) (xy 5.5306 -60.833) (xy 0.509016 -60.833)
			(xy 0.509016 -64.46012) (xy 86.877404 -64.46012) (xy 86.881424 -64.269469) (xy 86.893478 -64.079156)
			(xy 86.913544 -63.889521) (xy 86.941587 -63.7009) (xy 86.977556 -63.51363) (xy 87.021388 -63.328042)
			(xy 87.073005 -63.144467) (xy 87.132315 -62.963231) (xy 87.199213 -62.784656) (xy 87.273579 -62.609061)
			(xy 87.355281 -62.436756) (xy 87.444175 -62.268049) (xy 87.540101 -62.103239) (xy 87.64289 -61.94262)
			(xy 87.752359 -61.786477) (xy 87.868313 -61.635088) (xy 87.990547 -61.488721) (xy 88.118841 -61.347637)
			(xy 88.252969 -61.212088) (xy 88.392693 -61.082313) (xy 88.537763 -60.958543) (xy 88.687921 -60.841)
			(xy 88.842902 -60.729891) (xy 89.002429 -60.625414) (xy 89.166218 -60.527755) (xy 89.333978 -60.437088)
			(xy 89.505412 -60.353574) (xy 89.680214 -60.277361) (xy 89.858073 -60.208585) (xy 90.038674 -60.147367)
			(xy 90.221694 -60.093818) (xy 90.40681 -60.048032) (xy 90.593691 -60.01009) (xy 90.782006 -59.980061)
			(xy 90.971419 -59.957996) (xy 91.161593 -59.943937) (xy 91.352192 -59.937907) (xy 91.542875 -59.939917)
			(xy 91.733304 -59.949964) (xy 91.92314 -59.96803) (xy 92.112046 -59.994083) (xy 92.299685 -60.028076)
			(xy 92.485725 -60.069949) (xy 92.669834 -60.119628) (xy 92.851685 -60.177024) (xy 93.030955 -60.242035)
			(xy 93.207325 -60.314546) (xy 93.380481 -60.394427) (xy 93.550116 -60.481537) (xy 93.715928 -60.575721)
			(xy 93.877622 -60.676812) (xy 94.03491 -60.784628) (xy 94.187513 -60.89898) (xy 94.335161 -61.019663)
			(xy 94.477589 -61.146464) (xy 94.614545 -61.279155) (xy 94.745786 -61.417503) (xy 94.871078 -61.56126)
			(xy 94.990198 -61.710171) (xy 95.102934 -61.863972) (xy 95.209087 -62.022388) (xy 95.308467 -62.185139)
			(xy 95.400897 -62.351934) (xy 95.486214 -62.522478) (xy 95.564266 -62.696466) (xy 95.634913 -62.873591)
			(xy 95.698031 -63.053536) (xy 95.753507 -63.235982) (xy 95.801242 -63.420605) (xy 95.841152 -63.607075)
			(xy 95.873165 -63.795063) (xy 95.897225 -63.984233) (xy 95.913288 -64.174249) (xy 95.921327 -64.364773)
			(xy 95.92183 -64.46012) (xy 95.921327 -64.555467) (xy 95.913288 -64.745991) (xy 95.897225 -64.936007)
			(xy 95.873165 -65.125177) (xy 95.841152 -65.313165) (xy 95.801242 -65.499635) (xy 95.753507 -65.684258)
			(xy 95.698031 -65.866704) (xy 95.634913 -66.046649) (xy 95.564266 -66.223774) (xy 95.486214 -66.397762)
			(xy 95.400897 -66.568306) (xy 95.308467 -66.735101) (xy 95.209087 -66.897852) (xy 95.102934 -67.056268)
			(xy 94.990198 -67.210069) (xy 94.871078 -67.35898) (xy 94.745786 -67.502737) (xy 94.614545 -67.641085)
			(xy 94.477589 -67.773776) (xy 94.335161 -67.900577) (xy 94.187513 -68.02126) (xy 94.03491 -68.135612)
			(xy 93.877622 -68.243428) (xy 93.715928 -68.344519) (xy 93.550116 -68.438703) (xy 93.380481 -68.525813)
			(xy 93.207325 -68.605694) (xy 93.030955 -68.678205) (xy 92.851685 -68.743216) (xy 92.669834 -68.800612)
			(xy 92.485725 -68.850291) (xy 92.299685 -68.892164) (xy 92.112046 -68.926157) (xy 91.92314 -68.95221)
			(xy 91.733304 -68.970276) (xy 91.542875 -68.980323) (xy 91.352192 -68.982333) (xy 91.161593 -68.976303)
			(xy 90.971419 -68.962244) (xy 90.782006 -68.940179) (xy 90.593691 -68.91015) (xy 90.40681 -68.872208)
			(xy 90.221694 -68.826422) (xy 90.038674 -68.772873) (xy 89.858073 -68.711655) (xy 89.680214 -68.642879)
			(xy 89.505412 -68.566666) (xy 89.333978 -68.483152) (xy 89.166218 -68.392485) (xy 89.002429 -68.294826)
			(xy 88.842902 -68.190349) (xy 88.687921 -68.07924) (xy 88.537763 -67.961697) (xy 88.392693 -67.837927)
			(xy 88.252969 -67.708152) (xy 88.118841 -67.572603) (xy 87.990547 -67.431519) (xy 87.868313 -67.285152)
			(xy 87.752359 -67.133763) (xy 87.64289 -66.97762) (xy 87.540101 -66.817001) (xy 87.444175 -66.652191)
			(xy 87.355281 -66.483484) (xy 87.273579 -66.311179) (xy 87.199213 -66.135584) (xy 87.132315 -65.957009)
			(xy 87.073005 -65.775773) (xy 87.021388 -65.592198) (xy 86.977556 -65.40661) (xy 86.941587 -65.21934)
			(xy 86.913544 -65.030719) (xy 86.893478 -64.841084) (xy 86.881424 -64.650771) (xy 86.877404 -64.46012)
			(xy 0.509016 -64.46012) (xy 0.509016 -72.263) (xy 5.5306 -72.263) (xy 5.534631 -72.133434) (xy 5.54671 -72.00437)
			(xy 5.566789 -71.876306) (xy 5.594791 -71.749739) (xy 5.630608 -71.625156) (xy 5.6741 -71.503042)
			(xy 5.7251 -71.383868) (xy 5.783411 -71.268095) (xy 5.848806 -71.156171) (xy 5.921033 -71.048529)
			(xy 5.999813 -70.945586) (xy 6.08484 -70.84774) (xy 6.175785 -70.755368) (xy 6.272297 -70.66883)
			(xy 6.374003 -70.588459) (xy 6.480509 -70.514567) (xy 6.591402 -70.447439) (xy 6.706254 -70.387335)
			(xy 6.824621 -70.334488) (xy 6.946044 -70.289101) (xy 7.070054 -70.251352) (xy 7.196171 -70.221385)
			(xy 7.323907 -70.199316) (xy 7.452768 -70.185232) (xy 7.582255 -70.179186) (xy 7.711868 -70.181202)
			(xy 7.841104 -70.191272) (xy 7.969465 -70.209357) (xy 8.096453 -70.235387) (xy 8.221577 -70.269262)
			(xy 8.344353 -70.31085) (xy 8.464306 -70.359991) (xy 8.580971 -70.416494) (xy 8.693899 -70.480141)
			(xy 8.802651 -70.550685) (xy 8.906807 -70.627854) (xy 9.005964 -70.711349) (xy 9.099738 -70.800847)
			(xy 9.187767 -70.896002) (xy 9.26971 -70.996445) (xy 9.345249 -71.101788) (xy 9.414094 -71.211624)
			(xy 9.475977 -71.325528) (xy 9.530658 -71.443058) (xy 9.577928 -71.563761) (xy 9.617601 -71.687169)
			(xy 9.649526 -71.812805) (xy 9.673578 -71.940182) (xy 9.689665 -72.068808) (xy 9.697724 -72.198186)
			(xy 9.698228 -72.263) (xy 9.697724 -72.327814) (xy 9.689665 -72.457192) (xy 9.673578 -72.585818)
			(xy 9.649526 -72.713195) (xy 9.617601 -72.838831) (xy 9.577928 -72.962239) (xy 9.530658 -73.082942)
			(xy 9.475977 -73.200472) (xy 9.414094 -73.314376) (xy 9.345249 -73.424212) (xy 9.26971 -73.529555)
			(xy 9.187767 -73.629998) (xy 9.099738 -73.725153) (xy 9.005964 -73.814651) (xy 8.906807 -73.898146)
			(xy 8.802651 -73.975315) (xy 8.693899 -74.045859) (xy 8.580971 -74.109506) (xy 8.464306 -74.166009)
			(xy 8.344353 -74.21515) (xy 8.221577 -74.256738) (xy 8.096453 -74.290613) (xy 7.969465 -74.316643)
			(xy 7.841104 -74.334728) (xy 7.711868 -74.344798) (xy 7.582255 -74.346814) (xy 7.452768 -74.340768)
			(xy 7.323907 -74.326684) (xy 7.196171 -74.304615) (xy 7.070054 -74.274648) (xy 6.946044 -74.236899)
			(xy 6.824621 -74.191512) (xy 6.706254 -74.138665) (xy 6.591402 -74.078561) (xy 6.480509 -74.011433)
			(xy 6.374003 -73.937541) (xy 6.272297 -73.85717) (xy 6.175785 -73.770632) (xy 6.08484 -73.67826)
			(xy 5.999813 -73.580414) (xy 5.921033 -73.477471) (xy 5.848806 -73.369829) (xy 5.783411 -73.257905)
			(xy 5.7251 -73.142132) (xy 5.6741 -73.022958) (xy 5.630608 -72.900844) (xy 5.594791 -72.776261) (xy 5.566789 -72.649694)
			(xy 5.54671 -72.52163) (xy 5.534631 -72.392566) (xy 5.5306 -72.263) (xy 0.509016 -72.263) (xy 0.509016 -77.476858)
			(xy 6.601727 -77.476858) (xy 6.605682 -77.385021) (xy 6.617517 -77.293864) (xy 6.637144 -77.204061)
			(xy 6.664418 -77.116279) (xy 6.699138 -77.031165) (xy 6.741046 -76.949352) (xy 6.789832 -76.871444)
			(xy 6.845135 -76.798019) (xy 6.906545 -76.729619) (xy 6.973607 -76.666752) (xy 7.045826 -76.609882)
			(xy 7.122666 -76.559431) (xy 7.203559 -76.515772) (xy 7.287905 -76.479229) (xy 7.375081 -76.450072)
			(xy 7.46444 -76.428518) (xy 7.555321 -76.414724) (xy 7.647052 -76.408794) (xy 7.738953 -76.410772)
			(xy 7.830344 -76.420643) (xy 7.920548 -76.438333) (xy 8.008897 -76.463713) (xy 8.094737 -76.496593)
			(xy 8.177433 -76.536731) (xy 8.256373 -76.58383) (xy 8.330971 -76.63754) (xy 8.400677 -76.697464)
			(xy 8.464972 -76.763158) (xy 8.523383 -76.834136) (xy 8.575475 -76.909873) (xy 8.620864 -76.989808)
			(xy 8.659214 -77.073348) (xy 8.690239 -77.159876) (xy 8.713712 -77.248751) (xy 8.729458 -77.339315)
			(xy 8.73736 -77.430897) (xy 8.737854 -77.476858) (xy 8.73736 -77.522819) (xy 8.729458 -77.614401)
			(xy 8.713712 -77.704965) (xy 8.690239 -77.79384) (xy 8.659214 -77.880368) (xy 8.620864 -77.963908)
			(xy 8.575475 -78.043843) (xy 8.523383 -78.11958) (xy 8.464972 -78.190558) (xy 8.400677 -78.256252)
			(xy 8.330971 -78.316176) (xy 8.256373 -78.369886) (xy 8.241646 -78.378673) (xy 74.888081 -78.378673)
			(xy 74.888081 -78.220963) (xy 74.896069 -78.063456) (xy 74.912025 -77.906556) (xy 74.935906 -77.750665)
			(xy 74.967653 -77.596184) (xy 75.007183 -77.443509) (xy 75.054395 -77.293033) (xy 75.109169 -77.14514)
			(xy 75.171362 -77.000212) (xy 75.240817 -76.85862) (xy 75.317353 -76.720727) (xy 75.400776 -76.586888)
			(xy 75.49087 -76.457446) (xy 75.587405 -76.332733) (xy 75.690133 -76.21307) (xy 75.798789 -76.098763)
			(xy 75.913096 -75.990107) (xy 76.032759 -75.887379) (xy 76.157472 -75.790844) (xy 76.286914 -75.70075)
			(xy 76.420753 -75.617327) (xy 76.558646 -75.540791) (xy 76.700238 -75.471336) (xy 76.845166 -75.409143)
			(xy 76.993059 -75.354369) (xy 77.143535 -75.307157) (xy 77.29621 -75.267627) (xy 77.450691 -75.23588)
			(xy 77.606582 -75.211999) (xy 77.763482 -75.196043) (xy 77.920989 -75.188055) (xy 78.078699 -75.188055)
			(xy 78.236206 -75.196043) (xy 78.393106 -75.211999) (xy 78.548997 -75.23588) (xy 78.703478 -75.267627)
			(xy 78.856153 -75.307157) (xy 79.006629 -75.354369) (xy 79.154522 -75.409143) (xy 79.29945 -75.471336)
			(xy 79.441042 -75.540791) (xy 79.578935 -75.617327) (xy 79.712774 -75.70075) (xy 79.842216 -75.790844)
			(xy 79.966929 -75.887379) (xy 80.086592 -75.990107) (xy 80.200899 -76.098763) (xy 80.309555 -76.21307)
			(xy 80.412283 -76.332733) (xy 80.508818 -76.457446) (xy 80.598912 -76.586888) (xy 80.682335 -76.720727)
			(xy 80.758871 -76.85862) (xy 80.828326 -77.000212) (xy 80.890519 -77.14514) (xy 80.945293 -77.293033)
			(xy 80.992505 -77.443509) (xy 81.032035 -77.596184) (xy 81.063782 -77.750665) (xy 81.087663 -77.906556)
			(xy 81.103619 -78.063456) (xy 81.111607 -78.220963) (xy 81.112106 -78.299818) (xy 81.111607 -78.378673)
			(xy 81.103619 -78.53618) (xy 81.087663 -78.69308) (xy 81.063782 -78.848971) (xy 81.032035 -79.003452)
			(xy 80.992505 -79.156127) (xy 80.945293 -79.306603) (xy 80.890519 -79.454496) (xy 80.828326 -79.599424)
			(xy 80.758871 -79.741016) (xy 80.682335 -79.878909) (xy 80.598912 -80.012748) (xy 80.508818 -80.14219)
			(xy 80.412283 -80.266903) (xy 80.309555 -80.386566) (xy 80.200899 -80.500873) (xy 80.086592 -80.609529)
			(xy 79.966929 -80.712257) (xy 79.842216 -80.808792) (xy 79.712774 -80.898886) (xy 79.578935 -80.982309)
			(xy 79.441042 -81.058845) (xy 79.29945 -81.1283) (xy 79.154522 -81.190493) (xy 79.006629 -81.245267)
			(xy 78.856153 -81.292479) (xy 78.703478 -81.332009) (xy 78.548997 -81.363756) (xy 78.393106 -81.387637)
			(xy 78.236206 -81.403593) (xy 78.078699 -81.411581) (xy 77.920989 -81.411581) (xy 77.763482 -81.403593)
			(xy 77.606582 -81.387637) (xy 77.450691 -81.363756) (xy 77.29621 -81.332009) (xy 77.143535 -81.292479)
			(xy 76.993059 -81.245267) (xy 76.845166 -81.190493) (xy 76.700238 -81.1283) (xy 76.558646 -81.058845)
			(xy 76.420753 -80.982309) (xy 76.286914 -80.898886) (xy 76.157472 -80.808792) (xy 76.032759 -80.712257)
			(xy 75.913096 -80.609529) (xy 75.798789 -80.500873) (xy 75.690133 -80.386566) (xy 75.587405 -80.266903)
			(xy 75.49087 -80.14219) (xy 75.400776 -80.012748) (xy 75.317353 -79.878909) (xy 75.240817 -79.741016)
			(xy 75.171362 -79.599424) (xy 75.109169 -79.454496) (xy 75.054395 -79.306603) (xy 75.007183 -79.156127)
			(xy 74.967653 -79.003452) (xy 74.935906 -78.848971) (xy 74.912025 -78.69308) (xy 74.896069 -78.53618)
			(xy 74.888081 -78.378673) (xy 8.241646 -78.378673) (xy 8.177433 -78.416985) (xy 8.094737 -78.457123)
			(xy 8.008897 -78.490003) (xy 7.920548 -78.515383) (xy 7.830344 -78.533073) (xy 7.738953 -78.542944)
			(xy 7.647052 -78.544922) (xy 7.555321 -78.538992) (xy 7.46444 -78.525198) (xy 7.375081 -78.503644)
			(xy 7.287905 -78.474487) (xy 7.203559 -78.437944) (xy 7.122666 -78.394285) (xy 7.045826 -78.343834)
			(xy 6.973607 -78.286964) (xy 6.906545 -78.224097) (xy 6.845135 -78.155697) (xy 6.789832 -78.082272)
			(xy 6.741046 -78.004364) (xy 6.699138 -77.922551) (xy 6.664418 -77.837437) (xy 6.637144 -77.749655)
			(xy 6.617517 -77.659852) (xy 6.605682 -77.568695) (xy 6.601727 -77.476858) (xy 0.509016 -77.476858)
			(xy 0.509016 -89.476834) (xy 6.601727 -89.476834) (xy 6.605682 -89.384997) (xy 6.617517 -89.29384)
			(xy 6.637144 -89.204037) (xy 6.664418 -89.116255) (xy 6.699138 -89.031141) (xy 6.741046 -88.949328)
			(xy 6.789832 -88.87142) (xy 6.845135 -88.797995) (xy 6.906545 -88.729595) (xy 6.973607 -88.666728)
			(xy 7.045826 -88.609858) (xy 7.122666 -88.559407) (xy 7.203559 -88.515748) (xy 7.287905 -88.479205)
			(xy 7.375081 -88.450048) (xy 7.46444 -88.428494) (xy 7.555321 -88.4147) (xy 7.647052 -88.40877) (xy 7.738953 -88.410748)
			(xy 7.830344 -88.420619) (xy 7.920548 -88.438309) (xy 8.008897 -88.463689) (xy 8.094737 -88.496569)
			(xy 8.177433 -88.536707) (xy 8.256373 -88.583806) (xy 8.330971 -88.637516) (xy 8.400677 -88.69744)
			(xy 8.464972 -88.763134) (xy 8.523383 -88.834112) (xy 8.575475 -88.909849) (xy 8.620864 -88.989784)
			(xy 8.659214 -89.073324) (xy 8.690239 -89.159852) (xy 8.713712 -89.248727) (xy 8.729458 -89.339291)
			(xy 8.73736 -89.430873) (xy 8.737854 -89.476834) (xy 8.73736 -89.522795) (xy 8.729458 -89.614377)
			(xy 8.713712 -89.704941) (xy 8.690239 -89.793816) (xy 8.659214 -89.880344) (xy 8.620864 -89.963884)
			(xy 8.575475 -90.043819) (xy 8.523383 -90.119556) (xy 8.464972 -90.190534) (xy 8.400677 -90.256228)
			(xy 8.330971 -90.316152) (xy 8.256373 -90.369862) (xy 8.177433 -90.416961) (xy 8.094737 -90.457099)
			(xy 8.008897 -90.489979) (xy 7.920548 -90.515359) (xy 7.830344 -90.533049) (xy 7.738953 -90.54292)
			(xy 7.647052 -90.544898) (xy 7.555321 -90.538968) (xy 7.46444 -90.525174) (xy 7.375081 -90.50362)
			(xy 7.287905 -90.474463) (xy 7.203559 -90.43792) (xy 7.122666 -90.394261) (xy 7.045826 -90.34381)
			(xy 6.973607 -90.28694) (xy 6.906545 -90.224073) (xy 6.845135 -90.155673) (xy 6.789832 -90.082248)
			(xy 6.741046 -90.00434) (xy 6.699138 -89.922527) (xy 6.664418 -89.837413) (xy 6.637144 -89.749631)
			(xy 6.617517 -89.659828) (xy 6.605682 -89.568671) (xy 6.601727 -89.476834) (xy 0.509016 -89.476834)
			(xy 0.509016 -95.377) (xy 5.5306 -95.377) (xy 5.534631 -95.247434) (xy 5.54671 -95.11837) (xy 5.566789 -94.990306)
			(xy 5.594791 -94.863739) (xy 5.630608 -94.739156) (xy 5.6741 -94.617042) (xy 5.7251 -94.497868) (xy 5.783411 -94.382095)
			(xy 5.848806 -94.270171) (xy 5.921033 -94.162529) (xy 5.999813 -94.059586) (xy 6.08484 -93.96174)
			(xy 6.175785 -93.869368) (xy 6.272297 -93.78283) (xy 6.374003 -93.702459) (xy 6.480509 -93.628567)
			(xy 6.591402 -93.561439) (xy 6.706254 -93.501335) (xy 6.824621 -93.448488) (xy 6.946044 -93.403101)
			(xy 7.070054 -93.365352) (xy 7.196171 -93.335385) (xy 7.323907 -93.313316) (xy 7.452768 -93.299232)
			(xy 7.582255 -93.293186) (xy 7.711868 -93.295202) (xy 7.841104 -93.305272) (xy 7.969465 -93.323357)
			(xy 8.096453 -93.349387) (xy 8.221577 -93.383262) (xy 8.344353 -93.42485) (xy 8.464306 -93.473991)
			(xy 8.580971 -93.530494) (xy 8.693899 -93.594141) (xy 8.802651 -93.664685) (xy 8.906807 -93.741854)
			(xy 9.005964 -93.825349) (xy 9.099738 -93.914847) (xy 9.187767 -94.010002) (xy 9.26971 -94.110445)
			(xy 9.345249 -94.215788) (xy 9.414094 -94.325624) (xy 9.475977 -94.439528) (xy 9.530658 -94.557058)
			(xy 9.577928 -94.677761) (xy 9.617601 -94.801169) (xy 9.649526 -94.926805) (xy 9.673578 -95.054182)
			(xy 9.689665 -95.182808) (xy 9.697724 -95.312186) (xy 9.698228 -95.377) (xy 9.697724 -95.441814)
			(xy 9.689665 -95.571192) (xy 9.673578 -95.699818) (xy 9.65276 -95.81007) (xy 39.818564 -95.81007)
			(xy 39.819054 -95.752663) (xy 39.826889 -95.638117) (xy 39.842523 -95.524372) (xy 39.865882 -95.41196)
			(xy 39.896859 -95.301403) (xy 39.935308 -95.193218) (xy 39.98105 -95.08791) (xy 40.033872 -94.985968)
			(xy 40.093527 -94.887869) (xy 40.159738 -94.794069) (xy 40.232196 -94.705007) (xy 40.310562 -94.621096)
			(xy 40.394473 -94.54273) (xy 40.483535 -94.470272) (xy 40.577335 -94.404061) (xy 40.675434 -94.344406)
			(xy 40.777376 -94.291584) (xy 40.882684 -94.245842) (xy 40.990869 -94.207393) (xy 41.101426 -94.176416)
			(xy 41.213838 -94.153057) (xy 41.327583 -94.137423) (xy 41.442129 -94.129588) (xy 41.556943 -94.129588)
			(xy 41.671489 -94.137423) (xy 41.785234 -94.153057) (xy 41.897646 -94.176416) (xy 42.008203 -94.207393)
			(xy 42.116388 -94.245842) (xy 42.221696 -94.291584) (xy 42.323638 -94.344406) (xy 42.421737 -94.404061)
			(xy 42.515537 -94.470272) (xy 42.604599 -94.54273) (xy 42.68851 -94.621096) (xy 42.766876 -94.705007)
			(xy 42.839334 -94.794069) (xy 42.905545 -94.887869) (xy 42.9652 -94.985968) (xy 43.018022 -95.08791)
			(xy 43.063764 -95.193218) (xy 43.102213 -95.301403) (xy 43.13319 -95.41196) (xy 43.156549 -95.524372)
			(xy 43.172183 -95.638117) (xy 43.180018 -95.752663) (xy 43.180508 -95.81007) (xy 43.180381 -95.843251)
			(xy 43.177842 -95.909565) (xy 43.175428 -95.942658) (xy 43.170272 -96.000942) (xy 43.152948 -96.116671)
			(xy 43.127616 -96.230914) (xy 43.094401 -96.343119) (xy 43.053462 -96.452742) (xy 43.004999 -96.559253)
			(xy 42.949245 -96.662135) (xy 42.886471 -96.760891) (xy 42.816981 -96.855042) (xy 42.741111 -96.944132)
			(xy 42.659229 -97.027729) (xy 42.571732 -97.10543) (xy 42.500813 -97.16008) (xy 93.154506 -97.16008)
			(xy 93.158522 -97.04381) (xy 93.170549 -96.928095) (xy 93.190531 -96.813485) (xy 93.218373 -96.700526)
			(xy 93.253942 -96.589758) (xy 93.297068 -96.481707) (xy 93.347545 -96.376889) (xy 93.405134 -96.275804)
			(xy 93.46956 -96.178932) (xy 93.540515 -96.086736) (xy 93.617662 -95.999655) (xy 93.700633 -95.918104)
			(xy 93.789033 -95.842472) (xy 93.88244 -95.773118) (xy 93.980409 -95.710375) (xy 94.082473 -95.654539)
			(xy 94.188147 -95.605878) (xy 94.296926 -95.564624) (xy 94.408291 -95.530973) (xy 94.521714 -95.505085)
			(xy 94.636651 -95.487084) (xy 94.752557 -95.477055) (xy 94.868879 -95.475047) (xy 94.985062 -95.481069)
			(xy 95.100553 -95.495092) (xy 95.214801 -95.51705) (xy 95.327262 -95.546837) (xy 95.4374 -95.584312)
			(xy 95.54469 -95.629297) (xy 95.648621 -95.681576) (xy 95.748697 -95.740901) (xy 95.844443 -95.806989)
			(xy 95.9354 -95.879525) (xy 96.021136 -95.958164) (xy 96.101243 -96.04253) (xy 96.175339 -96.132222)
			(xy 96.243069 -96.226812) (xy 96.304113 -96.32585) (xy 96.358178 -96.428863) (xy 96.405008 -96.53536)
			(xy 96.444379 -96.644835) (xy 96.476103 -96.756765) (xy 96.500029 -96.870617) (xy 96.516043 -96.985849)
			(xy 96.52407 -97.101911) (xy 96.524572 -97.16008) (xy 96.52407 -97.218249) (xy 96.516043 -97.334311)
			(xy 96.500029 -97.449543) (xy 96.476103 -97.563395) (xy 96.444379 -97.675325) (xy 96.405008 -97.7848)
			(xy 96.358178 -97.891297) (xy 96.304113 -97.99431) (xy 96.243069 -98.093348) (xy 96.175339 -98.187938)
			(xy 96.101243 -98.27763) (xy 96.021136 -98.361996) (xy 95.9354 -98.440635) (xy 95.844443 -98.513171)
			(xy 95.748697 -98.579259) (xy 95.648621 -98.638584) (xy 95.54469 -98.690863) (xy 95.4374 -98.735848)
			(xy 95.327262 -98.773323) (xy 95.214801 -98.80311) (xy 95.100553 -98.825068) (xy 94.985062 -98.839091)
			(xy 94.868879 -98.845113) (xy 94.752557 -98.843105) (xy 94.636651 -98.833076) (xy 94.521714 -98.815075)
			(xy 94.408291 -98.789187) (xy 94.296926 -98.755536) (xy 94.188147 -98.714282) (xy 94.082473 -98.665621)
			(xy 93.980409 -98.609785) (xy 93.88244 -98.547042) (xy 93.789033 -98.477688) (xy 93.700633 -98.402056)
			(xy 93.617662 -98.320505) (xy 93.540515 -98.233424) (xy 93.46956 -98.141228) (xy 93.405134 -98.044356)
			(xy 93.347545 -97.943271) (xy 93.297068 -97.838453) (xy 93.253942 -97.730402) (xy 93.218373 -97.619634)
			(xy 93.190531 -97.506675) (xy 93.170549 -97.392065) (xy 93.158522 -97.27635) (xy 93.154506 -97.16008)
			(xy 42.500813 -97.16008) (xy 42.479042 -97.176857) (xy 42.381609 -97.241665) (xy 42.279905 -97.29954)
			(xy 42.174422 -97.350202) (xy 42.065671 -97.393404) (xy 41.954179 -97.428939) (xy 41.840485 -97.456634)
			(xy 41.725141 -97.476354) (xy 41.608704 -97.488005) (xy 41.491739 -97.49153) (xy 41.374812 -97.486912)
			(xy 41.258489 -97.474173) (xy 41.143334 -97.453375) (xy 41.029905 -97.424618) (xy 40.91875 -97.388042)
			(xy 40.810407 -97.343825) (xy 40.705403 -97.292179) (xy 40.604244 -97.233356) (xy 40.507421 -97.16764)
			(xy 40.415403 -97.095349) (xy 40.328636 -97.016834) (xy 40.247539 -96.932474) (xy 40.172506 -96.842679)
			(xy 40.103899 -96.747883) (xy 40.042051 -96.648544) (xy 39.987262 -96.545145) (xy 39.939796 -96.438186)
			(xy 39.899884 -96.328185) (xy 39.86772 -96.215674) (xy 39.843457 -96.101199) (xy 39.827215 -95.985313)
			(xy 39.819072 -95.868579) (xy 39.818564 -95.81007) (xy 9.65276 -95.81007) (xy 9.649526 -95.827195)
			(xy 9.617601 -95.952831) (xy 9.577928 -96.076239) (xy 9.530658 -96.196942) (xy 9.475977 -96.314472)
			(xy 9.414094 -96.428376) (xy 9.345249 -96.538212) (xy 9.26971 -96.643555) (xy 9.187767 -96.743998)
			(xy 9.099738 -96.839153) (xy 9.005964 -96.928651) (xy 8.906807 -97.012146) (xy 8.802651 -97.089315)
			(xy 8.693899 -97.159859) (xy 8.580971 -97.223506) (xy 8.464306 -97.280009) (xy 8.344353 -97.32915)
			(xy 8.221577 -97.370738) (xy 8.096453 -97.404613) (xy 7.969465 -97.430643) (xy 7.841104 -97.448728)
			(xy 7.711868 -97.458798) (xy 7.582255 -97.460814) (xy 7.452768 -97.454768) (xy 7.323907 -97.440684)
			(xy 7.196171 -97.418615) (xy 7.070054 -97.388648) (xy 6.946044 -97.350899) (xy 6.824621 -97.305512)
			(xy 6.706254 -97.252665) (xy 6.591402 -97.192561) (xy 6.480509 -97.125433) (xy 6.374003 -97.051541)
			(xy 6.272297 -96.97117) (xy 6.175785 -96.884632) (xy 6.08484 -96.79226) (xy 5.999813 -96.694414)
			(xy 5.921033 -96.591471) (xy 5.848806 -96.483829) (xy 5.783411 -96.371905) (xy 5.7251 -96.256132)
			(xy 5.6741 -96.136958) (xy 5.630608 -96.014844) (xy 5.594791 -95.890261) (xy 5.566789 -95.763694)
			(xy 5.54671 -95.63563) (xy 5.534631 -95.506566) (xy 5.5306 -95.377) (xy 0.509016 -95.377) (xy 0.509016 -106.807)
			(xy 5.5306 -106.807) (xy 5.534631 -106.677434) (xy 5.54671 -106.54837) (xy 5.566789 -106.420306)
			(xy 5.594791 -106.293739) (xy 5.630608 -106.169156) (xy 5.6741 -106.047042) (xy 5.7251 -105.927868)
			(xy 5.783411 -105.812095) (xy 5.848806 -105.700171) (xy 5.921033 -105.592529) (xy 5.999813 -105.489586)
			(xy 6.08484 -105.39174) (xy 6.175785 -105.299368) (xy 6.272297 -105.21283) (xy 6.374003 -105.132459)
			(xy 6.480509 -105.058567) (xy 6.591402 -104.991439) (xy 6.706254 -104.931335) (xy 6.824621 -104.878488)
			(xy 6.946044 -104.833101) (xy 7.070054 -104.795352) (xy 7.196171 -104.765385) (xy 7.323907 -104.743316)
			(xy 7.452768 -104.729232) (xy 7.582255 -104.723186) (xy 7.711868 -104.725202) (xy 7.841104 -104.735272)
			(xy 7.969465 -104.753357) (xy 8.096453 -104.779387) (xy 8.221577 -104.813262) (xy 8.344353 -104.85485)
			(xy 8.464306 -104.903991) (xy 8.580971 -104.960494) (xy 8.693899 -105.024141) (xy 8.802651 -105.094685)
			(xy 8.906807 -105.171854) (xy 9.005964 -105.255349) (xy 9.099738 -105.344847) (xy 9.187767 -105.440002)
			(xy 9.26971 -105.540445) (xy 9.345249 -105.645788) (xy 9.414094 -105.755624) (xy 9.475977 -105.869528)
			(xy 9.530658 -105.987058) (xy 9.577928 -106.107761) (xy 9.617601 -106.231169) (xy 9.649526 -106.356805)
			(xy 9.673578 -106.484182) (xy 9.689665 -106.612808) (xy 9.697724 -106.742186) (xy 9.698228 -106.807)
			(xy 9.697724 -106.871814) (xy 9.689665 -107.001192) (xy 9.673578 -107.129818) (xy 9.649526 -107.257195)
			(xy 9.617601 -107.382831) (xy 9.577928 -107.506239) (xy 9.530658 -107.626942) (xy 9.475977 -107.744472)
			(xy 9.414094 -107.858376) (xy 9.345249 -107.968212) (xy 9.26971 -108.073555) (xy 9.187767 -108.173998)
			(xy 9.099738 -108.269153) (xy 9.005964 -108.358651) (xy 8.906807 -108.442146) (xy 8.802651 -108.519315)
			(xy 8.693899 -108.589859) (xy 8.580971 -108.653506) (xy 8.464306 -108.710009) (xy 8.344353 -108.75915)
			(xy 8.221577 -108.800738) (xy 8.096453 -108.834613) (xy 7.969465 -108.860643) (xy 7.841104 -108.878728)
			(xy 7.711868 -108.888798) (xy 7.582255 -108.890814) (xy 7.452768 -108.884768) (xy 7.323907 -108.870684)
			(xy 7.196171 -108.848615) (xy 7.070054 -108.818648) (xy 6.946044 -108.780899) (xy 6.824621 -108.735512)
			(xy 6.706254 -108.682665) (xy 6.591402 -108.622561) (xy 6.480509 -108.555433) (xy 6.374003 -108.481541)
			(xy 6.272297 -108.40117) (xy 6.175785 -108.314632) (xy 6.08484 -108.22226) (xy 5.999813 -108.124414)
			(xy 5.921033 -108.021471) (xy 5.848806 -107.913829) (xy 5.783411 -107.801905) (xy 5.7251 -107.686132)
			(xy 5.6741 -107.566958) (xy 5.630608 -107.444844) (xy 5.594791 -107.320261) (xy 5.566789 -107.193694)
			(xy 5.54671 -107.06563) (xy 5.534631 -106.936566) (xy 5.5306 -106.807) (xy 0.509016 -106.807) (xy 0.509016 -108.909866)
			(xy 86.877404 -108.909866) (xy 86.881424 -108.719215) (xy 86.893478 -108.528902) (xy 86.913544 -108.339267)
			(xy 86.941587 -108.150646) (xy 86.977556 -107.963376) (xy 87.021388 -107.777788) (xy 87.073005 -107.594213)
			(xy 87.132315 -107.412977) (xy 87.199213 -107.234402) (xy 87.273579 -107.058807) (xy 87.355281 -106.886502)
			(xy 87.444175 -106.717795) (xy 87.540101 -106.552985) (xy 87.64289 -106.392366) (xy 87.752359 -106.236223)
			(xy 87.868313 -106.084834) (xy 87.990547 -105.938467) (xy 88.118841 -105.797383) (xy 88.252969 -105.661834)
			(xy 88.392693 -105.532059) (xy 88.537763 -105.408289) (xy 88.687921 -105.290746) (xy 88.842902 -105.179637)
			(xy 89.002429 -105.07516) (xy 89.166218 -104.977501) (xy 89.333978 -104.886834) (xy 89.505412 -104.80332)
			(xy 89.680214 -104.727107) (xy 89.858073 -104.658331) (xy 90.038674 -104.597113) (xy 90.221694 -104.543564)
			(xy 90.40681 -104.497778) (xy 90.593691 -104.459836) (xy 90.782006 -104.429807) (xy 90.971419 -104.407742)
			(xy 91.161593 -104.393683) (xy 91.352192 -104.387653) (xy 91.542875 -104.389663) (xy 91.733304 -104.39971)
			(xy 91.92314 -104.417776) (xy 92.112046 -104.443829) (xy 92.299685 -104.477822) (xy 92.485725 -104.519695)
			(xy 92.669834 -104.569374) (xy 92.851685 -104.62677) (xy 93.030955 -104.691781) (xy 93.207325 -104.764292)
			(xy 93.380481 -104.844173) (xy 93.550116 -104.931283) (xy 93.715928 -105.025467) (xy 93.877622 -105.126558)
			(xy 94.03491 -105.234374) (xy 94.187513 -105.348726) (xy 94.335161 -105.469409) (xy 94.477589 -105.59621)
			(xy 94.614545 -105.728901) (xy 94.745786 -105.867249) (xy 94.871078 -106.011006) (xy 94.990198 -106.159917)
			(xy 95.102934 -106.313718) (xy 95.209087 -106.472134) (xy 95.308467 -106.634885) (xy 95.400897 -106.80168)
			(xy 95.486214 -106.972224) (xy 95.564266 -107.146212) (xy 95.634913 -107.323337) (xy 95.698031 -107.503282)
			(xy 95.753507 -107.685728) (xy 95.801242 -107.870351) (xy 95.841152 -108.056821) (xy 95.873165 -108.244809)
			(xy 95.897225 -108.433979) (xy 95.913288 -108.623995) (xy 95.921327 -108.814519) (xy 95.92183 -108.909866)
			(xy 95.921327 -109.005213) (xy 95.913288 -109.195737) (xy 95.897225 -109.385753) (xy 95.873165 -109.574923)
			(xy 95.841152 -109.762911) (xy 95.801242 -109.949381) (xy 95.753507 -110.134004) (xy 95.698031 -110.31645)
			(xy 95.634913 -110.496395) (xy 95.564266 -110.67352) (xy 95.486214 -110.847508) (xy 95.400897 -111.018052)
			(xy 95.308467 -111.184847) (xy 95.209087 -111.347598) (xy 95.102934 -111.506014) (xy 94.990198 -111.659815)
			(xy 94.871078 -111.808726) (xy 94.745786 -111.952483) (xy 94.614545 -112.090831) (xy 94.477589 -112.223522)
			(xy 94.335161 -112.350323) (xy 94.187513 -112.471006) (xy 94.03491 -112.585358) (xy 93.877622 -112.693174)
			(xy 93.715928 -112.794265) (xy 93.550116 -112.888449) (xy 93.380481 -112.975559) (xy 93.207325 -113.05544)
			(xy 93.030955 -113.127951) (xy 92.851685 -113.192962) (xy 92.669834 -113.250358) (xy 92.485725 -113.300037)
			(xy 92.299685 -113.34191) (xy 92.112046 -113.375903) (xy 91.92314 -113.401956) (xy 91.733304 -113.420022)
			(xy 91.542875 -113.430069) (xy 91.352192 -113.432079) (xy 91.161593 -113.426049) (xy 90.971419 -113.41199)
			(xy 90.782006 -113.389925) (xy 90.593691 -113.359896) (xy 90.40681 -113.321954) (xy 90.221694 -113.276168)
			(xy 90.038674 -113.222619) (xy 89.858073 -113.161401) (xy 89.680214 -113.092625) (xy 89.505412 -113.016412)
			(xy 89.333978 -112.932898) (xy 89.166218 -112.842231) (xy 89.002429 -112.744572) (xy 88.842902 -112.640095)
			(xy 88.687921 -112.528986) (xy 88.537763 -112.411443) (xy 88.392693 -112.287673) (xy 88.252969 -112.157898)
			(xy 88.118841 -112.022349) (xy 87.990547 -111.881265) (xy 87.868313 -111.734898) (xy 87.752359 -111.583509)
			(xy 87.64289 -111.427366) (xy 87.540101 -111.266747) (xy 87.444175 -111.101937) (xy 87.355281 -110.93323)
			(xy 87.273579 -110.760925) (xy 87.199213 -110.58533) (xy 87.132315 -110.406755) (xy 87.073005 -110.225519)
			(xy 87.021388 -110.041944) (xy 86.977556 -109.856356) (xy 86.941587 -109.669086) (xy 86.913544 -109.480465)
			(xy 86.893478 -109.29083) (xy 86.881424 -109.100517) (xy 86.877404 -108.909866) (xy 0.509016 -108.909866)
			(xy 0.509016 -118.09984) (xy 14.086591 -118.09984) (xy 14.090616 -117.957648) (xy 14.102679 -117.815912)
			(xy 14.122742 -117.675086) (xy 14.15074 -117.53562) (xy 14.186584 -117.397961) (xy 14.230158 -117.262551)
			(xy 14.281323 -117.129823) (xy 14.339916 -117.000202) (xy 14.405747 -116.874104) (xy 14.478608 -116.751932)
			(xy 14.558263 -116.634078) (xy 14.644459 -116.520919) (xy 14.736918 -116.412817) (xy 14.835346 -116.31012)
			(xy 14.939425 -116.213156) (xy 15.048824 -116.122236) (xy 15.163192 -116.03765) (xy 15.282161 -115.95967)
			(xy 15.405352 -115.888546) (xy 15.532369 -115.824505) (xy 15.662806 -115.767753) (xy 15.796245 -115.718471)
			(xy 15.932258 -115.676817) (xy 16.07041 -115.642925) (xy 16.210259 -115.616904) (xy 16.351355 -115.598836)
			(xy 16.493247 -115.588779) (xy 16.635482 -115.586766) (xy 16.777602 -115.592803) (xy 16.919153 -115.606871)
			(xy 17.059682 -115.628925) (xy 17.198737 -115.658894) (xy 17.335875 -115.696682) (xy 17.470655 -115.742168)
			(xy 17.602646 -115.795206) (xy 17.731425 -115.855627) (xy 17.856579 -115.923236) (xy 17.977707 -115.997818)
			(xy 18.094423 -116.079134) (xy 18.206351 -116.166922) (xy 18.313133 -116.260902) (xy 18.414427 -116.360772)
			(xy 18.509908 -116.466214) (xy 18.599272 -116.576888) (xy 18.68223 -116.692441) (xy 18.758519 -116.812502)
			(xy 18.827893 -116.936687) (xy 18.89013 -117.064598) (xy 18.945031 -117.195825) (xy 18.992419 -117.329948)
			(xy 19.032144 -117.466537) (xy 19.064077 -117.605155) (xy 19.088118 -117.745357) (xy 19.104187 -117.886695)
			(xy 19.112235 -118.028716) (xy 19.112738 -118.09984) (xy 19.112235 -118.170964) (xy 19.104187 -118.312985)
			(xy 19.088118 -118.454323) (xy 19.064077 -118.594525) (xy 19.032144 -118.733143) (xy 18.992419 -118.869732)
			(xy 18.945031 -119.003855) (xy 18.89013 -119.135082) (xy 18.827893 -119.262993) (xy 18.758519 -119.387178)
			(xy 18.68223 -119.507239) (xy 18.599272 -119.622792) (xy 18.509908 -119.733466) (xy 18.414427 -119.838908)
			(xy 18.313133 -119.938778) (xy 18.206351 -120.032758) (xy 18.094423 -120.120546) (xy 17.977707 -120.201862)
			(xy 17.856579 -120.276444) (xy 17.731425 -120.344053) (xy 17.602646 -120.404474) (xy 17.470655 -120.457512)
			(xy 17.335875 -120.502998) (xy 17.198737 -120.540786) (xy 17.059682 -120.570755) (xy 16.919153 -120.592809)
			(xy 16.777602 -120.606877) (xy 16.635482 -120.612914) (xy 16.493247 -120.610901) (xy 16.351355 -120.600844)
			(xy 16.210259 -120.582776) (xy 16.07041 -120.556755) (xy 15.932258 -120.522863) (xy 15.796245 -120.481209)
			(xy 15.662806 -120.431927) (xy 15.532369 -120.375175) (xy 15.405352 -120.311134) (xy 15.282161 -120.24001)
			(xy 15.163192 -120.16203) (xy 15.048824 -120.077444) (xy 14.939425 -119.986524) (xy 14.835346 -119.88956)
			(xy 14.736918 -119.786863) (xy 14.644459 -119.678761) (xy 14.558263 -119.565602) (xy 14.478608 -119.447748)
			(xy 14.405747 -119.325576) (xy 14.339916 -119.199478) (xy 14.281323 -119.069857) (xy 14.230158 -118.937129)
			(xy 14.186584 -118.801719) (xy 14.15074 -118.66406) (xy 14.122742 -118.524594) (xy 14.102679 -118.383768)
			(xy 14.090616 -118.242032) (xy 14.086591 -118.09984) (xy 0.509016 -118.09984) (xy 0.509016 -121.19991)
			(xy 75.486519 -121.19991) (xy 75.490544 -121.057718) (xy 75.502607 -120.915982) (xy 75.52267 -120.775156)
			(xy 75.550668 -120.63569) (xy 75.586512 -120.498031) (xy 75.630086 -120.362621) (xy 75.681251 -120.229893)
			(xy 75.739844 -120.100272) (xy 75.805675 -119.974174) (xy 75.878536 -119.852002) (xy 75.958191 -119.734148)
			(xy 76.044387 -119.620989) (xy 76.136846 -119.512887) (xy 76.235274 -119.41019) (xy 76.339353 -119.313226)
			(xy 76.448752 -119.222306) (xy 76.56312 -119.13772) (xy 76.682089 -119.05974) (xy 76.80528 -118.988616)
			(xy 76.932297 -118.924575) (xy 77.062734 -118.867823) (xy 77.196173 -118.818541) (xy 77.332186 -118.776887)
			(xy 77.470338 -118.742995) (xy 77.610187 -118.716974) (xy 77.751283 -118.698906) (xy 77.893175 -118.688849)
			(xy 78.03541 -118.686836) (xy 78.17753 -118.692873) (xy 78.319081 -118.706941) (xy 78.45961 -118.728995)
			(xy 78.598665 -118.758964) (xy 78.735803 -118.796752) (xy 78.870583 -118.842238) (xy 79.002574 -118.895276)
			(xy 79.131353 -118.955697) (xy 79.256507 -119.023306) (xy 79.377635 -119.097888) (xy 79.494351 -119.179204)
			(xy 79.606279 -119.266992) (xy 79.713061 -119.360972) (xy 79.814355 -119.460842) (xy 79.909836 -119.566284)
			(xy 79.9992 -119.676958) (xy 80.082158 -119.792511) (xy 80.158447 -119.912572) (xy 80.227821 -120.036757)
			(xy 80.290058 -120.164668) (xy 80.344959 -120.295895) (xy 80.392347 -120.430018) (xy 80.432072 -120.566607)
			(xy 80.464005 -120.705225) (xy 80.488046 -120.845427) (xy 80.504115 -120.986765) (xy 80.512163 -121.128786)
			(xy 80.512666 -121.19991) (xy 80.512163 -121.271034) (xy 80.504115 -121.413055) (xy 80.488046 -121.554393)
			(xy 80.464005 -121.694595) (xy 80.432072 -121.833213) (xy 80.392347 -121.969802) (xy 80.344959 -122.103925)
			(xy 80.290058 -122.235152) (xy 80.227821 -122.363063) (xy 80.158447 -122.487248) (xy 80.082158 -122.607309)
			(xy 79.9992 -122.722862) (xy 79.909836 -122.833536) (xy 79.814355 -122.938978) (xy 79.713061 -123.038848)
			(xy 79.606279 -123.132828) (xy 79.494351 -123.220616) (xy 79.377635 -123.301932) (xy 79.256507 -123.376514)
			(xy 79.131353 -123.444123) (xy 79.002574 -123.504544) (xy 78.870583 -123.557582) (xy 78.735803 -123.603068)
			(xy 78.598665 -123.640856) (xy 78.45961 -123.670825) (xy 78.319081 -123.692879) (xy 78.17753 -123.706947)
			(xy 78.03541 -123.712984) (xy 77.893175 -123.710971) (xy 77.751283 -123.700914) (xy 77.610187 -123.682846)
			(xy 77.470338 -123.656825) (xy 77.332186 -123.622933) (xy 77.196173 -123.581279) (xy 77.062734 -123.531997)
			(xy 76.932297 -123.475245) (xy 76.80528 -123.411204) (xy 76.682089 -123.34008) (xy 76.56312 -123.2621)
			(xy 76.448752 -123.177514) (xy 76.339353 -123.086594) (xy 76.235274 -122.98963) (xy 76.136846 -122.886933)
			(xy 76.044387 -122.778831) (xy 75.958191 -122.665672) (xy 75.878536 -122.547818) (xy 75.805675 -122.425646)
			(xy 75.739844 -122.299548) (xy 75.681251 -122.169927) (xy 75.630086 -122.037199) (xy 75.586512 -121.901789)
			(xy 75.550668 -121.76413) (xy 75.52267 -121.624664) (xy 75.502607 -121.483838) (xy 75.490544 -121.342102)
			(xy 75.486519 -121.19991) (xy 0.509016 -121.19991) (xy 0.509016 -130.746068) (xy 5.677649 -130.746068)
			(xy 5.677649 -130.619932) (xy 5.685569 -130.494044) (xy 5.701379 -130.368902) (xy 5.725014 -130.244999)
			(xy 5.756383 -130.122826) (xy 5.795361 -130.002863) (xy 5.841795 -129.885584) (xy 5.895502 -129.771452)
			(xy 5.956269 -129.660917) (xy 6.023856 -129.554417) (xy 6.097997 -129.45237) (xy 6.1784 -129.35518)
			(xy 6.264746 -129.26323) (xy 6.356696 -129.176884) (xy 6.453886 -129.096481) (xy 6.555933 -129.02234)
			(xy 6.662433 -128.954753) (xy 6.772968 -128.893986) (xy 6.8871 -128.840279) (xy 7.004379 -128.793845)
			(xy 7.124342 -128.754867) (xy 7.246515 -128.723498) (xy 7.370418 -128.699863) (xy 7.49556 -128.684053)
			(xy 7.621448 -128.676133) (xy 7.747584 -128.676133) (xy 7.873472 -128.684053) (xy 7.998614 -128.699863)
			(xy 8.122517 -128.723498) (xy 8.24469 -128.754867) (xy 8.364653 -128.793845) (xy 8.481932 -128.840279)
			(xy 8.596064 -128.893986) (xy 8.706599 -128.954753) (xy 8.813099 -129.02234) (xy 8.915146 -129.096481)
			(xy 9.012336 -129.176884) (xy 9.104286 -129.26323) (xy 9.190632 -129.35518) (xy 9.271035 -129.45237)
			(xy 9.345176 -129.554417) (xy 9.412763 -129.660917) (xy 9.47353 -129.771452) (xy 9.527237 -129.885584)
			(xy 9.573671 -130.002863) (xy 9.612649 -130.122826) (xy 9.644018 -130.244999) (xy 9.667653 -130.368902)
			(xy 9.683463 -130.494044) (xy 9.691383 -130.619932) (xy 9.691878 -130.683) (xy 9.691383 -130.746068)
			(xy 9.683463 -130.871956) (xy 9.667653 -130.997098) (xy 9.644018 -131.121001) (xy 9.612649 -131.243174)
			(xy 9.573671 -131.363137) (xy 9.527237 -131.480416) (xy 9.47353 -131.594548) (xy 9.412763 -131.705083)
			(xy 9.345176 -131.811583) (xy 9.271035 -131.91363) (xy 9.190632 -132.01082) (xy 9.104286 -132.10277)
			(xy 9.012336 -132.189116) (xy 8.915146 -132.269519) (xy 8.813099 -132.34366) (xy 8.706599 -132.411247)
			(xy 8.596064 -132.472014) (xy 8.481932 -132.525721) (xy 8.364653 -132.572155) (xy 8.24469 -132.611133)
			(xy 8.122517 -132.642502) (xy 7.998614 -132.666137) (xy 7.873472 -132.681947) (xy 7.747584 -132.689867)
			(xy 7.621448 -132.689867) (xy 7.49556 -132.681947) (xy 7.370418 -132.666137) (xy 7.246515 -132.642502)
			(xy 7.124342 -132.611133) (xy 7.004379 -132.572155) (xy 6.8871 -132.525721) (xy 6.772968 -132.472014)
			(xy 6.662433 -132.411247) (xy 6.555933 -132.34366) (xy 6.453886 -132.269519) (xy 6.356696 -132.189116)
			(xy 6.264746 -132.10277) (xy 6.1784 -132.01082) (xy 6.097997 -131.91363) (xy 6.023856 -131.811583)
			(xy 5.956269 -131.705083) (xy 5.895502 -131.594548) (xy 5.841795 -131.480416) (xy 5.795361 -131.363137)
			(xy 5.756383 -131.243174) (xy 5.725014 -131.121001) (xy 5.701379 -130.997098) (xy 5.685569 -130.871956)
			(xy 5.677649 -130.746068) (xy 0.509016 -130.746068) (xy 0.509016 -142.176068) (xy 5.677649 -142.176068)
			(xy 5.677649 -142.049932) (xy 5.685569 -141.924044) (xy 5.701379 -141.798902) (xy 5.725014 -141.674999)
			(xy 5.756383 -141.552826) (xy 5.795361 -141.432863) (xy 5.841795 -141.315584) (xy 5.895502 -141.201452)
			(xy 5.956269 -141.090917) (xy 6.023856 -140.984417) (xy 6.097997 -140.88237) (xy 6.1784 -140.78518)
			(xy 6.264746 -140.69323) (xy 6.356696 -140.606884) (xy 6.453886 -140.526481) (xy 6.555933 -140.45234)
			(xy 6.662433 -140.384753) (xy 6.772968 -140.323986) (xy 6.8871 -140.270279) (xy 7.004379 -140.223845)
			(xy 7.124342 -140.184867) (xy 7.246515 -140.153498) (xy 7.370418 -140.129863) (xy 7.49556 -140.114053)
			(xy 7.621448 -140.106133) (xy 7.747584 -140.106133) (xy 7.873472 -140.114053) (xy 7.998614 -140.129863)
			(xy 8.122517 -140.153498) (xy 8.24469 -140.184867) (xy 8.364653 -140.223845) (xy 8.441392 -140.254228)
			(xy 39.818818 -140.254228) (xy 39.819523 -140.195605) (xy 39.828091 -140.078667) (xy 39.844787 -139.962611)
			(xy 39.86953 -139.848001) (xy 39.902199 -139.735393) (xy 39.942635 -139.625335) (xy 39.990642 -139.518363)
			(xy 40.045986 -139.414996) (xy 40.108399 -139.315737) (xy 40.177577 -139.221068) (xy 40.253183 -139.13145)
			(xy 40.334851 -139.047318) (xy 40.422182 -138.969081) (xy 40.514753 -138.89712) (xy 40.612113 -138.831784)
			(xy 40.713789 -138.773392) (xy 40.819288 -138.722226) (xy 40.928095 -138.678537) (xy 41.039682 -138.642535)
			(xy 41.153506 -138.614397) (xy 41.269014 -138.594259) (xy 41.385645 -138.582218) (xy 41.502832 -138.578334)
			(xy 41.620004 -138.582625) (xy 41.736593 -138.595071) (xy 41.85203 -138.615611) (xy 41.965756 -138.644144)
			(xy 42.077217 -138.680533) (xy 42.185872 -138.724601) (xy 42.291192 -138.776133) (xy 42.392665 -138.834878)
			(xy 42.489797 -138.900552) (xy 42.582117 -138.972834) (xy 42.669176 -139.051374) (xy 42.750551 -139.135789)
			(xy 42.825845 -139.225669) (xy 42.894694 -139.320578) (xy 42.956761 -139.420054) (xy 43.011746 -139.523612)
			(xy 43.059381 -139.630751) (xy 43.099434 -139.740948) (xy 43.131712 -139.853669) (xy 43.156056 -139.968365)
			(xy 43.172348 -140.084478) (xy 43.18051 -140.201445) (xy 43.181016 -140.26007) (xy 43.180861 -140.290833)
			(xy 43.178574 -140.352316) (xy 43.176444 -140.383006) (xy 43.175682 -140.392404) (xy 43.170622 -140.450806)
			(xy 43.153396 -140.566771) (xy 43.12813 -140.681253) (xy 43.094949 -140.793697) (xy 43.054014 -140.903555)
			(xy 43.005523 -141.010294) (xy 42.949712 -141.113395) (xy 42.886853 -141.212356) (xy 42.817252 -141.306696)
			(xy 42.741246 -141.395958) (xy 42.659204 -141.479706) (xy 42.571527 -141.557535) (xy 42.503292 -141.61008)
			(xy 93.15476 -141.61008) (xy 93.158776 -141.49381) (xy 93.170803 -141.378095) (xy 93.190785 -141.263485)
			(xy 93.218627 -141.150526) (xy 93.254196 -141.039758) (xy 93.297322 -140.931707) (xy 93.347799 -140.826889)
			(xy 93.405388 -140.725804) (xy 93.469814 -140.628932) (xy 93.540769 -140.536736) (xy 93.617916 -140.449655)
			(xy 93.700887 -140.368104) (xy 93.789287 -140.292472) (xy 93.882694 -140.223118) (xy 93.980663 -140.160375)
			(xy 94.082727 -140.104539) (xy 94.188401 -140.055878) (xy 94.29718 -140.014624) (xy 94.408545 -139.980973)
			(xy 94.521968 -139.955085) (xy 94.636905 -139.937084) (xy 94.752811 -139.927055) (xy 94.869133 -139.925047)
			(xy 94.985316 -139.931069) (xy 95.100807 -139.945092) (xy 95.215055 -139.96705) (xy 95.327516 -139.996837)
			(xy 95.437654 -140.034312) (xy 95.544944 -140.079297) (xy 95.648875 -140.131576) (xy 95.748951 -140.190901)
			(xy 95.844697 -140.256989) (xy 95.935654 -140.329525) (xy 96.02139 -140.408164) (xy 96.101497 -140.49253)
			(xy 96.175593 -140.582222) (xy 96.243323 -140.676812) (xy 96.304367 -140.77585) (xy 96.358432 -140.878863)
			(xy 96.405262 -140.98536) (xy 96.444633 -141.094835) (xy 96.476357 -141.206765) (xy 96.500283 -141.320617)
			(xy 96.516297 -141.435849) (xy 96.524324 -141.551911) (xy 96.524826 -141.61008) (xy 96.524324 -141.668249)
			(xy 96.516297 -141.784311) (xy 96.500283 -141.899543) (xy 96.476357 -142.013395) (xy 96.444633 -142.125325)
			(xy 96.405262 -142.2348) (xy 96.358432 -142.341297) (xy 96.304367 -142.44431) (xy 96.243323 -142.543348)
			(xy 96.175593 -142.637938) (xy 96.101497 -142.72763) (xy 96.02139 -142.811996) (xy 95.935654 -142.890635)
			(xy 95.844697 -142.963171) (xy 95.748951 -143.029259) (xy 95.648875 -143.088584) (xy 95.544944 -143.140863)
			(xy 95.437654 -143.185848) (xy 95.327516 -143.223323) (xy 95.215055 -143.25311) (xy 95.100807 -143.275068)
			(xy 94.985316 -143.289091) (xy 94.869133 -143.295113) (xy 94.752811 -143.293105) (xy 94.636905 -143.283076)
			(xy 94.521968 -143.265075) (xy 94.408545 -143.239187) (xy 94.29718 -143.205536) (xy 94.188401 -143.164282)
			(xy 94.082727 -143.115621) (xy 93.980663 -143.059785) (xy 93.882694 -142.997042) (xy 93.789287 -142.927688)
			(xy 93.700887 -142.852056) (xy 93.617916 -142.770505) (xy 93.540769 -142.683424) (xy 93.469814 -142.591228)
			(xy 93.405388 -142.494356) (xy 93.347799 -142.393271) (xy 93.297322 -142.288453) (xy 93.254196 -142.180402)
			(xy 93.218627 -142.069634) (xy 93.190785 -141.956675) (xy 93.170803 -141.842065) (xy 93.158776 -141.72635)
			(xy 93.15476 -141.61008) (xy 42.503292 -141.61008) (xy 42.47864 -141.629064) (xy 42.380994 -141.693948)
			(xy 42.279065 -141.75187) (xy 42.173347 -141.802549) (xy 42.064355 -141.845738) (xy 41.952619 -141.881228)
			(xy 41.838681 -141.908845) (xy 41.723096 -141.928457) (xy 41.606425 -141.939967) (xy 41.489236 -141.943319)
			(xy 41.372098 -141.938497) (xy 41.25558 -141.925525) (xy 41.14025 -141.904466) (xy 41.026668 -141.875421)
			(xy 40.915385 -141.838533) (xy 40.806943 -141.79398) (xy 40.70187 -141.74198) (xy 40.600675 -141.682784)
			(xy 40.50385 -141.616681) (xy 40.411868 -141.543992) (xy 40.325173 -141.46507) (xy 40.244189 -141.380299)
			(xy 40.169308 -141.290091) (xy 40.100895 -141.194885) (xy 40.039282 -141.095143) (xy 39.984769 -140.991351)
			(xy 39.937621 -140.884012) (xy 39.898066 -140.773649) (xy 39.866298 -140.660798) (xy 39.842471 -140.546008)
			(xy 39.826699 -140.429836) (xy 39.819061 -140.312848) (xy 39.818818 -140.254228) (xy 8.441392 -140.254228)
			(xy 8.481932 -140.270279) (xy 8.596064 -140.323986) (xy 8.706599 -140.384753) (xy 8.813099 -140.45234)
			(xy 8.915146 -140.526481) (xy 9.012336 -140.606884) (xy 9.104286 -140.69323) (xy 9.190632 -140.78518)
			(xy 9.271035 -140.88237) (xy 9.345176 -140.984417) (xy 9.412763 -141.090917) (xy 9.47353 -141.201452)
			(xy 9.527237 -141.315584) (xy 9.573671 -141.432863) (xy 9.612649 -141.552826) (xy 9.644018 -141.674999)
			(xy 9.667653 -141.798902) (xy 9.683463 -141.924044) (xy 9.691383 -142.049932) (xy 9.691878 -142.113)
			(xy 9.691383 -142.176068) (xy 9.683463 -142.301956) (xy 9.667653 -142.427098) (xy 9.644018 -142.551001)
			(xy 9.612649 -142.673174) (xy 9.573671 -142.793137) (xy 9.527237 -142.910416) (xy 9.47353 -143.024548)
			(xy 9.412763 -143.135083) (xy 9.345176 -143.241583) (xy 9.271035 -143.34363) (xy 9.190632 -143.44082)
			(xy 9.104286 -143.53277) (xy 9.012336 -143.619116) (xy 8.915146 -143.699519) (xy 8.813099 -143.77366)
			(xy 8.706599 -143.841247) (xy 8.596064 -143.902014) (xy 8.481932 -143.955721) (xy 8.364653 -144.002155)
			(xy 8.24469 -144.041133) (xy 8.122517 -144.072502) (xy 7.998614 -144.096137) (xy 7.873472 -144.111947)
			(xy 7.747584 -144.119867) (xy 7.621448 -144.119867) (xy 7.49556 -144.111947) (xy 7.370418 -144.096137)
			(xy 7.246515 -144.072502) (xy 7.124342 -144.041133) (xy 7.004379 -144.002155) (xy 6.8871 -143.955721)
			(xy 6.772968 -143.902014) (xy 6.662433 -143.841247) (xy 6.555933 -143.77366) (xy 6.453886 -143.699519)
			(xy 6.356696 -143.619116) (xy 6.264746 -143.53277) (xy 6.1784 -143.44082) (xy 6.097997 -143.34363)
			(xy 6.023856 -143.241583) (xy 5.956269 -143.135083) (xy 5.895502 -143.024548) (xy 5.841795 -142.910416)
			(xy 5.795361 -142.793137) (xy 5.756383 -142.673174) (xy 5.725014 -142.551001) (xy 5.701379 -142.427098)
			(xy 5.685569 -142.301956) (xy 5.677649 -142.176068) (xy 0.509016 -142.176068) (xy 0.509016 -153.359866)
			(xy 86.877404 -153.359866) (xy 86.881424 -153.169215) (xy 86.893478 -152.978902) (xy 86.913544 -152.789267)
			(xy 86.941587 -152.600646) (xy 86.977556 -152.413376) (xy 87.021388 -152.227788) (xy 87.073005 -152.044213)
			(xy 87.132315 -151.862977) (xy 87.199213 -151.684402) (xy 87.273579 -151.508807) (xy 87.355281 -151.336502)
			(xy 87.444175 -151.167795) (xy 87.540101 -151.002985) (xy 87.64289 -150.842366) (xy 87.752359 -150.686223)
			(xy 87.868313 -150.534834) (xy 87.990547 -150.388467) (xy 88.118841 -150.247383) (xy 88.252969 -150.111834)
			(xy 88.392693 -149.982059) (xy 88.537763 -149.858289) (xy 88.687921 -149.740746) (xy 88.842902 -149.629637)
			(xy 89.002429 -149.52516) (xy 89.166218 -149.427501) (xy 89.333978 -149.336834) (xy 89.505412 -149.25332)
			(xy 89.680214 -149.177107) (xy 89.858073 -149.108331) (xy 90.038674 -149.047113) (xy 90.221694 -148.993564)
			(xy 90.40681 -148.947778) (xy 90.593691 -148.909836) (xy 90.782006 -148.879807) (xy 90.971419 -148.857742)
			(xy 91.161593 -148.843683) (xy 91.352192 -148.837653) (xy 91.542875 -148.839663) (xy 91.733304 -148.84971)
			(xy 91.92314 -148.867776) (xy 92.112046 -148.893829) (xy 92.299685 -148.927822) (xy 92.485725 -148.969695)
			(xy 92.669834 -149.019374) (xy 92.851685 -149.07677) (xy 93.030955 -149.141781) (xy 93.207325 -149.214292)
			(xy 93.380481 -149.294173) (xy 93.550116 -149.381283) (xy 93.715928 -149.475467) (xy 93.877622 -149.576558)
			(xy 94.03491 -149.684374) (xy 94.187513 -149.798726) (xy 94.335161 -149.919409) (xy 94.477589 -150.04621)
			(xy 94.614545 -150.178901) (xy 94.745786 -150.317249) (xy 94.871078 -150.461006) (xy 94.990198 -150.609917)
			(xy 95.102934 -150.763718) (xy 95.209087 -150.922134) (xy 95.308467 -151.084885) (xy 95.400897 -151.25168)
			(xy 95.486214 -151.422224) (xy 95.564266 -151.596212) (xy 95.634913 -151.773337) (xy 95.698031 -151.953282)
			(xy 95.753507 -152.135728) (xy 95.801242 -152.320351) (xy 95.841152 -152.506821) (xy 95.873165 -152.694809)
			(xy 95.897225 -152.883979) (xy 95.913288 -153.073995) (xy 95.921327 -153.264519) (xy 95.92183 -153.359866)
			(xy 95.921327 -153.455213) (xy 95.913288 -153.645737) (xy 95.897225 -153.835753) (xy 95.873165 -154.024923)
			(xy 95.841152 -154.212911) (xy 95.801242 -154.399381) (xy 95.753507 -154.584004) (xy 95.698031 -154.76645)
			(xy 95.634913 -154.946395) (xy 95.564266 -155.12352) (xy 95.486214 -155.297508) (xy 95.400897 -155.468052)
			(xy 95.308467 -155.634847) (xy 95.209087 -155.797598) (xy 95.102934 -155.956014) (xy 94.990198 -156.109815)
			(xy 94.871078 -156.258726) (xy 94.745786 -156.402483) (xy 94.614545 -156.540831) (xy 94.477589 -156.673522)
			(xy 94.335161 -156.800323) (xy 94.187513 -156.921006) (xy 94.03491 -157.035358) (xy 93.877622 -157.143174)
			(xy 93.715928 -157.244265) (xy 93.550116 -157.338449) (xy 93.380481 -157.425559) (xy 93.207325 -157.50544)
			(xy 93.030955 -157.577951) (xy 92.851685 -157.642962) (xy 92.669834 -157.700358) (xy 92.485725 -157.750037)
			(xy 92.299685 -157.79191) (xy 92.112046 -157.825903) (xy 91.92314 -157.851956) (xy 91.733304 -157.870022)
			(xy 91.542875 -157.880069) (xy 91.352192 -157.882079) (xy 91.161593 -157.876049) (xy 90.971419 -157.86199)
			(xy 90.782006 -157.839925) (xy 90.593691 -157.809896) (xy 90.40681 -157.771954) (xy 90.221694 -157.726168)
			(xy 90.038674 -157.672619) (xy 89.858073 -157.611401) (xy 89.680214 -157.542625) (xy 89.505412 -157.466412)
			(xy 89.333978 -157.382898) (xy 89.166218 -157.292231) (xy 89.002429 -157.194572) (xy 88.842902 -157.090095)
			(xy 88.687921 -156.978986) (xy 88.537763 -156.861443) (xy 88.392693 -156.737673) (xy 88.252969 -156.607898)
			(xy 88.118841 -156.472349) (xy 87.990547 -156.331265) (xy 87.868313 -156.184898) (xy 87.752359 -156.033509)
			(xy 87.64289 -155.877366) (xy 87.540101 -155.716747) (xy 87.444175 -155.551937) (xy 87.355281 -155.38323)
			(xy 87.273579 -155.210925) (xy 87.199213 -155.03533) (xy 87.132315 -154.856755) (xy 87.073005 -154.675519)
			(xy 87.021388 -154.491944) (xy 86.977556 -154.306356) (xy 86.941587 -154.119086) (xy 86.913544 -153.930465)
			(xy 86.893478 -153.74083) (xy 86.881424 -153.550517) (xy 86.877404 -153.359866) (xy 0.509016 -153.359866)
			(xy 0.509016 -184.704228) (xy 39.818818 -184.704228) (xy 39.819523 -184.645605) (xy 39.828091 -184.528667)
			(xy 39.844787 -184.412611) (xy 39.86953 -184.298001) (xy 39.902199 -184.185393) (xy 39.942635 -184.075335)
			(xy 39.990642 -183.968363) (xy 40.045986 -183.864996) (xy 40.108399 -183.765737) (xy 40.177577 -183.671068)
			(xy 40.253183 -183.58145) (xy 40.334851 -183.497318) (xy 40.422182 -183.419081) (xy 40.514753 -183.34712)
			(xy 40.612113 -183.281784) (xy 40.713789 -183.223392) (xy 40.819288 -183.172226) (xy 40.928095 -183.128537)
			(xy 41.039682 -183.092535) (xy 41.153506 -183.064397) (xy 41.269014 -183.044259) (xy 41.385645 -183.032218)
			(xy 41.502832 -183.028334) (xy 41.620004 -183.032625) (xy 41.736593 -183.045071) (xy 41.85203 -183.065611)
			(xy 41.965756 -183.094144) (xy 42.077217 -183.130533) (xy 42.185872 -183.174601) (xy 42.291192 -183.226133)
			(xy 42.392665 -183.284878) (xy 42.489797 -183.350552) (xy 42.582117 -183.422834) (xy 42.669176 -183.501374)
			(xy 42.750551 -183.585789) (xy 42.825845 -183.675669) (xy 42.894694 -183.770578) (xy 42.956761 -183.870054)
			(xy 43.011746 -183.973612) (xy 43.059381 -184.080751) (xy 43.099434 -184.190948) (xy 43.131712 -184.303669)
			(xy 43.156056 -184.418365) (xy 43.172348 -184.534478) (xy 43.18051 -184.651445) (xy 43.181016 -184.71007)
			(xy 43.180861 -184.740833) (xy 43.178574 -184.802316) (xy 43.176444 -184.833006) (xy 43.175682 -184.842404)
			(xy 43.170622 -184.900806) (xy 43.153396 -185.016771) (xy 43.12813 -185.131253) (xy 43.094949 -185.243697)
			(xy 43.054014 -185.353555) (xy 43.005523 -185.460294) (xy 42.949712 -185.563395) (xy 42.886853 -185.662356)
			(xy 42.817252 -185.756696) (xy 42.741246 -185.845958) (xy 42.659204 -185.929706) (xy 42.571527 -186.007535)
			(xy 42.503292 -186.06008) (xy 93.15476 -186.06008) (xy 93.158776 -185.94381) (xy 93.170803 -185.828095)
			(xy 93.190785 -185.713485) (xy 93.218627 -185.600526) (xy 93.254196 -185.489758) (xy 93.297322 -185.381707)
			(xy 93.347799 -185.276889) (xy 93.405388 -185.175804) (xy 93.469814 -185.078932) (xy 93.540769 -184.986736)
			(xy 93.617916 -184.899655) (xy 93.700887 -184.818104) (xy 93.789287 -184.742472) (xy 93.882694 -184.673118)
			(xy 93.980663 -184.610375) (xy 94.082727 -184.554539) (xy 94.188401 -184.505878) (xy 94.29718 -184.464624)
			(xy 94.408545 -184.430973) (xy 94.521968 -184.405085) (xy 94.636905 -184.387084) (xy 94.752811 -184.377055)
			(xy 94.869133 -184.375047) (xy 94.985316 -184.381069) (xy 95.100807 -184.395092) (xy 95.215055 -184.41705)
			(xy 95.327516 -184.446837) (xy 95.437654 -184.484312) (xy 95.544944 -184.529297) (xy 95.648875 -184.581576)
			(xy 95.748951 -184.640901) (xy 95.844697 -184.706989) (xy 95.935654 -184.779525) (xy 96.02139 -184.858164)
			(xy 96.101497 -184.94253) (xy 96.175593 -185.032222) (xy 96.243323 -185.126812) (xy 96.304367 -185.22585)
			(xy 96.358432 -185.328863) (xy 96.405262 -185.43536) (xy 96.444633 -185.544835) (xy 96.476357 -185.656765)
			(xy 96.500283 -185.770617) (xy 96.516297 -185.885849) (xy 96.524324 -186.001911) (xy 96.524826 -186.06008)
			(xy 96.524324 -186.118249) (xy 96.516297 -186.234311) (xy 96.500283 -186.349543) (xy 96.476357 -186.463395)
			(xy 96.444633 -186.575325) (xy 96.405262 -186.6848) (xy 96.358432 -186.791297) (xy 96.304367 -186.89431)
			(xy 96.243323 -186.993348) (xy 96.175593 -187.087938) (xy 96.101497 -187.17763) (xy 96.02139 -187.261996)
			(xy 95.935654 -187.340635) (xy 95.844697 -187.413171) (xy 95.748951 -187.479259) (xy 95.648875 -187.538584)
			(xy 95.544944 -187.590863) (xy 95.437654 -187.635848) (xy 95.327516 -187.673323) (xy 95.215055 -187.70311)
			(xy 95.100807 -187.725068) (xy 94.985316 -187.739091) (xy 94.869133 -187.745113) (xy 94.752811 -187.743105)
			(xy 94.636905 -187.733076) (xy 94.521968 -187.715075) (xy 94.408545 -187.689187) (xy 94.29718 -187.655536)
			(xy 94.188401 -187.614282) (xy 94.082727 -187.565621) (xy 93.980663 -187.509785) (xy 93.882694 -187.447042)
			(xy 93.789287 -187.377688) (xy 93.700887 -187.302056) (xy 93.617916 -187.220505) (xy 93.540769 -187.133424)
			(xy 93.469814 -187.041228) (xy 93.405388 -186.944356) (xy 93.347799 -186.843271) (xy 93.297322 -186.738453)
			(xy 93.254196 -186.630402) (xy 93.218627 -186.519634) (xy 93.190785 -186.406675) (xy 93.170803 -186.292065)
			(xy 93.158776 -186.17635) (xy 93.15476 -186.06008) (xy 42.503292 -186.06008) (xy 42.47864 -186.079064)
			(xy 42.380994 -186.143948) (xy 42.279065 -186.20187) (xy 42.173347 -186.252549) (xy 42.064355 -186.295738)
			(xy 41.952619 -186.331228) (xy 41.838681 -186.358845) (xy 41.723096 -186.378457) (xy 41.606425 -186.389967)
			(xy 41.489236 -186.393319) (xy 41.372098 -186.388497) (xy 41.25558 -186.375525) (xy 41.14025 -186.354466)
			(xy 41.026668 -186.325421) (xy 40.915385 -186.288533) (xy 40.806943 -186.24398) (xy 40.70187 -186.19198)
			(xy 40.600675 -186.132784) (xy 40.50385 -186.066681) (xy 40.411868 -185.993992) (xy 40.325173 -185.91507)
			(xy 40.244189 -185.830299) (xy 40.169308 -185.740091) (xy 40.100895 -185.644885) (xy 40.039282 -185.545143)
			(xy 39.984769 -185.441351) (xy 39.937621 -185.334012) (xy 39.898066 -185.223649) (xy 39.866298 -185.110798)
			(xy 39.842471 -184.996008) (xy 39.826699 -184.879836) (xy 39.819061 -184.762848) (xy 39.818818 -184.704228)
			(xy 0.509016 -184.704228) (xy 0.509016 -197.81012) (xy 86.877404 -197.81012) (xy 86.881424 -197.619469)
			(xy 86.893478 -197.429156) (xy 86.913544 -197.239521) (xy 86.941587 -197.0509) (xy 86.977556 -196.86363)
			(xy 87.021388 -196.678042) (xy 87.073005 -196.494467) (xy 87.132315 -196.313231) (xy 87.199213 -196.134656)
			(xy 87.273579 -195.959061) (xy 87.355281 -195.786756) (xy 87.444175 -195.618049) (xy 87.540101 -195.453239)
			(xy 87.64289 -195.29262) (xy 87.752359 -195.136477) (xy 87.868313 -194.985088) (xy 87.990547 -194.838721)
			(xy 88.118841 -194.697637) (xy 88.252969 -194.562088) (xy 88.392693 -194.432313) (xy 88.537763 -194.308543)
			(xy 88.687921 -194.191) (xy 88.842902 -194.079891) (xy 89.002429 -193.975414) (xy 89.166218 -193.877755)
			(xy 89.333978 -193.787088) (xy 89.505412 -193.703574) (xy 89.680214 -193.627361) (xy 89.858073 -193.558585)
			(xy 90.038674 -193.497367) (xy 90.221694 -193.443818) (xy 90.40681 -193.398032) (xy 90.593691 -193.36009)
			(xy 90.782006 -193.330061) (xy 90.971419 -193.307996) (xy 91.161593 -193.293937) (xy 91.352192 -193.287907)
			(xy 91.542875 -193.289917) (xy 91.733304 -193.299964) (xy 91.92314 -193.31803) (xy 92.112046 -193.344083)
			(xy 92.299685 -193.378076) (xy 92.485725 -193.419949) (xy 92.669834 -193.469628) (xy 92.851685 -193.527024)
			(xy 93.030955 -193.592035) (xy 93.207325 -193.664546) (xy 93.380481 -193.744427) (xy 93.550116 -193.831537)
			(xy 93.715928 -193.925721) (xy 93.877622 -194.026812) (xy 94.03491 -194.134628) (xy 94.187513 -194.24898)
			(xy 94.335161 -194.369663) (xy 94.477589 -194.496464) (xy 94.614545 -194.629155) (xy 94.745786 -194.767503)
			(xy 94.871078 -194.91126) (xy 94.990198 -195.060171) (xy 95.102934 -195.213972) (xy 95.209087 -195.372388)
			(xy 95.308467 -195.535139) (xy 95.400897 -195.701934) (xy 95.486214 -195.872478) (xy 95.564266 -196.046466)
			(xy 95.634913 -196.223591) (xy 95.698031 -196.403536) (xy 95.753507 -196.585982) (xy 95.801242 -196.770605)
			(xy 95.841152 -196.957075) (xy 95.873165 -197.145063) (xy 95.897225 -197.334233) (xy 95.913288 -197.524249)
			(xy 95.921327 -197.714773) (xy 95.92183 -197.81012) (xy 95.921327 -197.905467) (xy 95.913288 -198.095991)
			(xy 95.897225 -198.286007) (xy 95.873165 -198.475177) (xy 95.841152 -198.663165) (xy 95.801242 -198.849635)
			(xy 95.753507 -199.034258) (xy 95.698031 -199.216704) (xy 95.634913 -199.396649) (xy 95.564266 -199.573774)
			(xy 95.486214 -199.747762) (xy 95.400897 -199.918306) (xy 95.308467 -200.085101) (xy 95.209087 -200.247852)
			(xy 95.102934 -200.406268) (xy 94.990198 -200.560069) (xy 94.871078 -200.70898) (xy 94.745786 -200.852737)
			(xy 94.614545 -200.991085) (xy 94.477589 -201.123776) (xy 94.335161 -201.250577) (xy 94.187513 -201.37126)
			(xy 94.03491 -201.485612) (xy 93.877622 -201.593428) (xy 93.715928 -201.694519) (xy 93.550116 -201.788703)
			(xy 93.380481 -201.875813) (xy 93.207325 -201.955694) (xy 93.030955 -202.028205) (xy 92.851685 -202.093216)
			(xy 92.669834 -202.150612) (xy 92.485725 -202.200291) (xy 92.299685 -202.242164) (xy 92.112046 -202.276157)
			(xy 91.92314 -202.30221) (xy 91.733304 -202.320276) (xy 91.542875 -202.330323) (xy 91.352192 -202.332333)
			(xy 91.161593 -202.326303) (xy 90.971419 -202.312244) (xy 90.782006 -202.290179) (xy 90.593691 -202.26015)
			(xy 90.40681 -202.222208) (xy 90.221694 -202.176422) (xy 90.038674 -202.122873) (xy 89.858073 -202.061655)
			(xy 89.680214 -201.992879) (xy 89.505412 -201.916666) (xy 89.333978 -201.833152) (xy 89.166218 -201.742485)
			(xy 89.002429 -201.644826) (xy 88.842902 -201.540349) (xy 88.687921 -201.42924) (xy 88.537763 -201.311697)
			(xy 88.392693 -201.187927) (xy 88.252969 -201.058152) (xy 88.118841 -200.922603) (xy 87.990547 -200.781519)
			(xy 87.868313 -200.635152) (xy 87.752359 -200.483763) (xy 87.64289 -200.32762) (xy 87.540101 -200.167001)
			(xy 87.444175 -200.002191) (xy 87.355281 -199.833484) (xy 87.273579 -199.661179) (xy 87.199213 -199.485584)
			(xy 87.132315 -199.307009) (xy 87.073005 -199.125773) (xy 87.021388 -198.942198) (xy 86.977556 -198.75661)
			(xy 86.941587 -198.56934) (xy 86.913544 -198.380719) (xy 86.893478 -198.191084) (xy 86.881424 -198.000771)
			(xy 86.877404 -197.81012) (xy 0.509016 -197.81012) (xy 0.509016 -206.99984) (xy 14.086591 -206.99984)
			(xy 14.090616 -206.857648) (xy 14.102679 -206.715912) (xy 14.122742 -206.575086) (xy 14.15074 -206.43562)
			(xy 14.186584 -206.297961) (xy 14.230158 -206.162551) (xy 14.281323 -206.029823) (xy 14.339916 -205.900202)
			(xy 14.405747 -205.774104) (xy 14.478608 -205.651932) (xy 14.558263 -205.534078) (xy 14.644459 -205.420919)
			(xy 14.736918 -205.312817) (xy 14.835346 -205.21012) (xy 14.939425 -205.113156) (xy 15.048824 -205.022236)
			(xy 15.163192 -204.93765) (xy 15.282161 -204.85967) (xy 15.405352 -204.788546) (xy 15.532369 -204.724505)
			(xy 15.662806 -204.667753) (xy 15.796245 -204.618471) (xy 15.932258 -204.576817) (xy 16.07041 -204.542925)
			(xy 16.210259 -204.516904) (xy 16.351355 -204.498836) (xy 16.493247 -204.488779) (xy 16.635482 -204.486766)
			(xy 16.777602 -204.492803) (xy 16.919153 -204.506871) (xy 17.059682 -204.528925) (xy 17.198737 -204.558894)
			(xy 17.335875 -204.596682) (xy 17.470655 -204.642168) (xy 17.602646 -204.695206) (xy 17.731425 -204.755627)
			(xy 17.856579 -204.823236) (xy 17.977707 -204.897818) (xy 18.094423 -204.979134) (xy 18.206351 -205.066922)
			(xy 18.313133 -205.160902) (xy 18.414427 -205.260772) (xy 18.509908 -205.366214) (xy 18.599272 -205.476888)
			(xy 18.68223 -205.592441) (xy 18.758519 -205.712502) (xy 18.827893 -205.836687) (xy 18.89013 -205.964598)
			(xy 18.945031 -206.095825) (xy 18.992419 -206.229948) (xy 19.032144 -206.366537) (xy 19.064077 -206.505155)
			(xy 19.088118 -206.645357) (xy 19.104187 -206.786695) (xy 19.112235 -206.928716) (xy 19.112738 -206.99984)
			(xy 19.112235 -207.070964) (xy 19.104187 -207.212985) (xy 19.088118 -207.354323) (xy 19.064077 -207.494525)
			(xy 19.032144 -207.633143) (xy 18.992419 -207.769732) (xy 18.945031 -207.903855) (xy 18.89013 -208.035082)
			(xy 18.827893 -208.162993) (xy 18.758519 -208.287178) (xy 18.68223 -208.407239) (xy 18.599272 -208.522792)
			(xy 18.509908 -208.633466) (xy 18.414427 -208.738908) (xy 18.313133 -208.838778) (xy 18.206351 -208.932758)
			(xy 18.094423 -209.020546) (xy 17.977707 -209.101862) (xy 17.856579 -209.176444) (xy 17.731425 -209.244053)
			(xy 17.602646 -209.304474) (xy 17.470655 -209.357512) (xy 17.335875 -209.402998) (xy 17.198737 -209.440786)
			(xy 17.059682 -209.470755) (xy 16.919153 -209.492809) (xy 16.777602 -209.506877) (xy 16.635482 -209.512914)
			(xy 16.493247 -209.510901) (xy 16.351355 -209.500844) (xy 16.210259 -209.482776) (xy 16.07041 -209.456755)
			(xy 15.932258 -209.422863) (xy 15.796245 -209.381209) (xy 15.662806 -209.331927) (xy 15.532369 -209.275175)
			(xy 15.405352 -209.211134) (xy 15.282161 -209.14001) (xy 15.163192 -209.06203) (xy 15.048824 -208.977444)
			(xy 14.939425 -208.886524) (xy 14.835346 -208.78956) (xy 14.736918 -208.686863) (xy 14.644459 -208.578761)
			(xy 14.558263 -208.465602) (xy 14.478608 -208.347748) (xy 14.405747 -208.225576) (xy 14.339916 -208.099478)
			(xy 14.281323 -207.969857) (xy 14.230158 -207.837129) (xy 14.186584 -207.701719) (xy 14.15074 -207.56406)
			(xy 14.122742 -207.424594) (xy 14.102679 -207.283768) (xy 14.090616 -207.142032) (xy 14.086591 -206.99984)
			(xy 0.509016 -206.99984) (xy 0.509016 -210.09991) (xy 75.486519 -210.09991) (xy 75.490544 -209.957718)
			(xy 75.502607 -209.815982) (xy 75.52267 -209.675156) (xy 75.550668 -209.53569) (xy 75.586512 -209.398031)
			(xy 75.630086 -209.262621) (xy 75.681251 -209.129893) (xy 75.739844 -209.000272) (xy 75.805675 -208.874174)
			(xy 75.878536 -208.752002) (xy 75.958191 -208.634148) (xy 76.044387 -208.520989) (xy 76.136846 -208.412887)
			(xy 76.235274 -208.31019) (xy 76.339353 -208.213226) (xy 76.448752 -208.122306) (xy 76.56312 -208.03772)
			(xy 76.682089 -207.95974) (xy 76.80528 -207.888616) (xy 76.932297 -207.824575) (xy 77.062734 -207.767823)
			(xy 77.196173 -207.718541) (xy 77.332186 -207.676887) (xy 77.470338 -207.642995) (xy 77.610187 -207.616974)
			(xy 77.751283 -207.598906) (xy 77.893175 -207.588849) (xy 78.03541 -207.586836) (xy 78.17753 -207.592873)
			(xy 78.319081 -207.606941) (xy 78.45961 -207.628995) (xy 78.598665 -207.658964) (xy 78.735803 -207.696752)
			(xy 78.870583 -207.742238) (xy 79.002574 -207.795276) (xy 79.131353 -207.855697) (xy 79.256507 -207.923306)
			(xy 79.377635 -207.997888) (xy 79.494351 -208.079204) (xy 79.606279 -208.166992) (xy 79.713061 -208.260972)
			(xy 79.814355 -208.360842) (xy 79.909836 -208.466284) (xy 79.9992 -208.576958) (xy 80.082158 -208.692511)
			(xy 80.158447 -208.812572) (xy 80.227821 -208.936757) (xy 80.290058 -209.064668) (xy 80.344959 -209.195895)
			(xy 80.392347 -209.330018) (xy 80.432072 -209.466607) (xy 80.464005 -209.605225) (xy 80.488046 -209.745427)
			(xy 80.504115 -209.886765) (xy 80.512163 -210.028786) (xy 80.512666 -210.09991) (xy 80.512163 -210.171034)
			(xy 80.504115 -210.313055) (xy 80.488046 -210.454393) (xy 80.464005 -210.594595) (xy 80.432072 -210.733213)
			(xy 80.392347 -210.869802) (xy 80.344959 -211.003925) (xy 80.290058 -211.135152) (xy 80.227821 -211.263063)
			(xy 80.158447 -211.387248) (xy 80.082158 -211.507309) (xy 79.9992 -211.622862) (xy 79.909836 -211.733536)
			(xy 79.814355 -211.838978) (xy 79.713061 -211.938848) (xy 79.606279 -212.032828) (xy 79.494351 -212.120616)
			(xy 79.377635 -212.201932) (xy 79.256507 -212.276514) (xy 79.131353 -212.344123) (xy 79.002574 -212.404544)
			(xy 78.870583 -212.457582) (xy 78.735803 -212.503068) (xy 78.598665 -212.540856) (xy 78.45961 -212.570825)
			(xy 78.319081 -212.592879) (xy 78.17753 -212.606947) (xy 78.03541 -212.612984) (xy 77.893175 -212.610971)
			(xy 77.751283 -212.600914) (xy 77.610187 -212.582846) (xy 77.470338 -212.556825) (xy 77.332186 -212.522933)
			(xy 77.196173 -212.481279) (xy 77.062734 -212.431997) (xy 76.932297 -212.375245) (xy 76.80528 -212.311204)
			(xy 76.682089 -212.24008) (xy 76.56312 -212.1621) (xy 76.448752 -212.077514) (xy 76.339353 -211.986594)
			(xy 76.235274 -211.88963) (xy 76.136846 -211.786933) (xy 76.044387 -211.678831) (xy 75.958191 -211.565672)
			(xy 75.878536 -211.447818) (xy 75.805675 -211.325646) (xy 75.739844 -211.199548) (xy 75.681251 -211.069927)
			(xy 75.630086 -210.937199) (xy 75.586512 -210.801789) (xy 75.550668 -210.66413) (xy 75.52267 -210.524664)
			(xy 75.502607 -210.383838) (xy 75.490544 -210.242102) (xy 75.486519 -210.09991) (xy 0.509016 -210.09991)
			(xy 0.509016 -229.16007) (xy 39.818564 -229.16007) (xy 39.819058 -229.102661) (xy 39.826902 -228.988113)
			(xy 39.842544 -228.874366) (xy 39.865911 -228.761952) (xy 39.896896 -228.651394) (xy 39.935352 -228.543209)
			(xy 39.981101 -228.4379) (xy 40.03393 -228.335958) (xy 40.093592 -228.237859) (xy 40.159809 -228.14406)
			(xy 40.232272 -228.054998) (xy 40.310645 -227.971089) (xy 40.39456 -227.892723) (xy 40.483627 -227.820266)
			(xy 40.577431 -227.754056) (xy 40.675535 -227.694402) (xy 40.777481 -227.641581) (xy 40.882793 -227.595839)
			(xy 40.990981 -227.557391) (xy 41.101541 -227.526415) (xy 41.213957 -227.503056) (xy 41.327705 -227.487423)
			(xy 41.442254 -227.479588) (xy 41.557072 -227.479588) (xy 41.671621 -227.487423) (xy 41.785369 -227.503056)
			(xy 41.897785 -227.526415) (xy 42.008345 -227.557391) (xy 42.116533 -227.595839) (xy 42.221845 -227.641581)
			(xy 42.323791 -227.694402) (xy 42.421895 -227.754056) (xy 42.515699 -227.820266) (xy 42.604766 -227.892723)
			(xy 42.688681 -227.971089) (xy 42.767054 -228.054998) (xy 42.839517 -228.14406) (xy 42.905734 -228.237859)
			(xy 42.965396 -228.335958) (xy 43.018225 -228.4379) (xy 43.063974 -228.543209) (xy 43.10243 -228.651394)
			(xy 43.133415 -228.761952) (xy 43.156782 -228.874366) (xy 43.172424 -228.988113) (xy 43.180268 -229.102661)
			(xy 43.180762 -229.16007) (xy 43.180576 -229.193253) (xy 43.177909 -229.259567) (xy 43.175428 -229.292658)
			(xy 43.170272 -229.350942) (xy 43.152948 -229.466671) (xy 43.127616 -229.580914) (xy 43.094401 -229.693119)
			(xy 43.053462 -229.802742) (xy 43.004999 -229.909253) (xy 42.949245 -230.012135) (xy 42.886471 -230.110891)
			(xy 42.816981 -230.205042) (xy 42.741111 -230.294132) (xy 42.659229 -230.377729) (xy 42.571732 -230.45543)
			(xy 42.500813 -230.51008) (xy 93.154506 -230.51008) (xy 93.158522 -230.39381) (xy 93.170549 -230.278095)
			(xy 93.190531 -230.163485) (xy 93.218373 -230.050526) (xy 93.253942 -229.939758) (xy 93.297068 -229.831707)
			(xy 93.347545 -229.726889) (xy 93.405134 -229.625804) (xy 93.46956 -229.528932) (xy 93.540515 -229.436736)
			(xy 93.617662 -229.349655) (xy 93.700633 -229.268104) (xy 93.789033 -229.192472) (xy 93.88244 -229.123118)
			(xy 93.980409 -229.060375) (xy 94.082473 -229.004539) (xy 94.188147 -228.955878) (xy 94.296926 -228.914624)
			(xy 94.408291 -228.880973) (xy 94.521714 -228.855085) (xy 94.636651 -228.837084) (xy 94.752557 -228.827055)
			(xy 94.868879 -228.825047) (xy 94.985062 -228.831069) (xy 95.100553 -228.845092) (xy 95.214801 -228.86705)
			(xy 95.327262 -228.896837) (xy 95.4374 -228.934312) (xy 95.54469 -228.979297) (xy 95.648621 -229.031576)
			(xy 95.748697 -229.090901) (xy 95.844443 -229.156989) (xy 95.9354 -229.229525) (xy 96.021136 -229.308164)
			(xy 96.101243 -229.39253) (xy 96.175339 -229.482222) (xy 96.243069 -229.576812) (xy 96.304113 -229.67585)
			(xy 96.358178 -229.778863) (xy 96.405008 -229.88536) (xy 96.444379 -229.994835) (xy 96.476103 -230.106765)
			(xy 96.500029 -230.220617) (xy 96.516043 -230.335849) (xy 96.52407 -230.451911) (xy 96.524572 -230.51008)
			(xy 96.52407 -230.568249) (xy 96.516043 -230.684311) (xy 96.500029 -230.799543) (xy 96.476103 -230.913395)
			(xy 96.444379 -231.025325) (xy 96.405008 -231.1348) (xy 96.358178 -231.241297) (xy 96.304113 -231.34431)
			(xy 96.243069 -231.443348) (xy 96.175339 -231.537938) (xy 96.101243 -231.62763) (xy 96.021136 -231.711996)
			(xy 95.9354 -231.790635) (xy 95.844443 -231.863171) (xy 95.748697 -231.929259) (xy 95.648621 -231.988584)
			(xy 95.54469 -232.040863) (xy 95.4374 -232.085848) (xy 95.327262 -232.123323) (xy 95.214801 -232.15311)
			(xy 95.100553 -232.175068) (xy 94.985062 -232.189091) (xy 94.868879 -232.195113) (xy 94.752557 -232.193105)
			(xy 94.636651 -232.183076) (xy 94.521714 -232.165075) (xy 94.408291 -232.139187) (xy 94.296926 -232.105536)
			(xy 94.188147 -232.064282) (xy 94.082473 -232.015621) (xy 93.980409 -231.959785) (xy 93.88244 -231.897042)
			(xy 93.789033 -231.827688) (xy 93.700633 -231.752056) (xy 93.617662 -231.670505) (xy 93.540515 -231.583424)
			(xy 93.46956 -231.491228) (xy 93.405134 -231.394356) (xy 93.347545 -231.293271) (xy 93.297068 -231.188453)
			(xy 93.253942 -231.080402) (xy 93.218373 -230.969634) (xy 93.190531 -230.856675) (xy 93.170549 -230.742065)
			(xy 93.158522 -230.62635) (xy 93.154506 -230.51008) (xy 42.500813 -230.51008) (xy 42.479042 -230.526857)
			(xy 42.381609 -230.591665) (xy 42.279905 -230.64954) (xy 42.174422 -230.700202) (xy 42.065671 -230.743404)
			(xy 41.954179 -230.778939) (xy 41.840485 -230.806634) (xy 41.725141 -230.826354) (xy 41.608704 -230.838005)
			(xy 41.491739 -230.84153) (xy 41.374812 -230.836912) (xy 41.258489 -230.824173) (xy 41.143334 -230.803375)
			(xy 41.029905 -230.774618) (xy 40.91875 -230.738042) (xy 40.810407 -230.693825) (xy 40.705403 -230.642179)
			(xy 40.604244 -230.583356) (xy 40.507421 -230.51764) (xy 40.415403 -230.445349) (xy 40.328636 -230.366834)
			(xy 40.247539 -230.282474) (xy 40.172506 -230.192679) (xy 40.103899 -230.097883) (xy 40.042051 -229.998544)
			(xy 39.987262 -229.895145) (xy 39.939796 -229.788186) (xy 39.899884 -229.678185) (xy 39.86772 -229.565674)
			(xy 39.843457 -229.451199) (xy 39.827215 -229.335313) (xy 39.819072 -229.218579) (xy 39.818564 -229.16007)
			(xy 0.509016 -229.16007) (xy 0.509016 -242.26012) (xy 86.877404 -242.26012) (xy 86.881424 -242.069469)
			(xy 86.893478 -241.879156) (xy 86.913544 -241.689521) (xy 86.941587 -241.5009) (xy 86.977556 -241.31363)
			(xy 87.021388 -241.128042) (xy 87.073005 -240.944467) (xy 87.132315 -240.763231) (xy 87.199213 -240.584656)
			(xy 87.273579 -240.409061) (xy 87.355281 -240.236756) (xy 87.444175 -240.068049) (xy 87.540101 -239.903239)
			(xy 87.64289 -239.74262) (xy 87.752359 -239.586477) (xy 87.868313 -239.435088) (xy 87.990547 -239.288721)
			(xy 88.118841 -239.147637) (xy 88.252969 -239.012088) (xy 88.392693 -238.882313) (xy 88.537763 -238.758543)
			(xy 88.687921 -238.641) (xy 88.842902 -238.529891) (xy 89.002429 -238.425414) (xy 89.166218 -238.327755)
			(xy 89.333978 -238.237088) (xy 89.505412 -238.153574) (xy 89.680214 -238.077361) (xy 89.858073 -238.008585)
			(xy 90.038674 -237.947367) (xy 90.221694 -237.893818) (xy 90.40681 -237.848032) (xy 90.593691 -237.81009)
			(xy 90.782006 -237.780061) (xy 90.971419 -237.757996) (xy 91.161593 -237.743937) (xy 91.352192 -237.737907)
			(xy 91.542875 -237.739917) (xy 91.733304 -237.749964) (xy 91.92314 -237.76803) (xy 92.112046 -237.794083)
			(xy 92.299685 -237.828076) (xy 92.485725 -237.869949) (xy 92.669834 -237.919628) (xy 92.851685 -237.977024)
			(xy 93.030955 -238.042035) (xy 93.207325 -238.114546) (xy 93.380481 -238.194427) (xy 93.550116 -238.281537)
			(xy 93.715928 -238.375721) (xy 93.877622 -238.476812) (xy 94.03491 -238.584628) (xy 94.187513 -238.69898)
			(xy 94.335161 -238.819663) (xy 94.477589 -238.946464) (xy 94.614545 -239.079155) (xy 94.745786 -239.217503)
			(xy 94.871078 -239.36126) (xy 94.990198 -239.510171) (xy 95.102934 -239.663972) (xy 95.209087 -239.822388)
			(xy 95.308467 -239.985139) (xy 95.400897 -240.151934) (xy 95.486214 -240.322478) (xy 95.564266 -240.496466)
			(xy 95.634913 -240.673591) (xy 95.698031 -240.853536) (xy 95.753507 -241.035982) (xy 95.801242 -241.220605)
			(xy 95.841152 -241.407075) (xy 95.873165 -241.595063) (xy 95.897225 -241.784233) (xy 95.913288 -241.974249)
			(xy 95.921327 -242.164773) (xy 95.92183 -242.26012) (xy 95.921327 -242.355467) (xy 95.913288 -242.545991)
			(xy 95.897225 -242.736007) (xy 95.873165 -242.925177) (xy 95.841152 -243.113165) (xy 95.801242 -243.299635)
			(xy 95.753507 -243.484258) (xy 95.698031 -243.666704) (xy 95.634913 -243.846649) (xy 95.564266 -244.023774)
			(xy 95.486214 -244.197762) (xy 95.400897 -244.368306) (xy 95.308467 -244.535101) (xy 95.209087 -244.697852)
			(xy 95.102934 -244.856268) (xy 94.990198 -245.010069) (xy 94.871078 -245.15898) (xy 94.745786 -245.302737)
			(xy 94.614545 -245.441085) (xy 94.477589 -245.573776) (xy 94.335161 -245.700577) (xy 94.187513 -245.82126)
			(xy 94.03491 -245.935612) (xy 93.877622 -246.043428) (xy 93.715928 -246.144519) (xy 93.550116 -246.238703)
			(xy 93.380481 -246.325813) (xy 93.207325 -246.405694) (xy 93.030955 -246.478205) (xy 92.851685 -246.543216)
			(xy 92.669834 -246.600612) (xy 92.485725 -246.650291) (xy 92.299685 -246.692164) (xy 92.112046 -246.726157)
			(xy 91.92314 -246.75221) (xy 91.733304 -246.770276) (xy 91.542875 -246.780323) (xy 91.352192 -246.782333)
			(xy 91.161593 -246.776303) (xy 90.971419 -246.762244) (xy 90.782006 -246.740179) (xy 90.593691 -246.71015)
			(xy 90.40681 -246.672208) (xy 90.221694 -246.626422) (xy 90.038674 -246.572873) (xy 89.858073 -246.511655)
			(xy 89.680214 -246.442879) (xy 89.505412 -246.366666) (xy 89.333978 -246.283152) (xy 89.166218 -246.192485)
			(xy 89.002429 -246.094826) (xy 88.842902 -245.990349) (xy 88.687921 -245.87924) (xy 88.537763 -245.761697)
			(xy 88.392693 -245.637927) (xy 88.252969 -245.508152) (xy 88.118841 -245.372603) (xy 87.990547 -245.231519)
			(xy 87.868313 -245.085152) (xy 87.752359 -244.933763) (xy 87.64289 -244.77762) (xy 87.540101 -244.617001)
			(xy 87.444175 -244.452191) (xy 87.355281 -244.283484) (xy 87.273579 -244.111179) (xy 87.199213 -243.935584)
			(xy 87.132315 -243.757009) (xy 87.073005 -243.575773) (xy 87.021388 -243.392198) (xy 86.977556 -243.20661)
			(xy 86.941587 -243.01934) (xy 86.913544 -242.830719) (xy 86.893478 -242.641084) (xy 86.881424 -242.450771)
			(xy 86.877404 -242.26012) (xy 0.509016 -242.26012) (xy 0.509016 -250.020582) (xy 3.582162 -250.020582)
			(xy 3.582653 -249.963338) (xy 3.590754 -249.849137) (xy 3.606915 -249.735795) (xy 3.631055 -249.623881)
			(xy 3.663052 -249.513955) (xy 3.702747 -249.406568) (xy 3.74994 -249.302259) (xy 3.804394 -249.20155)
			(xy 3.865837 -249.104947) (xy 3.933962 -249.012932) (xy 4.008425 -248.925969) (xy 4.088855 -248.844491)
			(xy 4.174848 -248.768908) (xy 4.265973 -248.699599) (xy 4.361773 -248.636911) (xy 4.461769 -248.581157)
			(xy 4.565458 -248.532619) (xy 4.672322 -248.491538) (xy 4.781825 -248.458121) (xy 4.893417 -248.432535)
			(xy 5.006541 -248.414908) (xy 5.120627 -248.405329) (xy 5.235106 -248.403846) (xy 5.349402 -248.410467)
			(xy 5.462944 -248.425157) (xy 5.575162 -248.447844) (xy 5.685494 -248.478413) (xy 5.793386 -248.516712)
			(xy 5.898298 -248.562549) (xy 5.999704 -248.615693) (xy 6.097096 -248.675879) (xy 6.189986 -248.742805)
			(xy 6.277908 -248.816135) (xy 6.360421 -248.895501) (xy 6.437112 -248.980507) (xy 6.507597 -249.070726)
			(xy 6.571522 -249.165706) (xy 6.628567 -249.26497) (xy 6.678446 -249.368022) (xy 6.720909 -249.474344)
			(xy 6.755743 -249.583404) (xy 6.782773 -249.694656) (xy 6.801865 -249.807541) (xy 6.812922 -249.921494)
			(xy 6.815888 -250.035944) (xy 6.81075 -250.150316) (xy 6.797533 -250.264039) (xy 6.776303 -250.376542)
			(xy 6.747166 -250.48726) (xy 6.710269 -250.59564) (xy 6.665797 -250.701137) (xy 6.613971 -250.803224)
			(xy 6.555053 -250.901388) (xy 6.489337 -250.995137) (xy 6.453632 -251.039884) (xy 6.059424 -251.039884)
			(xy 6.020367 -251.072253) (xy 5.938107 -251.131626) (xy 5.895086 -251.158502) (xy 5.881509 -251.167452)
			(xy 5.858992 -251.190897) (xy 5.843109 -251.219259) (xy 5.834884 -251.250707) (xy 5.83438 -251.26696)
			(xy 5.83438 -251.50699) (xy 5.834126 -251.50699) (xy 5.779452 -251.529781) (xy 5.667407 -251.568246)
			(xy 5.552848 -251.598407) (xy 5.436387 -251.620101) (xy 5.318652 -251.633212) (xy 5.200272 -251.637669)
			(xy 5.081884 -251.633449) (xy 4.964122 -251.620575) (xy 4.847619 -251.599114) (xy 4.732999 -251.569183)
			(xy 4.620877 -251.530943) (xy 4.566158 -251.50826) (xy 4.565904 -251.50826) (xy 4.565904 -251.26823)
			(xy 4.56544 -251.25195) (xy 4.557181 -251.220454) (xy 4.541219 -251.192074) (xy 4.518594 -251.168658)
			(xy 4.504944 -251.159772) (xy 4.45885 -251.131059) (xy 4.370982 -251.067228) (xy 4.32943 -251.032264)
			(xy 3.937762 -251.032264) (xy 3.903919 -250.989342) (xy 3.841441 -250.89964) (xy 3.785164 -250.805923)
			(xy 3.735346 -250.708619) (xy 3.692214 -250.608172) (xy 3.655964 -250.505042) (xy 3.626762 -250.399698)
			(xy 3.604742 -250.292623) (xy 3.590005 -250.184306) (xy 3.582617 -250.07524) (xy 3.582162 -250.020582)
			(xy 0.509016 -250.020582) (xy 0.509016 -267.850739) (xy 3.584556 -267.850739) (xy 3.589879 -267.737285)
			(xy 3.603163 -267.624485) (xy 3.624341 -267.512897) (xy 3.653308 -267.403074) (xy 3.689922 -267.295558)
			(xy 3.734001 -267.190881) (xy 3.785327 -267.08956) (xy 3.843647 -266.992097) (xy 3.908672 -266.898974)
			(xy 3.980081 -266.81065) (xy 4.05752 -266.727563) (xy 4.140607 -266.650124) (xy 4.228931 -266.578715)
			(xy 4.322054 -266.51369) (xy 4.419517 -266.455369) (xy 4.520837 -266.404043) (xy 4.625514 -266.359963)
			(xy 4.73303 -266.323349) (xy 4.842854 -266.294382) (xy 4.954441 -266.273204) (xy 5.067241 -266.25992)
			(xy 5.180695 -266.254596) (xy 5.294243 -266.257258) (xy 5.407324 -266.267894) (xy 5.519377 -266.28645)
			(xy 5.629849 -266.312835) (xy 5.738194 -266.346919) (xy 5.843876 -266.388532) (xy 5.946371 -266.437469)
			(xy 6.045175 -266.493488) (xy 6.139797 -266.556312) (xy 6.229771 -266.625631) (xy 6.31465 -266.701101)
			(xy 6.394016 -266.78235) (xy 6.467475 -266.868975) (xy 6.534666 -266.960549) (xy 6.595255 -267.056618)
			(xy 6.648942 -267.156707) (xy 6.695463 -267.260322) (xy 6.734588 -267.36695) (xy 6.766122 -267.476064)
			(xy 6.78991 -267.587124) (xy 6.805834 -267.699582) (xy 6.813816 -267.81288) (xy 6.814312 -267.86967)
			(xy 6.813806 -267.92732) (xy 6.805599 -268.042327) (xy 6.789208 -268.156456) (xy 6.764716 -268.269125)
			(xy 6.73225 -268.37976) (xy 6.691973 -268.487796) (xy 6.644093 -268.592684) (xy 6.588851 -268.693889)
			(xy 6.52653 -268.790895) (xy 6.457448 -268.883208) (xy 6.381956 -268.970358) (xy 6.30044 -269.0519)
			(xy 6.213314 -269.127419) (xy 6.121023 -269.196531) (xy 6.024036 -269.258882) (xy 5.922848 -269.314155)
			(xy 5.817976 -269.362069) (xy 5.709952 -269.402379) (xy 5.599327 -269.434881) (xy 5.486666 -269.459407)
			(xy 5.372543 -269.475834) (xy 5.257538 -269.484078) (xy 5.199888 -269.484602) (xy 5.199634 -269.484602)
			(xy 5.199634 -269.484348) (xy 5.142844 -269.483856) (xy 5.029546 -269.475875) (xy 4.917088 -269.459951)
			(xy 4.806028 -269.436163) (xy 4.696914 -269.404629) (xy 4.590286 -269.365505) (xy 4.486671 -269.318984)
			(xy 4.386581 -269.265297) (xy 4.290512 -269.204708) (xy 4.198938 -269.137518) (xy 4.112313 -269.064058)
			(xy 4.031064 -268.984693) (xy 3.955594 -268.899814) (xy 3.886275 -268.80984) (xy 3.82345 -268.715218)
			(xy 3.767431 -268.616415) (xy 3.718493 -268.513919) (xy 3.67688 -268.408238) (xy 3.642796 -268.299893)
			(xy 3.616411 -268.189421) (xy 3.597855 -268.077368) (xy 3.587219 -267.964287) (xy 3.584556 -267.850739)
			(xy 0.509016 -267.850739) (xy 0.509016 -273.61007) (xy 39.818564 -273.61007) (xy 39.819058 -273.552661)
			(xy 39.826902 -273.438113) (xy 39.842544 -273.324366) (xy 39.865911 -273.211952) (xy 39.896896 -273.101394)
			(xy 39.935352 -272.993209) (xy 39.981101 -272.8879) (xy 40.03393 -272.785958) (xy 40.093592 -272.687859)
			(xy 40.159809 -272.59406) (xy 40.232272 -272.504998) (xy 40.310645 -272.421089) (xy 40.39456 -272.342723)
			(xy 40.483627 -272.270266) (xy 40.577431 -272.204056) (xy 40.675535 -272.144402) (xy 40.777481 -272.091581)
			(xy 40.882793 -272.045839) (xy 40.990981 -272.007391) (xy 41.101541 -271.976415) (xy 41.213957 -271.953056)
			(xy 41.327705 -271.937423) (xy 41.442254 -271.929588) (xy 41.557072 -271.929588) (xy 41.671621 -271.937423)
			(xy 41.785369 -271.953056) (xy 41.897785 -271.976415) (xy 42.008345 -272.007391) (xy 42.116533 -272.045839)
			(xy 42.221845 -272.091581) (xy 42.323791 -272.144402) (xy 42.421895 -272.204056) (xy 42.515699 -272.270266)
			(xy 42.604766 -272.342723) (xy 42.688681 -272.421089) (xy 42.767054 -272.504998) (xy 42.839517 -272.59406)
			(xy 42.905734 -272.687859) (xy 42.965396 -272.785958) (xy 43.018225 -272.8879) (xy 43.063974 -272.993209)
			(xy 43.10243 -273.101394) (xy 43.133415 -273.211952) (xy 43.156782 -273.324366) (xy 43.172424 -273.438113)
			(xy 43.180268 -273.552661) (xy 43.180762 -273.61007) (xy 43.180576 -273.643253) (xy 43.177909 -273.709567)
			(xy 43.175428 -273.742658) (xy 43.170272 -273.800942) (xy 43.152948 -273.916671) (xy 43.127616 -274.030914)
			(xy 43.094401 -274.143119) (xy 43.053462 -274.252742) (xy 43.004999 -274.359253) (xy 42.949245 -274.462135)
			(xy 42.886471 -274.560891) (xy 42.816981 -274.655042) (xy 42.741111 -274.744132) (xy 42.659229 -274.827729)
			(xy 42.571732 -274.90543) (xy 42.500813 -274.96008) (xy 93.154506 -274.96008) (xy 93.158522 -274.84381)
			(xy 93.170549 -274.728095) (xy 93.190531 -274.613485) (xy 93.218373 -274.500526) (xy 93.253942 -274.389758)
			(xy 93.297068 -274.281707) (xy 93.347545 -274.176889) (xy 93.405134 -274.075804) (xy 93.46956 -273.978932)
			(xy 93.540515 -273.886736) (xy 93.617662 -273.799655) (xy 93.700633 -273.718104) (xy 93.789033 -273.642472)
			(xy 93.88244 -273.573118) (xy 93.980409 -273.510375) (xy 94.082473 -273.454539) (xy 94.188147 -273.405878)
			(xy 94.296926 -273.364624) (xy 94.408291 -273.330973) (xy 94.521714 -273.305085) (xy 94.636651 -273.287084)
			(xy 94.752557 -273.277055) (xy 94.868879 -273.275047) (xy 94.985062 -273.281069) (xy 95.100553 -273.295092)
			(xy 95.214801 -273.31705) (xy 95.327262 -273.346837) (xy 95.4374 -273.384312) (xy 95.54469 -273.429297)
			(xy 95.648621 -273.481576) (xy 95.748697 -273.540901) (xy 95.844443 -273.606989) (xy 95.9354 -273.679525)
			(xy 96.021136 -273.758164) (xy 96.101243 -273.84253) (xy 96.175339 -273.932222) (xy 96.243069 -274.026812)
			(xy 96.304113 -274.12585) (xy 96.358178 -274.228863) (xy 96.405008 -274.33536) (xy 96.444379 -274.444835)
			(xy 96.476103 -274.556765) (xy 96.500029 -274.670617) (xy 96.516043 -274.785849) (xy 96.52407 -274.901911)
			(xy 96.524572 -274.96008) (xy 96.52407 -275.018249) (xy 96.516043 -275.134311) (xy 96.500029 -275.249543)
			(xy 96.476103 -275.363395) (xy 96.444379 -275.475325) (xy 96.405008 -275.5848) (xy 96.358178 -275.691297)
			(xy 96.304113 -275.79431) (xy 96.243069 -275.893348) (xy 96.175339 -275.987938) (xy 96.101243 -276.07763)
			(xy 96.021136 -276.161996) (xy 95.9354 -276.240635) (xy 95.844443 -276.313171) (xy 95.748697 -276.379259)
			(xy 95.648621 -276.438584) (xy 95.54469 -276.490863) (xy 95.4374 -276.535848) (xy 95.327262 -276.573323)
			(xy 95.214801 -276.60311) (xy 95.100553 -276.625068) (xy 94.985062 -276.639091) (xy 94.868879 -276.645113)
			(xy 94.752557 -276.643105) (xy 94.636651 -276.633076) (xy 94.521714 -276.615075) (xy 94.408291 -276.589187)
			(xy 94.296926 -276.555536) (xy 94.188147 -276.514282) (xy 94.082473 -276.465621) (xy 93.980409 -276.409785)
			(xy 93.88244 -276.347042) (xy 93.789033 -276.277688) (xy 93.700633 -276.202056) (xy 93.617662 -276.120505)
			(xy 93.540515 -276.033424) (xy 93.46956 -275.941228) (xy 93.405134 -275.844356) (xy 93.347545 -275.743271)
			(xy 93.297068 -275.638453) (xy 93.253942 -275.530402) (xy 93.218373 -275.419634) (xy 93.190531 -275.306675)
			(xy 93.170549 -275.192065) (xy 93.158522 -275.07635) (xy 93.154506 -274.96008) (xy 42.500813 -274.96008)
			(xy 42.479042 -274.976857) (xy 42.381609 -275.041665) (xy 42.279905 -275.09954) (xy 42.174422 -275.150202)
			(xy 42.065671 -275.193404) (xy 41.954179 -275.228939) (xy 41.840485 -275.256634) (xy 41.725141 -275.276354)
			(xy 41.608704 -275.288005) (xy 41.491739 -275.29153) (xy 41.374812 -275.286912) (xy 41.258489 -275.274173)
			(xy 41.143334 -275.253375) (xy 41.029905 -275.224618) (xy 40.91875 -275.188042) (xy 40.810407 -275.143825)
			(xy 40.705403 -275.092179) (xy 40.604244 -275.033356) (xy 40.507421 -274.96764) (xy 40.415403 -274.895349)
			(xy 40.328636 -274.816834) (xy 40.247539 -274.732474) (xy 40.172506 -274.642679) (xy 40.103899 -274.547883)
			(xy 40.042051 -274.448544) (xy 39.987262 -274.345145) (xy 39.939796 -274.238186) (xy 39.899884 -274.128185)
			(xy 39.86772 -274.015674) (xy 39.843457 -273.901199) (xy 39.827215 -273.785313) (xy 39.819072 -273.668579)
			(xy 39.818564 -273.61007) (xy 0.509016 -273.61007) (xy 0.509016 -286.709866) (xy 86.877404 -286.709866)
			(xy 86.881424 -286.519215) (xy 86.893478 -286.328902) (xy 86.913544 -286.139267) (xy 86.941587 -285.950646)
			(xy 86.977556 -285.763376) (xy 87.021388 -285.577788) (xy 87.073005 -285.394213) (xy 87.132315 -285.212977)
			(xy 87.199213 -285.034402) (xy 87.273579 -284.858807) (xy 87.355281 -284.686502) (xy 87.444175 -284.517795)
			(xy 87.540101 -284.352985) (xy 87.64289 -284.192366) (xy 87.752359 -284.036223) (xy 87.868313 -283.884834)
			(xy 87.990547 -283.738467) (xy 88.118841 -283.597383) (xy 88.252969 -283.461834) (xy 88.392693 -283.332059)
			(xy 88.537763 -283.208289) (xy 88.687921 -283.090746) (xy 88.842902 -282.979637) (xy 89.002429 -282.87516)
			(xy 89.166218 -282.777501) (xy 89.333978 -282.686834) (xy 89.505412 -282.60332) (xy 89.680214 -282.527107)
			(xy 89.858073 -282.458331) (xy 90.038674 -282.397113) (xy 90.221694 -282.343564) (xy 90.40681 -282.297778)
			(xy 90.593691 -282.259836) (xy 90.782006 -282.229807) (xy 90.971419 -282.207742) (xy 91.161593 -282.193683)
			(xy 91.352192 -282.187653) (xy 91.542875 -282.189663) (xy 91.733304 -282.19971) (xy 91.92314 -282.217776)
			(xy 92.112046 -282.243829) (xy 92.299685 -282.277822) (xy 92.485725 -282.319695) (xy 92.669834 -282.369374)
			(xy 92.851685 -282.42677) (xy 93.030955 -282.491781) (xy 93.207325 -282.564292) (xy 93.380481 -282.644173)
			(xy 93.550116 -282.731283) (xy 93.715928 -282.825467) (xy 93.877622 -282.926558) (xy 94.03491 -283.034374)
			(xy 94.187513 -283.148726) (xy 94.335161 -283.269409) (xy 94.477589 -283.39621) (xy 94.614545 -283.528901)
			(xy 94.745786 -283.667249) (xy 94.871078 -283.811006) (xy 94.990198 -283.959917) (xy 95.102934 -284.113718)
			(xy 95.209087 -284.272134) (xy 95.308467 -284.434885) (xy 95.400897 -284.60168) (xy 95.486214 -284.772224)
			(xy 95.564266 -284.946212) (xy 95.634913 -285.123337) (xy 95.698031 -285.303282) (xy 95.753507 -285.485728)
			(xy 95.801242 -285.670351) (xy 95.841152 -285.856821) (xy 95.873165 -286.044809) (xy 95.897225 -286.233979)
			(xy 95.913288 -286.423995) (xy 95.921327 -286.614519) (xy 95.92183 -286.709866) (xy 95.921327 -286.805213)
			(xy 95.913288 -286.995737) (xy 95.897225 -287.185753) (xy 95.873165 -287.374923) (xy 95.841152 -287.562911)
			(xy 95.801242 -287.749381) (xy 95.753507 -287.934004) (xy 95.698031 -288.11645) (xy 95.634913 -288.296395)
			(xy 95.564266 -288.47352) (xy 95.486214 -288.647508) (xy 95.400897 -288.818052) (xy 95.308467 -288.984847)
			(xy 95.209087 -289.147598) (xy 95.102934 -289.306014) (xy 94.990198 -289.459815) (xy 94.871078 -289.608726)
			(xy 94.745786 -289.752483) (xy 94.614545 -289.890831) (xy 94.477589 -290.023522) (xy 94.335161 -290.150323)
			(xy 94.187513 -290.271006) (xy 94.03491 -290.385358) (xy 93.877622 -290.493174) (xy 93.715928 -290.594265)
			(xy 93.550116 -290.688449) (xy 93.380481 -290.775559) (xy 93.207325 -290.85544) (xy 93.030955 -290.927951)
			(xy 92.851685 -290.992962) (xy 92.669834 -291.050358) (xy 92.485725 -291.100037) (xy 92.299685 -291.14191)
			(xy 92.112046 -291.175903) (xy 91.92314 -291.201956) (xy 91.733304 -291.220022) (xy 91.542875 -291.230069)
			(xy 91.352192 -291.232079) (xy 91.161593 -291.226049) (xy 90.971419 -291.21199) (xy 90.782006 -291.189925)
			(xy 90.593691 -291.159896) (xy 90.40681 -291.121954) (xy 90.221694 -291.076168) (xy 90.038674 -291.022619)
			(xy 89.858073 -290.961401) (xy 89.680214 -290.892625) (xy 89.505412 -290.816412) (xy 89.333978 -290.732898)
			(xy 89.166218 -290.642231) (xy 89.002429 -290.544572) (xy 88.842902 -290.440095) (xy 88.687921 -290.328986)
			(xy 88.537763 -290.211443) (xy 88.392693 -290.087673) (xy 88.252969 -289.957898) (xy 88.118841 -289.822349)
			(xy 87.990547 -289.681265) (xy 87.868313 -289.534898) (xy 87.752359 -289.383509) (xy 87.64289 -289.227366)
			(xy 87.540101 -289.066747) (xy 87.444175 -288.901937) (xy 87.355281 -288.73323) (xy 87.273579 -288.560925)
			(xy 87.199213 -288.38533) (xy 87.132315 -288.206755) (xy 87.073005 -288.025519) (xy 87.021388 -287.841944)
			(xy 86.977556 -287.656356) (xy 86.941587 -287.469086) (xy 86.913544 -287.280465) (xy 86.893478 -287.09083)
			(xy 86.881424 -286.900517) (xy 86.877404 -286.709866) (xy 0.509016 -286.709866) (xy 0.509016 -295.89984)
			(xy 14.086591 -295.89984) (xy 14.090616 -295.757648) (xy 14.102679 -295.615912) (xy 14.122742 -295.475086)
			(xy 14.15074 -295.33562) (xy 14.186584 -295.197961) (xy 14.230158 -295.062551) (xy 14.281323 -294.929823)
			(xy 14.339916 -294.800202) (xy 14.405747 -294.674104) (xy 14.478608 -294.551932) (xy 14.558263 -294.434078)
			(xy 14.644459 -294.320919) (xy 14.736918 -294.212817) (xy 14.835346 -294.11012) (xy 14.939425 -294.013156)
			(xy 15.048824 -293.922236) (xy 15.163192 -293.83765) (xy 15.282161 -293.75967) (xy 15.405352 -293.688546)
			(xy 15.532369 -293.624505) (xy 15.662806 -293.567753) (xy 15.796245 -293.518471) (xy 15.932258 -293.476817)
			(xy 16.07041 -293.442925) (xy 16.210259 -293.416904) (xy 16.351355 -293.398836) (xy 16.493247 -293.388779)
			(xy 16.635482 -293.386766) (xy 16.777602 -293.392803) (xy 16.919153 -293.406871) (xy 17.059682 -293.428925)
			(xy 17.198737 -293.458894) (xy 17.335875 -293.496682) (xy 17.470655 -293.542168) (xy 17.602646 -293.595206)
			(xy 17.731425 -293.655627) (xy 17.856579 -293.723236) (xy 17.977707 -293.797818) (xy 18.094423 -293.879134)
			(xy 18.206351 -293.966922) (xy 18.313133 -294.060902) (xy 18.414427 -294.160772) (xy 18.509908 -294.266214)
			(xy 18.599272 -294.376888) (xy 18.68223 -294.492441) (xy 18.758519 -294.612502) (xy 18.827893 -294.736687)
			(xy 18.89013 -294.864598) (xy 18.945031 -294.995825) (xy 18.992419 -295.129948) (xy 19.032144 -295.266537)
			(xy 19.064077 -295.405155) (xy 19.088118 -295.545357) (xy 19.104187 -295.686695) (xy 19.112235 -295.828716)
			(xy 19.112738 -295.89984) (xy 19.112235 -295.970964) (xy 19.104187 -296.112985) (xy 19.088118 -296.254323)
			(xy 19.064077 -296.394525) (xy 19.032144 -296.533143) (xy 18.992419 -296.669732) (xy 18.945031 -296.803855)
			(xy 18.89013 -296.935082) (xy 18.827893 -297.062993) (xy 18.758519 -297.187178) (xy 18.68223 -297.307239)
			(xy 18.599272 -297.422792) (xy 18.509908 -297.533466) (xy 18.414427 -297.638908) (xy 18.313133 -297.738778)
			(xy 18.206351 -297.832758) (xy 18.094423 -297.920546) (xy 17.977707 -298.001862) (xy 17.856579 -298.076444)
			(xy 17.731425 -298.144053) (xy 17.602646 -298.204474) (xy 17.470655 -298.257512) (xy 17.335875 -298.302998)
			(xy 17.198737 -298.340786) (xy 17.059682 -298.370755) (xy 16.919153 -298.392809) (xy 16.777602 -298.406877)
			(xy 16.635482 -298.412914) (xy 16.493247 -298.410901) (xy 16.351355 -298.400844) (xy 16.210259 -298.382776)
			(xy 16.07041 -298.356755) (xy 15.932258 -298.322863) (xy 15.796245 -298.281209) (xy 15.662806 -298.231927)
			(xy 15.532369 -298.175175) (xy 15.405352 -298.111134) (xy 15.282161 -298.04001) (xy 15.163192 -297.96203)
			(xy 15.048824 -297.877444) (xy 14.939425 -297.786524) (xy 14.835346 -297.68956) (xy 14.736918 -297.586863)
			(xy 14.644459 -297.478761) (xy 14.558263 -297.365602) (xy 14.478608 -297.247748) (xy 14.405747 -297.125576)
			(xy 14.339916 -296.999478) (xy 14.281323 -296.869857) (xy 14.230158 -296.737129) (xy 14.186584 -296.601719)
			(xy 14.15074 -296.46406) (xy 14.122742 -296.324594) (xy 14.102679 -296.183768) (xy 14.090616 -296.042032)
			(xy 14.086591 -295.89984) (xy 0.509016 -295.89984) (xy 0.509016 -318.06007) (xy 39.818564 -318.06007)
			(xy 39.819058 -318.002661) (xy 39.826902 -317.888113) (xy 39.842544 -317.774366) (xy 39.865911 -317.661952)
			(xy 39.896896 -317.551394) (xy 39.935352 -317.443209) (xy 39.981101 -317.3379) (xy 40.03393 -317.235958)
			(xy 40.093592 -317.137859) (xy 40.159809 -317.04406) (xy 40.232272 -316.954998) (xy 40.310645 -316.871089)
			(xy 40.39456 -316.792723) (xy 40.483627 -316.720266) (xy 40.577431 -316.654056) (xy 40.675535 -316.594402)
			(xy 40.777481 -316.541581) (xy 40.882793 -316.495839) (xy 40.990981 -316.457391) (xy 41.101541 -316.426415)
			(xy 41.213957 -316.403056) (xy 41.327705 -316.387423) (xy 41.442254 -316.379588) (xy 41.557072 -316.379588)
			(xy 41.671621 -316.387423) (xy 41.785369 -316.403056) (xy 41.897785 -316.426415) (xy 42.008345 -316.457391)
			(xy 42.116533 -316.495839) (xy 42.221845 -316.541581) (xy 42.323791 -316.594402) (xy 42.421895 -316.654056)
			(xy 42.515699 -316.720266) (xy 42.604766 -316.792723) (xy 42.688681 -316.871089) (xy 42.767054 -316.954998)
			(xy 42.839517 -317.04406) (xy 42.905734 -317.137859) (xy 42.965396 -317.235958) (xy 43.018225 -317.3379)
			(xy 43.063974 -317.443209) (xy 43.10243 -317.551394) (xy 43.133415 -317.661952) (xy 43.156782 -317.774366)
			(xy 43.172424 -317.888113) (xy 43.180268 -318.002661) (xy 43.180762 -318.06007) (xy 43.180576 -318.093253)
			(xy 43.177909 -318.159567) (xy 43.175428 -318.192658) (xy 43.170272 -318.250942) (xy 43.152948 -318.366671)
			(xy 43.127616 -318.480914) (xy 43.094401 -318.593119) (xy 43.053462 -318.702742) (xy 43.004999 -318.809253)
			(xy 42.949245 -318.912135) (xy 42.886471 -319.010891) (xy 42.816981 -319.105042) (xy 42.741111 -319.194132)
			(xy 42.659229 -319.277729) (xy 42.571732 -319.35543) (xy 42.500813 -319.41008) (xy 93.154506 -319.41008)
			(xy 93.158522 -319.29381) (xy 93.170549 -319.178095) (xy 93.190531 -319.063485) (xy 93.218373 -318.950526)
			(xy 93.253942 -318.839758) (xy 93.297068 -318.731707) (xy 93.347545 -318.626889) (xy 93.405134 -318.525804)
			(xy 93.46956 -318.428932) (xy 93.540515 -318.336736) (xy 93.617662 -318.249655) (xy 93.700633 -318.168104)
			(xy 93.789033 -318.092472) (xy 93.88244 -318.023118) (xy 93.980409 -317.960375) (xy 94.082473 -317.904539)
			(xy 94.188147 -317.855878) (xy 94.296926 -317.814624) (xy 94.408291 -317.780973) (xy 94.521714 -317.755085)
			(xy 94.636651 -317.737084) (xy 94.752557 -317.727055) (xy 94.868879 -317.725047) (xy 94.985062 -317.731069)
			(xy 95.100553 -317.745092) (xy 95.214801 -317.76705) (xy 95.327262 -317.796837) (xy 95.4374 -317.834312)
			(xy 95.54469 -317.879297) (xy 95.648621 -317.931576) (xy 95.748697 -317.990901) (xy 95.844443 -318.056989)
			(xy 95.9354 -318.129525) (xy 96.021136 -318.208164) (xy 96.101243 -318.29253) (xy 96.175339 -318.382222)
			(xy 96.243069 -318.476812) (xy 96.304113 -318.57585) (xy 96.358178 -318.678863) (xy 96.405008 -318.78536)
			(xy 96.444379 -318.894835) (xy 96.476103 -319.006765) (xy 96.500029 -319.120617) (xy 96.516043 -319.235849)
			(xy 96.52407 -319.351911) (xy 96.524572 -319.41008) (xy 96.52407 -319.468249) (xy 96.516043 -319.584311)
			(xy 96.500029 -319.699543) (xy 96.476103 -319.813395) (xy 96.444379 -319.925325) (xy 96.405008 -320.0348)
			(xy 96.358178 -320.141297) (xy 96.304113 -320.24431) (xy 96.243069 -320.343348) (xy 96.175339 -320.437938)
			(xy 96.101243 -320.52763) (xy 96.021136 -320.611996) (xy 95.9354 -320.690635) (xy 95.844443 -320.763171)
			(xy 95.748697 -320.829259) (xy 95.648621 -320.888584) (xy 95.54469 -320.940863) (xy 95.4374 -320.985848)
			(xy 95.327262 -321.023323) (xy 95.214801 -321.05311) (xy 95.100553 -321.075068) (xy 94.985062 -321.089091)
			(xy 94.868879 -321.095113) (xy 94.752557 -321.093105) (xy 94.636651 -321.083076) (xy 94.521714 -321.065075)
			(xy 94.408291 -321.039187) (xy 94.296926 -321.005536) (xy 94.188147 -320.964282) (xy 94.082473 -320.915621)
			(xy 93.980409 -320.859785) (xy 93.88244 -320.797042) (xy 93.789033 -320.727688) (xy 93.700633 -320.652056)
			(xy 93.617662 -320.570505) (xy 93.540515 -320.483424) (xy 93.46956 -320.391228) (xy 93.405134 -320.294356)
			(xy 93.347545 -320.193271) (xy 93.297068 -320.088453) (xy 93.253942 -319.980402) (xy 93.218373 -319.869634)
			(xy 93.190531 -319.756675) (xy 93.170549 -319.642065) (xy 93.158522 -319.52635) (xy 93.154506 -319.41008)
			(xy 42.500813 -319.41008) (xy 42.479042 -319.426857) (xy 42.381609 -319.491665) (xy 42.279905 -319.54954)
			(xy 42.174422 -319.600202) (xy 42.065671 -319.643404) (xy 41.954179 -319.678939) (xy 41.840485 -319.706634)
			(xy 41.725141 -319.726354) (xy 41.608704 -319.738005) (xy 41.491739 -319.74153) (xy 41.374812 -319.736912)
			(xy 41.258489 -319.724173) (xy 41.143334 -319.703375) (xy 41.029905 -319.674618) (xy 40.91875 -319.638042)
			(xy 40.810407 -319.593825) (xy 40.705403 -319.542179) (xy 40.604244 -319.483356) (xy 40.507421 -319.41764)
			(xy 40.415403 -319.345349) (xy 40.328636 -319.266834) (xy 40.247539 -319.182474) (xy 40.172506 -319.092679)
			(xy 40.103899 -318.997883) (xy 40.042051 -318.898544) (xy 39.987262 -318.795145) (xy 39.939796 -318.688186)
			(xy 39.899884 -318.578185) (xy 39.86772 -318.465674) (xy 39.843457 -318.351199) (xy 39.827215 -318.235313)
			(xy 39.819072 -318.118579) (xy 39.818564 -318.06007) (xy 0.509016 -318.06007) (xy 0.509016 -331.16012)
			(xy 86.877404 -331.16012) (xy 86.881424 -330.969469) (xy 86.893478 -330.779156) (xy 86.913544 -330.589521)
			(xy 86.941587 -330.4009) (xy 86.977556 -330.21363) (xy 87.021388 -330.028042) (xy 87.073005 -329.844467)
			(xy 87.132315 -329.663231) (xy 87.199213 -329.484656) (xy 87.273579 -329.309061) (xy 87.355281 -329.136756)
			(xy 87.444175 -328.968049) (xy 87.540101 -328.803239) (xy 87.64289 -328.64262) (xy 87.752359 -328.486477)
			(xy 87.868313 -328.335088) (xy 87.990547 -328.188721) (xy 88.118841 -328.047637) (xy 88.252969 -327.912088)
			(xy 88.392693 -327.782313) (xy 88.537763 -327.658543) (xy 88.687921 -327.541) (xy 88.842902 -327.429891)
			(xy 89.002429 -327.325414) (xy 89.166218 -327.227755) (xy 89.333978 -327.137088) (xy 89.505412 -327.053574)
			(xy 89.680214 -326.977361) (xy 89.858073 -326.908585) (xy 90.038674 -326.847367) (xy 90.221694 -326.793818)
			(xy 90.40681 -326.748032) (xy 90.593691 -326.71009) (xy 90.782006 -326.680061) (xy 90.971419 -326.657996)
			(xy 91.161593 -326.643937) (xy 91.352192 -326.637907) (xy 91.542875 -326.639917) (xy 91.733304 -326.649964)
			(xy 91.92314 -326.66803) (xy 92.112046 -326.694083) (xy 92.299685 -326.728076) (xy 92.485725 -326.769949)
			(xy 92.669834 -326.819628) (xy 92.851685 -326.877024) (xy 93.030955 -326.942035) (xy 93.207325 -327.014546)
			(xy 93.380481 -327.094427) (xy 93.550116 -327.181537) (xy 93.715928 -327.275721) (xy 93.877622 -327.376812)
			(xy 94.03491 -327.484628) (xy 94.187513 -327.59898) (xy 94.335161 -327.719663) (xy 94.477589 -327.846464)
			(xy 94.614545 -327.979155) (xy 94.745786 -328.117503) (xy 94.871078 -328.26126) (xy 94.990198 -328.410171)
			(xy 95.102934 -328.563972) (xy 95.209087 -328.722388) (xy 95.308467 -328.885139) (xy 95.400897 -329.051934)
			(xy 95.486214 -329.222478) (xy 95.564266 -329.396466) (xy 95.634913 -329.573591) (xy 95.698031 -329.753536)
			(xy 95.753507 -329.935982) (xy 95.801242 -330.120605) (xy 95.841152 -330.307075) (xy 95.873165 -330.495063)
			(xy 95.897225 -330.684233) (xy 95.913288 -330.874249) (xy 95.921327 -331.064773) (xy 95.92183 -331.16012)
			(xy 95.921327 -331.255467) (xy 95.913288 -331.445991) (xy 95.897225 -331.636007) (xy 95.873165 -331.825177)
			(xy 95.841152 -332.013165) (xy 95.801242 -332.199635) (xy 95.753507 -332.384258) (xy 95.698031 -332.566704)
			(xy 95.634913 -332.746649) (xy 95.564266 -332.923774) (xy 95.486214 -333.097762) (xy 95.400897 -333.268306)
			(xy 95.308467 -333.435101) (xy 95.209087 -333.597852) (xy 95.102934 -333.756268) (xy 94.990198 -333.910069)
			(xy 94.871078 -334.05898) (xy 94.745786 -334.202737) (xy 94.614545 -334.341085) (xy 94.477589 -334.473776)
			(xy 94.335161 -334.600577) (xy 94.187513 -334.72126) (xy 94.03491 -334.835612) (xy 93.877622 -334.943428)
			(xy 93.715928 -335.044519) (xy 93.550116 -335.138703) (xy 93.380481 -335.225813) (xy 93.207325 -335.305694)
			(xy 93.030955 -335.378205) (xy 92.851685 -335.443216) (xy 92.669834 -335.500612) (xy 92.485725 -335.550291)
			(xy 92.299685 -335.592164) (xy 92.112046 -335.626157) (xy 91.92314 -335.65221) (xy 91.733304 -335.670276)
			(xy 91.542875 -335.680323) (xy 91.352192 -335.682333) (xy 91.161593 -335.676303) (xy 90.971419 -335.662244)
			(xy 90.782006 -335.640179) (xy 90.593691 -335.61015) (xy 90.40681 -335.572208) (xy 90.221694 -335.526422)
			(xy 90.038674 -335.472873) (xy 89.858073 -335.411655) (xy 89.680214 -335.342879) (xy 89.505412 -335.266666)
			(xy 89.333978 -335.183152) (xy 89.166218 -335.092485) (xy 89.002429 -334.994826) (xy 88.842902 -334.890349)
			(xy 88.687921 -334.77924) (xy 88.537763 -334.661697) (xy 88.392693 -334.537927) (xy 88.252969 -334.408152)
			(xy 88.118841 -334.272603) (xy 87.990547 -334.131519) (xy 87.868313 -333.985152) (xy 87.752359 -333.833763)
			(xy 87.64289 -333.67762) (xy 87.540101 -333.517001) (xy 87.444175 -333.352191) (xy 87.355281 -333.183484)
			(xy 87.273579 -333.011179) (xy 87.199213 -332.835584) (xy 87.132315 -332.657009) (xy 87.073005 -332.475773)
			(xy 87.021388 -332.292198) (xy 86.977556 -332.10661) (xy 86.941587 -331.91934) (xy 86.913544 -331.730719)
			(xy 86.893478 -331.541084) (xy 86.881424 -331.350771) (xy 86.877404 -331.16012) (xy 0.509016 -331.16012)
			(xy 0.509016 -341.019892) (xy 3.583178 -341.019892) (xy 3.583676 -340.962648) (xy 3.591778 -340.848447)
			(xy 3.607939 -340.735105) (xy 3.632078 -340.623191) (xy 3.664075 -340.513266) (xy 3.70377 -340.405879)
			(xy 3.750962 -340.30157) (xy 3.805417 -340.200862) (xy 3.86686 -340.104258) (xy 3.934984 -340.012244)
			(xy 4.009448 -339.92528) (xy 4.089877 -339.843803) (xy 4.17587 -339.76822) (xy 4.266995 -339.698911)
			(xy 4.362795 -339.636223) (xy 4.462791 -339.58047) (xy 4.56648 -339.531931) (xy 4.673344 -339.49085)
			(xy 4.782847 -339.457433) (xy 4.894439 -339.431847) (xy 5.007562 -339.414221) (xy 5.121648 -339.404642)
			(xy 5.236127 -339.40316) (xy 5.350423 -339.40978) (xy 5.463965 -339.42447) (xy 5.576183 -339.447157)
			(xy 5.686514 -339.477727) (xy 5.794406 -339.516026) (xy 5.899318 -339.561862) (xy 6.000724 -339.615007)
			(xy 6.098116 -339.675192) (xy 6.191005 -339.742118) (xy 6.278927 -339.815448) (xy 6.36144 -339.894815)
			(xy 6.438131 -339.97982) (xy 6.508616 -340.070039) (xy 6.57254 -340.165019) (xy 6.629585 -340.264283)
			(xy 6.679464 -340.367335) (xy 6.721926 -340.473657) (xy 6.75676 -340.582717) (xy 6.78379 -340.693968)
			(xy 6.802882 -340.806853) (xy 6.813939 -340.920806) (xy 6.816905 -341.035256) (xy 6.811767 -341.149628)
			(xy 6.8001 -341.250016) (xy 75.486519 -341.250016) (xy 75.490544 -341.107824) (xy 75.502607 -340.966088)
			(xy 75.52267 -340.825262) (xy 75.550668 -340.685796) (xy 75.586512 -340.548137) (xy 75.630086 -340.412727)
			(xy 75.681251 -340.279999) (xy 75.739844 -340.150378) (xy 75.805675 -340.02428) (xy 75.878536 -339.902108)
			(xy 75.958191 -339.784254) (xy 76.044387 -339.671095) (xy 76.136846 -339.562993) (xy 76.235274 -339.460296)
			(xy 76.339353 -339.363332) (xy 76.448752 -339.272412) (xy 76.56312 -339.187826) (xy 76.682089 -339.109846)
			(xy 76.80528 -339.038722) (xy 76.932297 -338.974681) (xy 77.062734 -338.917929) (xy 77.196173 -338.868647)
			(xy 77.332186 -338.826993) (xy 77.470338 -338.793101) (xy 77.610187 -338.76708) (xy 77.751283 -338.749012)
			(xy 77.893175 -338.738955) (xy 78.03541 -338.736942) (xy 78.17753 -338.742979) (xy 78.319081 -338.757047)
			(xy 78.45961 -338.779101) (xy 78.598665 -338.80907) (xy 78.735803 -338.846858) (xy 78.870583 -338.892344)
			(xy 79.002574 -338.945382) (xy 79.131353 -339.005803) (xy 79.256507 -339.073412) (xy 79.377635 -339.147994)
			(xy 79.494351 -339.22931) (xy 79.606279 -339.317098) (xy 79.713061 -339.411078) (xy 79.814355 -339.510948)
			(xy 79.909836 -339.61639) (xy 79.9992 -339.727064) (xy 80.082158 -339.842617) (xy 80.158447 -339.962678)
			(xy 80.227821 -340.086863) (xy 80.290058 -340.214774) (xy 80.344959 -340.346001) (xy 80.392347 -340.480124)
			(xy 80.432072 -340.616713) (xy 80.464005 -340.755331) (xy 80.488046 -340.895533) (xy 80.504115 -341.036871)
			(xy 80.512163 -341.178892) (xy 80.512666 -341.250016) (xy 80.512163 -341.32114) (xy 80.504115 -341.463161)
			(xy 80.488046 -341.604499) (xy 80.464005 -341.744701) (xy 80.432072 -341.883319) (xy 80.392347 -342.019908)
			(xy 80.344959 -342.154031) (xy 80.290058 -342.285258) (xy 80.227821 -342.413169) (xy 80.158447 -342.537354)
			(xy 80.082158 -342.657415) (xy 79.9992 -342.772968) (xy 79.909836 -342.883642) (xy 79.814355 -342.989084)
			(xy 79.713061 -343.088954) (xy 79.606279 -343.182934) (xy 79.494351 -343.270722) (xy 79.377635 -343.352038)
			(xy 79.256507 -343.42662) (xy 79.131353 -343.494229) (xy 79.002574 -343.55465) (xy 78.870583 -343.607688)
			(xy 78.735803 -343.653174) (xy 78.598665 -343.690962) (xy 78.45961 -343.720931) (xy 78.319081 -343.742985)
			(xy 78.17753 -343.757053) (xy 78.03541 -343.76309) (xy 77.893175 -343.761077) (xy 77.751283 -343.75102)
			(xy 77.610187 -343.732952) (xy 77.470338 -343.706931) (xy 77.332186 -343.673039) (xy 77.196173 -343.631385)
			(xy 77.062734 -343.582103) (xy 76.932297 -343.525351) (xy 76.80528 -343.46131) (xy 76.682089 -343.390186)
			(xy 76.56312 -343.312206) (xy 76.448752 -343.22762) (xy 76.339353 -343.1367) (xy 76.235274 -343.039736)
			(xy 76.136846 -342.937039) (xy 76.044387 -342.828937) (xy 75.958191 -342.715778) (xy 75.878536 -342.597924)
			(xy 75.805675 -342.475752) (xy 75.739844 -342.349654) (xy 75.681251 -342.220033) (xy 75.630086 -342.087305)
			(xy 75.586512 -341.951895) (xy 75.550668 -341.814236) (xy 75.52267 -341.67477) (xy 75.502607 -341.533944)
			(xy 75.490544 -341.392208) (xy 75.486519 -341.250016) (xy 6.8001 -341.250016) (xy 6.79855 -341.263351)
			(xy 6.77732 -341.375853) (xy 6.748183 -341.486571) (xy 6.711286 -341.594951) (xy 6.666813 -341.700448)
			(xy 6.614988 -341.802534) (xy 6.556069 -341.900698) (xy 6.490353 -341.994448) (xy 6.454648 -342.039194)
			(xy 6.454394 -342.039448) (xy 6.060186 -342.039448) (xy 6.021179 -342.071737) (xy 5.939048 -342.130983)
			(xy 5.896102 -342.157812) (xy 5.882524 -342.166761) (xy 5.860006 -342.190206) (xy 5.844123 -342.218568)
			(xy 5.8359 -342.250017) (xy 5.835396 -342.26627) (xy 5.835396 -342.5063) (xy 5.835142 -342.5063)
			(xy 5.780469 -342.529093) (xy 5.668424 -342.567559) (xy 5.553864 -342.597719) (xy 5.437404 -342.619413)
			(xy 5.319668 -342.632524) (xy 5.201288 -342.636981) (xy 5.0829 -342.632761) (xy 4.965138 -342.619886)
			(xy 4.848635 -342.598425) (xy 4.734015 -342.568494) (xy 4.621893 -342.530253) (xy 4.567174 -342.50757)
			(xy 4.56692 -342.50757) (xy 4.56692 -342.26754) (xy 4.566441 -342.251261) (xy 4.558186 -342.219766)
			(xy 4.542229 -342.191387) (xy 4.519608 -342.167969) (xy 4.50596 -342.159082) (xy 4.459776 -342.130343)
			(xy 4.371783 -342.066378) (xy 4.330192 -342.03132) (xy 3.938778 -342.03132) (xy 3.904941 -341.988409)
			(xy 3.842477 -341.898728) (xy 3.78621 -341.805035) (xy 3.736399 -341.707756) (xy 3.69327 -341.607335)
			(xy 3.657021 -341.504231) (xy 3.627816 -341.398915) (xy 3.60579 -341.291867) (xy 3.591042 -341.183577)
			(xy 3.583641 -341.074537) (xy 3.583178 -341.019892) (xy 0.509016 -341.019892) (xy 0.509016 -362.51007)
			(xy 39.818564 -362.51007) (xy 39.819058 -362.452661) (xy 39.826902 -362.338113) (xy 39.842544 -362.224366)
			(xy 39.865911 -362.111952) (xy 39.896896 -362.001394) (xy 39.935352 -361.893209) (xy 39.981101 -361.7879)
			(xy 40.03393 -361.685958) (xy 40.093592 -361.587859) (xy 40.159809 -361.49406) (xy 40.232272 -361.404998)
			(xy 40.310645 -361.321089) (xy 40.39456 -361.242723) (xy 40.483627 -361.170266) (xy 40.577431 -361.104056)
			(xy 40.675535 -361.044402) (xy 40.777481 -360.991581) (xy 40.882793 -360.945839) (xy 40.990981 -360.907391)
			(xy 41.101541 -360.876415) (xy 41.213957 -360.853056) (xy 41.327705 -360.837423) (xy 41.442254 -360.829588)
			(xy 41.557072 -360.829588) (xy 41.671621 -360.837423) (xy 41.785369 -360.853056) (xy 41.897785 -360.876415)
			(xy 42.008345 -360.907391) (xy 42.116533 -360.945839) (xy 42.221845 -360.991581) (xy 42.323791 -361.044402)
			(xy 42.421895 -361.104056) (xy 42.515699 -361.170266) (xy 42.604766 -361.242723) (xy 42.688681 -361.321089)
			(xy 42.767054 -361.404998) (xy 42.839517 -361.49406) (xy 42.905734 -361.587859) (xy 42.965396 -361.685958)
			(xy 43.018225 -361.7879) (xy 43.063974 -361.893209) (xy 43.10243 -362.001394) (xy 43.133415 -362.111952)
			(xy 43.156782 -362.224366) (xy 43.172424 -362.338113) (xy 43.180268 -362.452661) (xy 43.180762 -362.51007)
			(xy 43.180576 -362.543253) (xy 43.177909 -362.609567) (xy 43.175428 -362.642658) (xy 43.170272 -362.700942)
			(xy 43.152948 -362.816671) (xy 43.127616 -362.930914) (xy 43.094401 -363.043119) (xy 43.053462 -363.152742)
			(xy 43.004999 -363.259253) (xy 42.949245 -363.362135) (xy 42.886471 -363.460891) (xy 42.816981 -363.555042)
			(xy 42.741111 -363.644132) (xy 42.659229 -363.727729) (xy 42.571732 -363.80543) (xy 42.500813 -363.86008)
			(xy 93.154506 -363.86008) (xy 93.158522 -363.74381) (xy 93.170549 -363.628095) (xy 93.190531 -363.513485)
			(xy 93.218373 -363.400526) (xy 93.253942 -363.289758) (xy 93.297068 -363.181707) (xy 93.347545 -363.076889)
			(xy 93.405134 -362.975804) (xy 93.46956 -362.878932) (xy 93.540515 -362.786736) (xy 93.617662 -362.699655)
			(xy 93.700633 -362.618104) (xy 93.789033 -362.542472) (xy 93.88244 -362.473118) (xy 93.980409 -362.410375)
			(xy 94.082473 -362.354539) (xy 94.188147 -362.305878) (xy 94.296926 -362.264624) (xy 94.408291 -362.230973)
			(xy 94.521714 -362.205085) (xy 94.636651 -362.187084) (xy 94.752557 -362.177055) (xy 94.868879 -362.175047)
			(xy 94.985062 -362.181069) (xy 95.100553 -362.195092) (xy 95.214801 -362.21705) (xy 95.327262 -362.246837)
			(xy 95.4374 -362.284312) (xy 95.54469 -362.329297) (xy 95.648621 -362.381576) (xy 95.748697 -362.440901)
			(xy 95.844443 -362.506989) (xy 95.9354 -362.579525) (xy 96.021136 -362.658164) (xy 96.101243 -362.74253)
			(xy 96.175339 -362.832222) (xy 96.243069 -362.926812) (xy 96.304113 -363.02585) (xy 96.358178 -363.128863)
			(xy 96.405008 -363.23536) (xy 96.444379 -363.344835) (xy 96.476103 -363.456765) (xy 96.500029 -363.570617)
			(xy 96.516043 -363.685849) (xy 96.52407 -363.801911) (xy 96.524572 -363.86008) (xy 96.52407 -363.918249)
			(xy 96.516043 -364.034311) (xy 96.500029 -364.149543) (xy 96.476103 -364.263395) (xy 96.444379 -364.375325)
			(xy 96.405008 -364.4848) (xy 96.358178 -364.591297) (xy 96.304113 -364.69431) (xy 96.243069 -364.793348)
			(xy 96.175339 -364.887938) (xy 96.101243 -364.97763) (xy 96.021136 -365.061996) (xy 95.9354 -365.140635)
			(xy 95.844443 -365.213171) (xy 95.748697 -365.279259) (xy 95.648621 -365.338584) (xy 95.54469 -365.390863)
			(xy 95.4374 -365.435848) (xy 95.327262 -365.473323) (xy 95.214801 -365.50311) (xy 95.100553 -365.525068)
			(xy 94.985062 -365.539091) (xy 94.868879 -365.545113) (xy 94.752557 -365.543105) (xy 94.636651 -365.533076)
			(xy 94.521714 -365.515075) (xy 94.408291 -365.489187) (xy 94.296926 -365.455536) (xy 94.188147 -365.414282)
			(xy 94.082473 -365.365621) (xy 93.980409 -365.309785) (xy 93.88244 -365.247042) (xy 93.789033 -365.177688)
			(xy 93.700633 -365.102056) (xy 93.617662 -365.020505) (xy 93.540515 -364.933424) (xy 93.46956 -364.841228)
			(xy 93.405134 -364.744356) (xy 93.347545 -364.643271) (xy 93.297068 -364.538453) (xy 93.253942 -364.430402)
			(xy 93.218373 -364.319634) (xy 93.190531 -364.206675) (xy 93.170549 -364.092065) (xy 93.158522 -363.97635)
			(xy 93.154506 -363.86008) (xy 42.500813 -363.86008) (xy 42.479042 -363.876857) (xy 42.381609 -363.941665)
			(xy 42.279905 -363.99954) (xy 42.174422 -364.050202) (xy 42.065671 -364.093404) (xy 41.954179 -364.128939)
			(xy 41.840485 -364.156634) (xy 41.725141 -364.176354) (xy 41.608704 -364.188005) (xy 41.491739 -364.19153)
			(xy 41.374812 -364.186912) (xy 41.258489 -364.174173) (xy 41.143334 -364.153375) (xy 41.029905 -364.124618)
			(xy 40.91875 -364.088042) (xy 40.810407 -364.043825) (xy 40.705403 -363.992179) (xy 40.604244 -363.933356)
			(xy 40.507421 -363.86764) (xy 40.415403 -363.795349) (xy 40.328636 -363.716834) (xy 40.247539 -363.632474)
			(xy 40.172506 -363.542679) (xy 40.103899 -363.447883) (xy 40.042051 -363.348544) (xy 39.987262 -363.245145)
			(xy 39.939796 -363.138186) (xy 39.899884 -363.028185) (xy 39.86772 -362.915674) (xy 39.843457 -362.801199)
			(xy 39.827215 -362.685313) (xy 39.819072 -362.568579) (xy 39.818564 -362.51007) (xy 0.509016 -362.51007)
			(xy 0.509016 -375.61012) (xy 86.877404 -375.61012) (xy 86.881424 -375.419469) (xy 86.893478 -375.229156)
			(xy 86.913544 -375.039521) (xy 86.941587 -374.8509) (xy 86.977556 -374.66363) (xy 87.021388 -374.478042)
			(xy 87.073005 -374.294467) (xy 87.132315 -374.113231) (xy 87.199213 -373.934656) (xy 87.273579 -373.759061)
			(xy 87.355281 -373.586756) (xy 87.444175 -373.418049) (xy 87.540101 -373.253239) (xy 87.64289 -373.09262)
			(xy 87.752359 -372.936477) (xy 87.868313 -372.785088) (xy 87.990547 -372.638721) (xy 88.118841 -372.497637)
			(xy 88.252969 -372.362088) (xy 88.392693 -372.232313) (xy 88.537763 -372.108543) (xy 88.687921 -371.991)
			(xy 88.842902 -371.879891) (xy 89.002429 -371.775414) (xy 89.166218 -371.677755) (xy 89.333978 -371.587088)
			(xy 89.505412 -371.503574) (xy 89.680214 -371.427361) (xy 89.858073 -371.358585) (xy 90.038674 -371.297367)
			(xy 90.221694 -371.243818) (xy 90.40681 -371.198032) (xy 90.593691 -371.16009) (xy 90.782006 -371.130061)
			(xy 90.971419 -371.107996) (xy 91.161593 -371.093937) (xy 91.352192 -371.087907) (xy 91.542875 -371.089917)
			(xy 91.733304 -371.099964) (xy 91.92314 -371.11803) (xy 92.112046 -371.144083) (xy 92.299685 -371.178076)
			(xy 92.485725 -371.219949) (xy 92.669834 -371.269628) (xy 92.851685 -371.327024) (xy 93.030955 -371.392035)
			(xy 93.207325 -371.464546) (xy 93.380481 -371.544427) (xy 93.550116 -371.631537) (xy 93.715928 -371.725721)
			(xy 93.877622 -371.826812) (xy 94.03491 -371.934628) (xy 94.187513 -372.04898) (xy 94.335161 -372.169663)
			(xy 94.477589 -372.296464) (xy 94.614545 -372.429155) (xy 94.745786 -372.567503) (xy 94.871078 -372.71126)
			(xy 94.990198 -372.860171) (xy 95.102934 -373.013972) (xy 95.209087 -373.172388) (xy 95.308467 -373.335139)
			(xy 95.400897 -373.501934) (xy 95.486214 -373.672478) (xy 95.564266 -373.846466) (xy 95.634913 -374.023591)
			(xy 95.698031 -374.203536) (xy 95.753507 -374.385982) (xy 95.801242 -374.570605) (xy 95.841152 -374.757075)
			(xy 95.873165 -374.945063) (xy 95.897225 -375.134233) (xy 95.913288 -375.324249) (xy 95.921327 -375.514773)
			(xy 95.92183 -375.61012) (xy 95.921327 -375.705467) (xy 95.913288 -375.895991) (xy 95.897225 -376.086007)
			(xy 95.873165 -376.275177) (xy 95.841152 -376.463165) (xy 95.801242 -376.649635) (xy 95.753507 -376.834258)
			(xy 95.698031 -377.016704) (xy 95.634913 -377.196649) (xy 95.564266 -377.373774) (xy 95.486214 -377.547762)
			(xy 95.400897 -377.718306) (xy 95.308467 -377.885101) (xy 95.209087 -378.047852) (xy 95.102934 -378.206268)
			(xy 94.990198 -378.360069) (xy 94.871078 -378.50898) (xy 94.745786 -378.652737) (xy 94.614545 -378.791085)
			(xy 94.477589 -378.923776) (xy 94.335161 -379.050577) (xy 94.187513 -379.17126) (xy 94.03491 -379.285612)
			(xy 93.877622 -379.393428) (xy 93.715928 -379.494519) (xy 93.550116 -379.588703) (xy 93.380481 -379.675813)
			(xy 93.207325 -379.755694) (xy 93.030955 -379.828205) (xy 92.851685 -379.893216) (xy 92.669834 -379.950612)
			(xy 92.485725 -380.000291) (xy 92.299685 -380.042164) (xy 92.112046 -380.076157) (xy 91.92314 -380.10221)
			(xy 91.733304 -380.120276) (xy 91.542875 -380.130323) (xy 91.352192 -380.132333) (xy 91.161593 -380.126303)
			(xy 90.971419 -380.112244) (xy 90.782006 -380.090179) (xy 90.593691 -380.06015) (xy 90.40681 -380.022208)
			(xy 90.221694 -379.976422) (xy 90.038674 -379.922873) (xy 89.858073 -379.861655) (xy 89.680214 -379.792879)
			(xy 89.505412 -379.716666) (xy 89.333978 -379.633152) (xy 89.166218 -379.542485) (xy 89.002429 -379.444826)
			(xy 88.842902 -379.340349) (xy 88.687921 -379.22924) (xy 88.537763 -379.111697) (xy 88.392693 -378.987927)
			(xy 88.252969 -378.858152) (xy 88.118841 -378.722603) (xy 87.990547 -378.581519) (xy 87.868313 -378.435152)
			(xy 87.752359 -378.283763) (xy 87.64289 -378.12762) (xy 87.540101 -377.967001) (xy 87.444175 -377.802191)
			(xy 87.355281 -377.633484) (xy 87.273579 -377.461179) (xy 87.199213 -377.285584) (xy 87.132315 -377.107009)
			(xy 87.073005 -376.925773) (xy 87.021388 -376.742198) (xy 86.977556 -376.55661) (xy 86.941587 -376.36934)
			(xy 86.913544 -376.180719) (xy 86.893478 -375.991084) (xy 86.881424 -375.800771) (xy 86.877404 -375.61012)
			(xy 0.509016 -375.61012) (xy 0.509016 -384.79984) (xy 14.086591 -384.79984) (xy 14.090616 -384.657648)
			(xy 14.102679 -384.515912) (xy 14.122742 -384.375086) (xy 14.15074 -384.23562) (xy 14.186584 -384.097961)
			(xy 14.230158 -383.962551) (xy 14.281323 -383.829823) (xy 14.339916 -383.700202) (xy 14.405747 -383.574104)
			(xy 14.478608 -383.451932) (xy 14.558263 -383.334078) (xy 14.644459 -383.220919) (xy 14.736918 -383.112817)
			(xy 14.835346 -383.01012) (xy 14.939425 -382.913156) (xy 15.048824 -382.822236) (xy 15.163192 -382.73765)
			(xy 15.282161 -382.65967) (xy 15.405352 -382.588546) (xy 15.532369 -382.524505) (xy 15.662806 -382.467753)
			(xy 15.796245 -382.418471) (xy 15.932258 -382.376817) (xy 16.07041 -382.342925) (xy 16.210259 -382.316904)
			(xy 16.351355 -382.298836) (xy 16.493247 -382.288779) (xy 16.635482 -382.286766) (xy 16.777602 -382.292803)
			(xy 16.919153 -382.306871) (xy 17.059682 -382.328925) (xy 17.198737 -382.358894) (xy 17.335875 -382.396682)
			(xy 17.470655 -382.442168) (xy 17.602646 -382.495206) (xy 17.731425 -382.555627) (xy 17.856579 -382.623236)
			(xy 17.977707 -382.697818) (xy 18.094423 -382.779134) (xy 18.206351 -382.866922) (xy 18.313133 -382.960902)
			(xy 18.414427 -383.060772) (xy 18.509908 -383.166214) (xy 18.599272 -383.276888) (xy 18.68223 -383.392441)
			(xy 18.758519 -383.512502) (xy 18.827893 -383.636687) (xy 18.89013 -383.764598) (xy 18.945031 -383.895825)
			(xy 18.992419 -384.029948) (xy 19.032144 -384.166537) (xy 19.064077 -384.305155) (xy 19.088118 -384.445357)
			(xy 19.104187 -384.586695) (xy 19.112235 -384.728716) (xy 19.112738 -384.79984) (xy 19.112235 -384.870964)
			(xy 19.104187 -385.012985) (xy 19.088118 -385.154323) (xy 19.064077 -385.294525) (xy 19.032144 -385.433143)
			(xy 18.992419 -385.569732) (xy 18.945031 -385.703855) (xy 18.89013 -385.835082) (xy 18.827893 -385.962993)
			(xy 18.758519 -386.087178) (xy 18.68223 -386.207239) (xy 18.599272 -386.322792) (xy 18.509908 -386.433466)
			(xy 18.414427 -386.538908) (xy 18.313133 -386.638778) (xy 18.206351 -386.732758) (xy 18.094423 -386.820546)
			(xy 17.977707 -386.901862) (xy 17.856579 -386.976444) (xy 17.731425 -387.044053) (xy 17.602646 -387.104474)
			(xy 17.470655 -387.157512) (xy 17.335875 -387.202998) (xy 17.198737 -387.240786) (xy 17.059682 -387.270755)
			(xy 16.919153 -387.292809) (xy 16.777602 -387.306877) (xy 16.635482 -387.312914) (xy 16.493247 -387.310901)
			(xy 16.351355 -387.300844) (xy 16.210259 -387.282776) (xy 16.07041 -387.256755) (xy 15.932258 -387.222863)
			(xy 15.796245 -387.181209) (xy 15.662806 -387.131927) (xy 15.532369 -387.075175) (xy 15.405352 -387.011134)
			(xy 15.282161 -386.94001) (xy 15.163192 -386.86203) (xy 15.048824 -386.777444) (xy 14.939425 -386.686524)
			(xy 14.835346 -386.58956) (xy 14.736918 -386.486863) (xy 14.644459 -386.378761) (xy 14.558263 -386.265602)
			(xy 14.478608 -386.147748) (xy 14.405747 -386.025576) (xy 14.339916 -385.899478) (xy 14.281323 -385.769857)
			(xy 14.230158 -385.637129) (xy 14.186584 -385.501719) (xy 14.15074 -385.36406) (xy 14.122742 -385.224594)
			(xy 14.102679 -385.083768) (xy 14.090616 -384.942032) (xy 14.086591 -384.79984) (xy 0.509016 -384.79984)
			(xy 0.509016 -399.479084) (xy 5.677649 -399.479084) (xy 5.677649 -399.352948) (xy 5.685569 -399.22706)
			(xy 5.701379 -399.101918) (xy 5.725014 -398.978015) (xy 5.756383 -398.855842) (xy 5.795361 -398.735879)
			(xy 5.841795 -398.6186) (xy 5.895502 -398.504468) (xy 5.956269 -398.393933) (xy 6.023856 -398.287433)
			(xy 6.097997 -398.185386) (xy 6.1784 -398.088196) (xy 6.264746 -397.996246) (xy 6.356696 -397.9099)
			(xy 6.453886 -397.829497) (xy 6.555933 -397.755356) (xy 6.662433 -397.687769) (xy 6.772968 -397.627002)
			(xy 6.8871 -397.573295) (xy 7.004379 -397.526861) (xy 7.124342 -397.487883) (xy 7.246515 -397.456514)
			(xy 7.370418 -397.432879) (xy 7.49556 -397.417069) (xy 7.621448 -397.409149) (xy 7.747584 -397.409149)
			(xy 7.873472 -397.417069) (xy 7.998614 -397.432879) (xy 8.122517 -397.456514) (xy 8.24469 -397.487883)
			(xy 8.364653 -397.526861) (xy 8.481932 -397.573295) (xy 8.596064 -397.627002) (xy 8.706599 -397.687769)
			(xy 8.813099 -397.755356) (xy 8.915146 -397.829497) (xy 9.012336 -397.9099) (xy 9.104286 -397.996246)
			(xy 9.190632 -398.088196) (xy 9.271035 -398.185386) (xy 9.345176 -398.287433) (xy 9.412763 -398.393933)
			(xy 9.47353 -398.504468) (xy 9.527237 -398.6186) (xy 9.573671 -398.735879) (xy 9.612649 -398.855842)
			(xy 9.644018 -398.978015) (xy 9.667653 -399.101918) (xy 9.683463 -399.22706) (xy 9.691383 -399.352948)
			(xy 9.691878 -399.416016) (xy 9.691383 -399.479084) (xy 9.683463 -399.604972) (xy 9.667653 -399.730114)
			(xy 9.644018 -399.854017) (xy 9.612649 -399.97619) (xy 9.573671 -400.096153) (xy 9.527237 -400.213432)
			(xy 9.47353 -400.327564) (xy 9.412763 -400.438099) (xy 9.345176 -400.544599) (xy 9.271035 -400.646646)
			(xy 9.190632 -400.743836) (xy 9.104286 -400.835786) (xy 9.012336 -400.922132) (xy 8.915146 -401.002535)
			(xy 8.813099 -401.076676) (xy 8.706599 -401.144263) (xy 8.596064 -401.20503) (xy 8.481932 -401.258737)
			(xy 8.364653 -401.305171) (xy 8.24469 -401.344149) (xy 8.122517 -401.375518) (xy 7.998614 -401.399153)
			(xy 7.873472 -401.414963) (xy 7.747584 -401.422883) (xy 7.621448 -401.422883) (xy 7.49556 -401.414963)
			(xy 7.370418 -401.399153) (xy 7.246515 -401.375518) (xy 7.124342 -401.344149) (xy 7.004379 -401.305171)
			(xy 6.8871 -401.258737) (xy 6.772968 -401.20503) (xy 6.662433 -401.144263) (xy 6.555933 -401.076676)
			(xy 6.453886 -401.002535) (xy 6.356696 -400.922132) (xy 6.264746 -400.835786) (xy 6.1784 -400.743836)
			(xy 6.097997 -400.646646) (xy 6.023856 -400.544599) (xy 5.956269 -400.438099) (xy 5.895502 -400.327564)
			(xy 5.841795 -400.213432) (xy 5.795361 -400.096153) (xy 5.756383 -399.97619) (xy 5.725014 -399.854017)
			(xy 5.701379 -399.730114) (xy 5.685569 -399.604972) (xy 5.677649 -399.479084) (xy 0.509016 -399.479084)
			(xy 0.509016 -406.96007) (xy 39.818564 -406.96007) (xy 39.819058 -406.902661) (xy 39.826902 -406.788113)
			(xy 39.842544 -406.674366) (xy 39.865911 -406.561952) (xy 39.896896 -406.451394) (xy 39.935352 -406.343209)
			(xy 39.981101 -406.2379) (xy 40.03393 -406.135958) (xy 40.093592 -406.037859) (xy 40.159809 -405.94406)
			(xy 40.232272 -405.854998) (xy 40.310645 -405.771089) (xy 40.39456 -405.692723) (xy 40.483627 -405.620266)
			(xy 40.577431 -405.554056) (xy 40.675535 -405.494402) (xy 40.777481 -405.441581) (xy 40.882793 -405.395839)
			(xy 40.990981 -405.357391) (xy 41.101541 -405.326415) (xy 41.213957 -405.303056) (xy 41.327705 -405.287423)
			(xy 41.442254 -405.279588) (xy 41.557072 -405.279588) (xy 41.671621 -405.287423) (xy 41.785369 -405.303056)
			(xy 41.897785 -405.326415) (xy 42.008345 -405.357391) (xy 42.116533 -405.395839) (xy 42.221845 -405.441581)
			(xy 42.323791 -405.494402) (xy 42.421895 -405.554056) (xy 42.515699 -405.620266) (xy 42.604766 -405.692723)
			(xy 42.688681 -405.771089) (xy 42.767054 -405.854998) (xy 42.839517 -405.94406) (xy 42.905734 -406.037859)
			(xy 42.965396 -406.135958) (xy 43.018225 -406.2379) (xy 43.063974 -406.343209) (xy 43.10243 -406.451394)
			(xy 43.133415 -406.561952) (xy 43.156782 -406.674366) (xy 43.172424 -406.788113) (xy 43.180268 -406.902661)
			(xy 43.180762 -406.96007) (xy 43.180576 -406.993253) (xy 43.177909 -407.059567) (xy 43.175428 -407.092658)
			(xy 43.170272 -407.150942) (xy 43.152948 -407.266671) (xy 43.127616 -407.380914) (xy 43.094401 -407.493119)
			(xy 43.053462 -407.602742) (xy 43.004999 -407.709253) (xy 42.949245 -407.812135) (xy 42.886471 -407.910891)
			(xy 42.816981 -408.005042) (xy 42.741111 -408.094132) (xy 42.659229 -408.177729) (xy 42.571732 -408.25543)
			(xy 42.500813 -408.31008) (xy 93.154506 -408.31008) (xy 93.158522 -408.19381) (xy 93.170549 -408.078095)
			(xy 93.190531 -407.963485) (xy 93.218373 -407.850526) (xy 93.253942 -407.739758) (xy 93.297068 -407.631707)
			(xy 93.347545 -407.526889) (xy 93.405134 -407.425804) (xy 93.46956 -407.328932) (xy 93.540515 -407.236736)
			(xy 93.617662 -407.149655) (xy 93.700633 -407.068104) (xy 93.789033 -406.992472) (xy 93.88244 -406.923118)
			(xy 93.980409 -406.860375) (xy 94.082473 -406.804539) (xy 94.188147 -406.755878) (xy 94.296926 -406.714624)
			(xy 94.408291 -406.680973) (xy 94.521714 -406.655085) (xy 94.636651 -406.637084) (xy 94.752557 -406.627055)
			(xy 94.868879 -406.625047) (xy 94.985062 -406.631069) (xy 95.100553 -406.645092) (xy 95.214801 -406.66705)
			(xy 95.327262 -406.696837) (xy 95.4374 -406.734312) (xy 95.54469 -406.779297) (xy 95.648621 -406.831576)
			(xy 95.748697 -406.890901) (xy 95.844443 -406.956989) (xy 95.9354 -407.029525) (xy 96.021136 -407.108164)
			(xy 96.101243 -407.19253) (xy 96.175339 -407.282222) (xy 96.243069 -407.376812) (xy 96.304113 -407.47585)
			(xy 96.358178 -407.578863) (xy 96.405008 -407.68536) (xy 96.444379 -407.794835) (xy 96.476103 -407.906765)
			(xy 96.500029 -408.020617) (xy 96.516043 -408.135849) (xy 96.52407 -408.251911) (xy 96.524572 -408.31008)
			(xy 96.52407 -408.368249) (xy 96.516043 -408.484311) (xy 96.500029 -408.599543) (xy 96.476103 -408.713395)
			(xy 96.444379 -408.825325) (xy 96.405008 -408.9348) (xy 96.358178 -409.041297) (xy 96.304113 -409.14431)
			(xy 96.243069 -409.243348) (xy 96.175339 -409.337938) (xy 96.101243 -409.42763) (xy 96.021136 -409.511996)
			(xy 95.9354 -409.590635) (xy 95.844443 -409.663171) (xy 95.748697 -409.729259) (xy 95.648621 -409.788584)
			(xy 95.54469 -409.840863) (xy 95.4374 -409.885848) (xy 95.327262 -409.923323) (xy 95.214801 -409.95311)
			(xy 95.100553 -409.975068) (xy 94.985062 -409.989091) (xy 94.868879 -409.995113) (xy 94.752557 -409.993105)
			(xy 94.636651 -409.983076) (xy 94.521714 -409.965075) (xy 94.408291 -409.939187) (xy 94.296926 -409.905536)
			(xy 94.188147 -409.864282) (xy 94.082473 -409.815621) (xy 93.980409 -409.759785) (xy 93.88244 -409.697042)
			(xy 93.789033 -409.627688) (xy 93.700633 -409.552056) (xy 93.617662 -409.470505) (xy 93.540515 -409.383424)
			(xy 93.46956 -409.291228) (xy 93.405134 -409.194356) (xy 93.347545 -409.093271) (xy 93.297068 -408.988453)
			(xy 93.253942 -408.880402) (xy 93.218373 -408.769634) (xy 93.190531 -408.656675) (xy 93.170549 -408.542065)
			(xy 93.158522 -408.42635) (xy 93.154506 -408.31008) (xy 42.500813 -408.31008) (xy 42.479042 -408.326857)
			(xy 42.381609 -408.391665) (xy 42.279905 -408.44954) (xy 42.174422 -408.500202) (xy 42.065671 -408.543404)
			(xy 41.954179 -408.578939) (xy 41.840485 -408.606634) (xy 41.725141 -408.626354) (xy 41.608704 -408.638005)
			(xy 41.491739 -408.64153) (xy 41.374812 -408.636912) (xy 41.258489 -408.624173) (xy 41.143334 -408.603375)
			(xy 41.029905 -408.574618) (xy 40.91875 -408.538042) (xy 40.810407 -408.493825) (xy 40.705403 -408.442179)
			(xy 40.604244 -408.383356) (xy 40.507421 -408.31764) (xy 40.415403 -408.245349) (xy 40.328636 -408.166834)
			(xy 40.247539 -408.082474) (xy 40.172506 -407.992679) (xy 40.103899 -407.897883) (xy 40.042051 -407.798544)
			(xy 39.987262 -407.695145) (xy 39.939796 -407.588186) (xy 39.899884 -407.478185) (xy 39.86772 -407.365674)
			(xy 39.843457 -407.251199) (xy 39.827215 -407.135313) (xy 39.819072 -407.018579) (xy 39.818564 -406.96007)
			(xy 0.509016 -406.96007) (xy 0.509016 -410.909084) (xy 5.677649 -410.909084) (xy 5.677649 -410.782948)
			(xy 5.685569 -410.65706) (xy 5.701379 -410.531918) (xy 5.725014 -410.408015) (xy 5.756383 -410.285842)
			(xy 5.795361 -410.165879) (xy 5.841795 -410.0486) (xy 5.895502 -409.934468) (xy 5.956269 -409.823933)
			(xy 6.023856 -409.717433) (xy 6.097997 -409.615386) (xy 6.1784 -409.518196) (xy 6.264746 -409.426246)
			(xy 6.356696 -409.3399) (xy 6.453886 -409.259497) (xy 6.555933 -409.185356) (xy 6.662433 -409.117769)
			(xy 6.772968 -409.057002) (xy 6.8871 -409.003295) (xy 7.004379 -408.956861) (xy 7.124342 -408.917883)
			(xy 7.246515 -408.886514) (xy 7.370418 -408.862879) (xy 7.49556 -408.847069) (xy 7.621448 -408.839149)
			(xy 7.747584 -408.839149) (xy 7.873472 -408.847069) (xy 7.998614 -408.862879) (xy 8.122517 -408.886514)
			(xy 8.24469 -408.917883) (xy 8.364653 -408.956861) (xy 8.481932 -409.003295) (xy 8.596064 -409.057002)
			(xy 8.706599 -409.117769) (xy 8.813099 -409.185356) (xy 8.915146 -409.259497) (xy 9.012336 -409.3399)
			(xy 9.104286 -409.426246) (xy 9.190632 -409.518196) (xy 9.271035 -409.615386) (xy 9.345176 -409.717433)
			(xy 9.412763 -409.823933) (xy 9.47353 -409.934468) (xy 9.527237 -410.0486) (xy 9.573671 -410.165879)
			(xy 9.612649 -410.285842) (xy 9.644018 -410.408015) (xy 9.667653 -410.531918) (xy 9.683463 -410.65706)
			(xy 9.691383 -410.782948) (xy 9.691878 -410.846016) (xy 9.691383 -410.909084) (xy 9.683463 -411.034972)
			(xy 9.667653 -411.160114) (xy 9.644018 -411.284017) (xy 9.612649 -411.40619) (xy 9.573671 -411.526153)
			(xy 9.527237 -411.643432) (xy 9.47353 -411.757564) (xy 9.412763 -411.868099) (xy 9.345176 -411.974599)
			(xy 9.271035 -412.076646) (xy 9.190632 -412.173836) (xy 9.104286 -412.265786) (xy 9.012336 -412.352132)
			(xy 8.915146 -412.432535) (xy 8.813099 -412.506676) (xy 8.706599 -412.574263) (xy 8.596064 -412.63503)
			(xy 8.481932 -412.688737) (xy 8.364653 -412.735171) (xy 8.24469 -412.774149) (xy 8.122517 -412.805518)
			(xy 7.998614 -412.829153) (xy 7.873472 -412.844963) (xy 7.747584 -412.852883) (xy 7.621448 -412.852883)
			(xy 7.49556 -412.844963) (xy 7.370418 -412.829153) (xy 7.246515 -412.805518) (xy 7.124342 -412.774149)
			(xy 7.004379 -412.735171) (xy 6.8871 -412.688737) (xy 6.772968 -412.63503) (xy 6.662433 -412.574263)
			(xy 6.555933 -412.506676) (xy 6.453886 -412.432535) (xy 6.356696 -412.352132) (xy 6.264746 -412.265786)
			(xy 6.1784 -412.173836) (xy 6.097997 -412.076646) (xy 6.023856 -411.974599) (xy 5.956269 -411.868099)
			(xy 5.895502 -411.757564) (xy 5.841795 -411.643432) (xy 5.795361 -411.526153) (xy 5.756383 -411.40619)
			(xy 5.725014 -411.284017) (xy 5.701379 -411.160114) (xy 5.685569 -411.034972) (xy 5.677649 -410.909084)
			(xy 0.509016 -410.909084) (xy 0.509016 -420.06012) (xy 86.877404 -420.06012) (xy 86.881424 -419.869469)
			(xy 86.893478 -419.679156) (xy 86.913544 -419.489521) (xy 86.941587 -419.3009) (xy 86.977556 -419.11363)
			(xy 87.021388 -418.928042) (xy 87.073005 -418.744467) (xy 87.132315 -418.563231) (xy 87.199213 -418.384656)
			(xy 87.273579 -418.209061) (xy 87.355281 -418.036756) (xy 87.444175 -417.868049) (xy 87.540101 -417.703239)
			(xy 87.64289 -417.54262) (xy 87.752359 -417.386477) (xy 87.868313 -417.235088) (xy 87.990547 -417.088721)
			(xy 88.118841 -416.947637) (xy 88.252969 -416.812088) (xy 88.392693 -416.682313) (xy 88.537763 -416.558543)
			(xy 88.687921 -416.441) (xy 88.842902 -416.329891) (xy 89.002429 -416.225414) (xy 89.166218 -416.127755)
			(xy 89.333978 -416.037088) (xy 89.505412 -415.953574) (xy 89.680214 -415.877361) (xy 89.858073 -415.808585)
			(xy 90.038674 -415.747367) (xy 90.221694 -415.693818) (xy 90.40681 -415.648032) (xy 90.593691 -415.61009)
			(xy 90.782006 -415.580061) (xy 90.971419 -415.557996) (xy 91.161593 -415.543937) (xy 91.352192 -415.537907)
			(xy 91.542875 -415.539917) (xy 91.733304 -415.549964) (xy 91.92314 -415.56803) (xy 92.112046 -415.594083)
			(xy 92.299685 -415.628076) (xy 92.485725 -415.669949) (xy 92.669834 -415.719628) (xy 92.851685 -415.777024)
			(xy 93.030955 -415.842035) (xy 93.207325 -415.914546) (xy 93.380481 -415.994427) (xy 93.550116 -416.081537)
			(xy 93.715928 -416.175721) (xy 93.877622 -416.276812) (xy 94.03491 -416.384628) (xy 94.187513 -416.49898)
			(xy 94.335161 -416.619663) (xy 94.477589 -416.746464) (xy 94.614545 -416.879155) (xy 94.745786 -417.017503)
			(xy 94.871078 -417.16126) (xy 94.990198 -417.310171) (xy 95.102934 -417.463972) (xy 95.209087 -417.622388)
			(xy 95.308467 -417.785139) (xy 95.400897 -417.951934) (xy 95.486214 -418.122478) (xy 95.564266 -418.296466)
			(xy 95.634913 -418.473591) (xy 95.698031 -418.653536) (xy 95.753507 -418.835982) (xy 95.801242 -419.020605)
			(xy 95.841152 -419.207075) (xy 95.873165 -419.395063) (xy 95.897225 -419.584233) (xy 95.913288 -419.774249)
			(xy 95.921327 -419.964773) (xy 95.92183 -420.06012) (xy 95.921327 -420.155467) (xy 95.913288 -420.345991)
			(xy 95.897225 -420.536007) (xy 95.873165 -420.725177) (xy 95.841152 -420.913165) (xy 95.801242 -421.099635)
			(xy 95.753507 -421.284258) (xy 95.698031 -421.466704) (xy 95.634913 -421.646649) (xy 95.564266 -421.823774)
			(xy 95.486214 -421.997762) (xy 95.400897 -422.168306) (xy 95.308467 -422.335101) (xy 95.209087 -422.497852)
			(xy 95.102934 -422.656268) (xy 94.990198 -422.810069) (xy 94.871078 -422.95898) (xy 94.745786 -423.102737)
			(xy 94.614545 -423.241085) (xy 94.477589 -423.373776) (xy 94.335161 -423.500577) (xy 94.187513 -423.62126)
			(xy 94.03491 -423.735612) (xy 93.877622 -423.843428) (xy 93.715928 -423.944519) (xy 93.550116 -424.038703)
			(xy 93.380481 -424.125813) (xy 93.207325 -424.205694) (xy 93.030955 -424.278205) (xy 92.851685 -424.343216)
			(xy 92.669834 -424.400612) (xy 92.485725 -424.450291) (xy 92.299685 -424.492164) (xy 92.112046 -424.526157)
			(xy 91.92314 -424.55221) (xy 91.733304 -424.570276) (xy 91.542875 -424.580323) (xy 91.352192 -424.582333)
			(xy 91.161593 -424.576303) (xy 90.971419 -424.562244) (xy 90.782006 -424.540179) (xy 90.593691 -424.51015)
			(xy 90.40681 -424.472208) (xy 90.221694 -424.426422) (xy 90.038674 -424.372873) (xy 89.858073 -424.311655)
			(xy 89.680214 -424.242879) (xy 89.505412 -424.166666) (xy 89.333978 -424.083152) (xy 89.166218 -423.992485)
			(xy 89.002429 -423.894826) (xy 88.842902 -423.790349) (xy 88.687921 -423.67924) (xy 88.537763 -423.561697)
			(xy 88.392693 -423.437927) (xy 88.252969 -423.308152) (xy 88.118841 -423.172603) (xy 87.990547 -423.031519)
			(xy 87.868313 -422.885152) (xy 87.752359 -422.733763) (xy 87.64289 -422.57762) (xy 87.540101 -422.417001)
			(xy 87.444175 -422.252191) (xy 87.355281 -422.083484) (xy 87.273579 -421.911179) (xy 87.199213 -421.735584)
			(xy 87.132315 -421.557009) (xy 87.073005 -421.375773) (xy 87.021388 -421.192198) (xy 86.977556 -421.00661)
			(xy 86.941587 -420.81934) (xy 86.913544 -420.630719) (xy 86.893478 -420.441084) (xy 86.881424 -420.250771)
			(xy 86.877404 -420.06012) (xy 0.509016 -420.06012) (xy 0.509016 -430.150016) (xy 75.486519 -430.150016)
			(xy 75.490544 -430.007824) (xy 75.502607 -429.866088) (xy 75.52267 -429.725262) (xy 75.550668 -429.585796)
			(xy 75.586512 -429.448137) (xy 75.630086 -429.312727) (xy 75.681251 -429.179999) (xy 75.739844 -429.050378)
			(xy 75.805675 -428.92428) (xy 75.878536 -428.802108) (xy 75.958191 -428.684254) (xy 76.044387 -428.571095)
			(xy 76.136846 -428.462993) (xy 76.235274 -428.360296) (xy 76.339353 -428.263332) (xy 76.448752 -428.172412)
			(xy 76.56312 -428.087826) (xy 76.682089 -428.009846) (xy 76.80528 -427.938722) (xy 76.932297 -427.874681)
			(xy 77.062734 -427.817929) (xy 77.196173 -427.768647) (xy 77.332186 -427.726993) (xy 77.470338 -427.693101)
			(xy 77.610187 -427.66708) (xy 77.751283 -427.649012) (xy 77.893175 -427.638955) (xy 78.03541 -427.636942)
			(xy 78.17753 -427.642979) (xy 78.319081 -427.657047) (xy 78.45961 -427.679101) (xy 78.598665 -427.70907)
			(xy 78.735803 -427.746858) (xy 78.870583 -427.792344) (xy 79.002574 -427.845382) (xy 79.131353 -427.905803)
			(xy 79.256507 -427.973412) (xy 79.377635 -428.047994) (xy 79.494351 -428.12931) (xy 79.606279 -428.217098)
			(xy 79.713061 -428.311078) (xy 79.814355 -428.410948) (xy 79.909836 -428.51639) (xy 79.9992 -428.627064)
			(xy 80.082158 -428.742617) (xy 80.158447 -428.862678) (xy 80.227821 -428.986863) (xy 80.290058 -429.114774)
			(xy 80.344959 -429.246001) (xy 80.392347 -429.380124) (xy 80.432072 -429.516713) (xy 80.464005 -429.655331)
			(xy 80.488046 -429.795533) (xy 80.504115 -429.936871) (xy 80.512163 -430.078892) (xy 80.512666 -430.150016)
			(xy 80.512163 -430.22114) (xy 80.504115 -430.363161) (xy 80.488046 -430.504499) (xy 80.464005 -430.644701)
			(xy 80.432072 -430.783319) (xy 80.392347 -430.919908) (xy 80.344959 -431.054031) (xy 80.290058 -431.185258)
			(xy 80.227821 -431.313169) (xy 80.158447 -431.437354) (xy 80.082158 -431.557415) (xy 79.9992 -431.672968)
			(xy 79.909836 -431.783642) (xy 79.814355 -431.889084) (xy 79.713061 -431.988954) (xy 79.606279 -432.082934)
			(xy 79.494351 -432.170722) (xy 79.377635 -432.252038) (xy 79.256507 -432.32662) (xy 79.131353 -432.394229)
			(xy 79.002574 -432.45465) (xy 78.870583 -432.507688) (xy 78.735803 -432.553174) (xy 78.598665 -432.590962)
			(xy 78.45961 -432.620931) (xy 78.319081 -432.642985) (xy 78.17753 -432.657053) (xy 78.03541 -432.66309)
			(xy 77.893175 -432.661077) (xy 77.751283 -432.65102) (xy 77.610187 -432.632952) (xy 77.470338 -432.606931)
			(xy 77.332186 -432.573039) (xy 77.196173 -432.531385) (xy 77.062734 -432.482103) (xy 76.932297 -432.425351)
			(xy 76.80528 -432.36131) (xy 76.682089 -432.290186) (xy 76.56312 -432.212206) (xy 76.448752 -432.12762)
			(xy 76.339353 -432.0367) (xy 76.235274 -431.939736) (xy 76.136846 -431.837039) (xy 76.044387 -431.728937)
			(xy 75.958191 -431.615778) (xy 75.878536 -431.497924) (xy 75.805675 -431.375752) (xy 75.739844 -431.249654)
			(xy 75.681251 -431.120033) (xy 75.630086 -430.987305) (xy 75.586512 -430.851895) (xy 75.550668 -430.714236)
			(xy 75.52267 -430.57477) (xy 75.502607 -430.433944) (xy 75.490544 -430.292208) (xy 75.486519 -430.150016)
			(xy 0.509016 -430.150016) (xy 0.509016 -451.41007) (xy 39.818564 -451.41007) (xy 39.819058 -451.352661)
			(xy 39.826902 -451.238113) (xy 39.842544 -451.124366) (xy 39.865911 -451.011952) (xy 39.896896 -450.901394)
			(xy 39.935352 -450.793209) (xy 39.981101 -450.6879) (xy 40.03393 -450.585958) (xy 40.093592 -450.487859)
			(xy 40.159809 -450.39406) (xy 40.232272 -450.304998) (xy 40.310645 -450.221089) (xy 40.39456 -450.142723)
			(xy 40.483627 -450.070266) (xy 40.577431 -450.004056) (xy 40.675535 -449.944402) (xy 40.777481 -449.891581)
			(xy 40.882793 -449.845839) (xy 40.990981 -449.807391) (xy 41.101541 -449.776415) (xy 41.213957 -449.753056)
			(xy 41.327705 -449.737423) (xy 41.442254 -449.729588) (xy 41.557072 -449.729588) (xy 41.671621 -449.737423)
			(xy 41.785369 -449.753056) (xy 41.897785 -449.776415) (xy 42.008345 -449.807391) (xy 42.116533 -449.845839)
			(xy 42.221845 -449.891581) (xy 42.323791 -449.944402) (xy 42.421895 -450.004056) (xy 42.515699 -450.070266)
			(xy 42.604766 -450.142723) (xy 42.688681 -450.221089) (xy 42.767054 -450.304998) (xy 42.839517 -450.39406)
			(xy 42.905734 -450.487859) (xy 42.965396 -450.585958) (xy 43.018225 -450.6879) (xy 43.063974 -450.793209)
			(xy 43.10243 -450.901394) (xy 43.133415 -451.011952) (xy 43.156782 -451.124366) (xy 43.172424 -451.238113)
			(xy 43.180268 -451.352661) (xy 43.180762 -451.41007) (xy 43.180576 -451.443253) (xy 43.177909 -451.509567)
			(xy 43.175428 -451.542658) (xy 43.170272 -451.600942) (xy 43.152948 -451.716671) (xy 43.127616 -451.830914)
			(xy 43.094401 -451.943119) (xy 43.053462 -452.052742) (xy 43.004999 -452.159253) (xy 42.949245 -452.262135)
			(xy 42.886471 -452.360891) (xy 42.816981 -452.455042) (xy 42.741111 -452.544132) (xy 42.659229 -452.627729)
			(xy 42.571732 -452.70543) (xy 42.500813 -452.76008) (xy 93.154506 -452.76008) (xy 93.158522 -452.64381)
			(xy 93.170549 -452.528095) (xy 93.190531 -452.413485) (xy 93.218373 -452.300526) (xy 93.253942 -452.189758)
			(xy 93.297068 -452.081707) (xy 93.347545 -451.976889) (xy 93.405134 -451.875804) (xy 93.46956 -451.778932)
			(xy 93.540515 -451.686736) (xy 93.617662 -451.599655) (xy 93.700633 -451.518104) (xy 93.789033 -451.442472)
			(xy 93.88244 -451.373118) (xy 93.980409 -451.310375) (xy 94.082473 -451.254539) (xy 94.188147 -451.205878)
			(xy 94.296926 -451.164624) (xy 94.408291 -451.130973) (xy 94.521714 -451.105085) (xy 94.636651 -451.087084)
			(xy 94.752557 -451.077055) (xy 94.868879 -451.075047) (xy 94.985062 -451.081069) (xy 95.100553 -451.095092)
			(xy 95.214801 -451.11705) (xy 95.327262 -451.146837) (xy 95.4374 -451.184312) (xy 95.54469 -451.229297)
			(xy 95.648621 -451.281576) (xy 95.748697 -451.340901) (xy 95.844443 -451.406989) (xy 95.9354 -451.479525)
			(xy 96.021136 -451.558164) (xy 96.101243 -451.64253) (xy 96.175339 -451.732222) (xy 96.243069 -451.826812)
			(xy 96.304113 -451.92585) (xy 96.358178 -452.028863) (xy 96.405008 -452.13536) (xy 96.444379 -452.244835)
			(xy 96.476103 -452.356765) (xy 96.500029 -452.470617) (xy 96.516043 -452.585849) (xy 96.52407 -452.701911)
			(xy 96.524572 -452.76008) (xy 96.52407 -452.818249) (xy 96.516043 -452.934311) (xy 96.500029 -453.049543)
			(xy 96.476103 -453.163395) (xy 96.444379 -453.275325) (xy 96.405008 -453.3848) (xy 96.358178 -453.491297)
			(xy 96.304113 -453.59431) (xy 96.243069 -453.693348) (xy 96.175339 -453.787938) (xy 96.101243 -453.87763)
			(xy 96.021136 -453.961996) (xy 95.9354 -454.040635) (xy 95.844443 -454.113171) (xy 95.748697 -454.179259)
			(xy 95.648621 -454.238584) (xy 95.54469 -454.290863) (xy 95.4374 -454.335848) (xy 95.327262 -454.373323)
			(xy 95.214801 -454.40311) (xy 95.100553 -454.425068) (xy 94.985062 -454.439091) (xy 94.868879 -454.445113)
			(xy 94.752557 -454.443105) (xy 94.636651 -454.433076) (xy 94.521714 -454.415075) (xy 94.408291 -454.389187)
			(xy 94.296926 -454.355536) (xy 94.188147 -454.314282) (xy 94.082473 -454.265621) (xy 93.980409 -454.209785)
			(xy 93.88244 -454.147042) (xy 93.789033 -454.077688) (xy 93.700633 -454.002056) (xy 93.617662 -453.920505)
			(xy 93.540515 -453.833424) (xy 93.46956 -453.741228) (xy 93.405134 -453.644356) (xy 93.347545 -453.543271)
			(xy 93.297068 -453.438453) (xy 93.253942 -453.330402) (xy 93.218373 -453.219634) (xy 93.190531 -453.106675)
			(xy 93.170549 -452.992065) (xy 93.158522 -452.87635) (xy 93.154506 -452.76008) (xy 42.500813 -452.76008)
			(xy 42.479042 -452.776857) (xy 42.381609 -452.841665) (xy 42.279905 -452.89954) (xy 42.174422 -452.950202)
			(xy 42.065671 -452.993404) (xy 41.954179 -453.028939) (xy 41.840485 -453.056634) (xy 41.725141 -453.076354)
			(xy 41.608704 -453.088005) (xy 41.491739 -453.09153) (xy 41.374812 -453.086912) (xy 41.258489 -453.074173)
			(xy 41.143334 -453.053375) (xy 41.029905 -453.024618) (xy 40.91875 -452.988042) (xy 40.810407 -452.943825)
			(xy 40.705403 -452.892179) (xy 40.604244 -452.833356) (xy 40.507421 -452.76764) (xy 40.415403 -452.695349)
			(xy 40.328636 -452.616834) (xy 40.247539 -452.532474) (xy 40.172506 -452.442679) (xy 40.103899 -452.347883)
			(xy 40.042051 -452.248544) (xy 39.987262 -452.145145) (xy 39.939796 -452.038186) (xy 39.899884 -451.928185)
			(xy 39.86772 -451.815674) (xy 39.843457 -451.701199) (xy 39.827215 -451.585313) (xy 39.819072 -451.468579)
			(xy 39.818564 -451.41007) (xy 0.509016 -451.41007) (xy 0.509016 -464.509866) (xy 86.877404 -464.509866)
			(xy 86.881424 -464.319215) (xy 86.893478 -464.128902) (xy 86.913544 -463.939267) (xy 86.941587 -463.750646)
			(xy 86.977556 -463.563376) (xy 87.021388 -463.377788) (xy 87.073005 -463.194213) (xy 87.132315 -463.012977)
			(xy 87.199213 -462.834402) (xy 87.273579 -462.658807) (xy 87.355281 -462.486502) (xy 87.444175 -462.317795)
			(xy 87.540101 -462.152985) (xy 87.64289 -461.992366) (xy 87.752359 -461.836223) (xy 87.868313 -461.684834)
			(xy 87.990547 -461.538467) (xy 88.118841 -461.397383) (xy 88.252969 -461.261834) (xy 88.392693 -461.132059)
			(xy 88.537763 -461.008289) (xy 88.687921 -460.890746) (xy 88.842902 -460.779637) (xy 89.002429 -460.67516)
			(xy 89.166218 -460.577501) (xy 89.333978 -460.486834) (xy 89.505412 -460.40332) (xy 89.680214 -460.327107)
			(xy 89.858073 -460.258331) (xy 90.038674 -460.197113) (xy 90.221694 -460.143564) (xy 90.40681 -460.097778)
			(xy 90.593691 -460.059836) (xy 90.782006 -460.029807) (xy 90.971419 -460.007742) (xy 91.161593 -459.993683)
			(xy 91.352192 -459.987653) (xy 91.542875 -459.989663) (xy 91.733304 -459.99971) (xy 91.92314 -460.017776)
			(xy 92.112046 -460.043829) (xy 92.299685 -460.077822) (xy 92.485725 -460.119695) (xy 92.669834 -460.169374)
			(xy 92.851685 -460.22677) (xy 93.030955 -460.291781) (xy 93.207325 -460.364292) (xy 93.380481 -460.444173)
			(xy 93.550116 -460.531283) (xy 93.715928 -460.625467) (xy 93.877622 -460.726558) (xy 94.03491 -460.834374)
			(xy 94.187513 -460.948726) (xy 94.335161 -461.069409) (xy 94.477589 -461.19621) (xy 94.614545 -461.328901)
			(xy 94.745786 -461.467249) (xy 94.871078 -461.611006) (xy 94.990198 -461.759917) (xy 95.102934 -461.913718)
			(xy 95.209087 -462.072134) (xy 95.308467 -462.234885) (xy 95.400897 -462.40168) (xy 95.486214 -462.572224)
			(xy 95.564266 -462.746212) (xy 95.634913 -462.923337) (xy 95.698031 -463.103282) (xy 95.753507 -463.285728)
			(xy 95.801242 -463.470351) (xy 95.841152 -463.656821) (xy 95.873165 -463.844809) (xy 95.897225 -464.033979)
			(xy 95.913288 -464.223995) (xy 95.921327 -464.414519) (xy 95.92183 -464.509866) (xy 95.921327 -464.605213)
			(xy 95.913288 -464.795737) (xy 95.897225 -464.985753) (xy 95.873165 -465.174923) (xy 95.841152 -465.362911)
			(xy 95.801242 -465.549381) (xy 95.753507 -465.734004) (xy 95.698031 -465.91645) (xy 95.634913 -466.096395)
			(xy 95.564266 -466.27352) (xy 95.486214 -466.447508) (xy 95.400897 -466.618052) (xy 95.308467 -466.784847)
			(xy 95.209087 -466.947598) (xy 95.102934 -467.106014) (xy 94.990198 -467.259815) (xy 94.871078 -467.408726)
			(xy 94.745786 -467.552483) (xy 94.614545 -467.690831) (xy 94.477589 -467.823522) (xy 94.335161 -467.950323)
			(xy 94.187513 -468.071006) (xy 94.03491 -468.185358) (xy 93.877622 -468.293174) (xy 93.715928 -468.394265)
			(xy 93.550116 -468.488449) (xy 93.380481 -468.575559) (xy 93.207325 -468.65544) (xy 93.030955 -468.727951)
			(xy 92.851685 -468.792962) (xy 92.669834 -468.850358) (xy 92.485725 -468.900037) (xy 92.299685 -468.94191)
			(xy 92.112046 -468.975903) (xy 91.92314 -469.001956) (xy 91.733304 -469.020022) (xy 91.542875 -469.030069)
			(xy 91.352192 -469.032079) (xy 91.161593 -469.026049) (xy 90.971419 -469.01199) (xy 90.782006 -468.989925)
			(xy 90.593691 -468.959896) (xy 90.40681 -468.921954) (xy 90.221694 -468.876168) (xy 90.038674 -468.822619)
			(xy 89.858073 -468.761401) (xy 89.680214 -468.692625) (xy 89.505412 -468.616412) (xy 89.333978 -468.532898)
			(xy 89.166218 -468.442231) (xy 89.002429 -468.344572) (xy 88.842902 -468.240095) (xy 88.687921 -468.128986)
			(xy 88.537763 -468.011443) (xy 88.392693 -467.887673) (xy 88.252969 -467.757898) (xy 88.118841 -467.622349)
			(xy 87.990547 -467.481265) (xy 87.868313 -467.334898) (xy 87.752359 -467.183509) (xy 87.64289 -467.027366)
			(xy 87.540101 -466.866747) (xy 87.444175 -466.701937) (xy 87.355281 -466.53323) (xy 87.273579 -466.360925)
			(xy 87.199213 -466.18533) (xy 87.132315 -466.006755) (xy 87.073005 -465.825519) (xy 87.021388 -465.641944)
			(xy 86.977556 -465.456356) (xy 86.941587 -465.269086) (xy 86.913544 -465.080465) (xy 86.893478 -464.89083)
			(xy 86.881424 -464.700517) (xy 86.877404 -464.509866) (xy 0.509016 -464.509866) (xy 0.509016 -471.172032)
			(xy 6.671831 -471.172032) (xy 6.675786 -471.080195) (xy 6.687621 -470.989038) (xy 6.707248 -470.899235)
			(xy 6.734522 -470.811453) (xy 6.769242 -470.726339) (xy 6.81115 -470.644526) (xy 6.859936 -470.566618)
			(xy 6.915239 -470.493193) (xy 6.976649 -470.424793) (xy 7.043711 -470.361926) (xy 7.11593 -470.305056)
			(xy 7.19277 -470.254605) (xy 7.273663 -470.210946) (xy 7.358009 -470.174403) (xy 7.445185 -470.145246)
			(xy 7.534544 -470.123692) (xy 7.625425 -470.109898) (xy 7.717156 -470.103968) (xy 7.809057 -470.105946)
			(xy 7.900448 -470.115817) (xy 7.990652 -470.133507) (xy 8.079001 -470.158887) (xy 8.164841 -470.191767)
			(xy 8.247537 -470.231905) (xy 8.326477 -470.279004) (xy 8.401075 -470.332714) (xy 8.470781 -470.392638)
			(xy 8.535076 -470.458332) (xy 8.593487 -470.52931) (xy 8.645579 -470.605047) (xy 8.690968 -470.684982)
			(xy 8.729318 -470.768522) (xy 8.760343 -470.85505) (xy 8.783816 -470.943925) (xy 8.799562 -471.034489)
			(xy 8.807464 -471.126071) (xy 8.807958 -471.172032) (xy 8.807464 -471.217993) (xy 8.799562 -471.309575)
			(xy 8.783816 -471.400139) (xy 8.760343 -471.489014) (xy 8.729318 -471.575542) (xy 8.690968 -471.659082)
			(xy 8.645579 -471.739017) (xy 8.593487 -471.814754) (xy 8.535076 -471.885732) (xy 8.470781 -471.951426)
			(xy 8.401075 -472.01135) (xy 8.326477 -472.06506) (xy 8.247537 -472.112159) (xy 8.164841 -472.152297)
			(xy 8.079001 -472.185177) (xy 7.990652 -472.210557) (xy 7.900448 -472.228247) (xy 7.809057 -472.238118)
			(xy 7.717156 -472.240096) (xy 7.625425 -472.234166) (xy 7.534544 -472.220372) (xy 7.445185 -472.198818)
			(xy 7.358009 -472.169661) (xy 7.273663 -472.133118) (xy 7.19277 -472.089459) (xy 7.11593 -472.039008)
			(xy 7.043711 -471.982138) (xy 6.976649 -471.919271) (xy 6.915239 -471.850871) (xy 6.859936 -471.777446)
			(xy 6.81115 -471.699538) (xy 6.769242 -471.617725) (xy 6.734522 -471.532611) (xy 6.707248 -471.444829)
			(xy 6.687621 -471.355026) (xy 6.675786 -471.263869) (xy 6.671831 -471.172032) (xy 0.509016 -471.172032)
			(xy 0.509016 -473.69984) (xy 14.086591 -473.69984) (xy 14.090616 -473.557648) (xy 14.102679 -473.415912)
			(xy 14.122742 -473.275086) (xy 14.15074 -473.13562) (xy 14.186584 -472.997961) (xy 14.230158 -472.862551)
			(xy 14.281323 -472.729823) (xy 14.339916 -472.600202) (xy 14.405747 -472.474104) (xy 14.478608 -472.351932)
			(xy 14.558263 -472.234078) (xy 14.644459 -472.120919) (xy 14.736918 -472.012817) (xy 14.835346 -471.91012)
			(xy 14.939425 -471.813156) (xy 15.048824 -471.722236) (xy 15.163192 -471.63765) (xy 15.282161 -471.55967)
			(xy 15.405352 -471.488546) (xy 15.532369 -471.424505) (xy 15.662806 -471.367753) (xy 15.796245 -471.318471)
			(xy 15.932258 -471.276817) (xy 16.07041 -471.242925) (xy 16.210259 -471.216904) (xy 16.351355 -471.198836)
			(xy 16.493247 -471.188779) (xy 16.635482 -471.186766) (xy 16.777602 -471.192803) (xy 16.919153 -471.206871)
			(xy 17.059682 -471.228925) (xy 17.198737 -471.258894) (xy 17.335875 -471.296682) (xy 17.470655 -471.342168)
			(xy 17.602646 -471.395206) (xy 17.731425 -471.455627) (xy 17.856579 -471.523236) (xy 17.977707 -471.597818)
			(xy 18.094423 -471.679134) (xy 18.206351 -471.766922) (xy 18.313133 -471.860902) (xy 18.414427 -471.960772)
			(xy 18.509908 -472.066214) (xy 18.599272 -472.176888) (xy 18.68223 -472.292441) (xy 18.758519 -472.412502)
			(xy 18.827893 -472.536687) (xy 18.89013 -472.664598) (xy 18.945031 -472.795825) (xy 18.992419 -472.929948)
			(xy 19.032144 -473.066537) (xy 19.064077 -473.205155) (xy 19.088118 -473.345357) (xy 19.104187 -473.486695)
			(xy 19.112235 -473.628716) (xy 19.112738 -473.69984) (xy 19.112235 -473.770964) (xy 19.104187 -473.912985)
			(xy 19.088118 -474.054323) (xy 19.064077 -474.194525) (xy 19.032144 -474.333143) (xy 18.992419 -474.469732)
			(xy 18.945031 -474.603855) (xy 18.89013 -474.735082) (xy 18.827893 -474.862993) (xy 18.758519 -474.987178)
			(xy 18.68223 -475.107239) (xy 18.599272 -475.222792) (xy 18.509908 -475.333466) (xy 18.414427 -475.438908)
			(xy 18.313133 -475.538778) (xy 18.206351 -475.632758) (xy 18.094423 -475.720546) (xy 17.977707 -475.801862)
			(xy 17.856579 -475.876444) (xy 17.731425 -475.944053) (xy 17.602646 -476.004474) (xy 17.470655 -476.057512)
			(xy 17.335875 -476.102998) (xy 17.198737 -476.140786) (xy 17.059682 -476.170755) (xy 16.919153 -476.192809)
			(xy 16.777602 -476.206877) (xy 16.635482 -476.212914) (xy 16.493247 -476.210901) (xy 16.351355 -476.200844)
			(xy 16.210259 -476.182776) (xy 16.07041 -476.156755) (xy 15.932258 -476.122863) (xy 15.796245 -476.081209)
			(xy 15.662806 -476.031927) (xy 15.532369 -475.975175) (xy 15.405352 -475.911134) (xy 15.282161 -475.84001)
			(xy 15.163192 -475.76203) (xy 15.048824 -475.677444) (xy 14.939425 -475.586524) (xy 14.835346 -475.48956)
			(xy 14.736918 -475.386863) (xy 14.644459 -475.278761) (xy 14.558263 -475.165602) (xy 14.478608 -475.047748)
			(xy 14.405747 -474.925576) (xy 14.339916 -474.799478) (xy 14.281323 -474.669857) (xy 14.230158 -474.537129)
			(xy 14.186584 -474.401719) (xy 14.15074 -474.26406) (xy 14.122742 -474.124594) (xy 14.102679 -473.983768)
			(xy 14.090616 -473.842032) (xy 14.086591 -473.69984) (xy 0.509016 -473.69984) (xy 0.509016 -477.804734)
			(xy 74.887582 -477.804734) (xy 74.888063 -477.725879) (xy 74.896049 -477.56837) (xy 74.912003 -477.411469)
			(xy 74.935883 -477.255577) (xy 74.967629 -477.101094) (xy 75.007158 -476.948418) (xy 75.05437 -476.79794)
			(xy 75.109143 -476.650046) (xy 75.171337 -476.505116) (xy 75.240791 -476.363523) (xy 75.317328 -476.225629)
			(xy 75.400751 -476.091789) (xy 75.490846 -475.962345) (xy 75.587381 -475.837632) (xy 75.69011 -475.717967)
			(xy 75.798767 -475.60366) (xy 75.913075 -475.495003) (xy 76.032739 -475.392275) (xy 76.157453 -475.29574)
			(xy 76.286897 -475.205645) (xy 76.420738 -475.122223) (xy 76.558632 -475.045686) (xy 76.700225 -474.976233)
			(xy 76.845155 -474.91404) (xy 76.993049 -474.859267) (xy 77.143528 -474.812056) (xy 77.296204 -474.772527)
			(xy 77.450687 -474.740781) (xy 77.606579 -474.716902) (xy 77.76348 -474.700948) (xy 77.920989 -474.692962)
			(xy 77.999844 -474.692472) (xy 77.999844 -474.692726) (xy 78.078692 -474.693217) (xy 78.236187 -474.701205)
			(xy 78.393074 -474.717159) (xy 78.548952 -474.741039) (xy 78.703421 -474.772783) (xy 78.856084 -474.81231)
			(xy 79.006548 -474.859519) (xy 79.154429 -474.914288) (xy 79.299345 -474.976477) (xy 79.440926 -475.045926)
			(xy 79.578807 -475.122457) (xy 79.712636 -475.205873) (xy 79.842067 -475.29596) (xy 79.96677 -475.392487)
			(xy 80.086424 -475.495207) (xy 80.200721 -475.603855) (xy 80.309368 -475.718152) (xy 80.412088 -475.837806)
			(xy 80.508615 -475.962509) (xy 80.598702 -476.091941) (xy 80.682117 -476.225769) (xy 80.758648 -476.363651)
			(xy 80.828096 -476.505232) (xy 80.890285 -476.650149) (xy 80.945053 -476.798029) (xy 80.992262 -476.948494)
			(xy 81.031789 -477.101157) (xy 81.063533 -477.255625) (xy 81.087412 -477.411504) (xy 81.103366 -477.568391)
			(xy 81.111353 -477.725886) (xy 81.111852 -477.804734) (xy 81.111852 -478.795334) (xy 81.111342 -478.874182)
			(xy 81.103353 -479.031675) (xy 81.087398 -479.188562) (xy 81.063517 -479.344439) (xy 81.031772 -479.498906)
			(xy 80.992244 -479.651567) (xy 80.945035 -479.802031) (xy 80.890265 -479.94991) (xy 80.828077 -480.094826)
			(xy 80.758628 -480.236405) (xy 80.682097 -480.374286) (xy 80.598682 -480.508113) (xy 80.508595 -480.637544)
			(xy 80.412068 -480.762246) (xy 80.30935 -480.881899) (xy 80.200703 -480.996196) (xy 80.086406 -481.104843)
			(xy 79.966754 -481.207562) (xy 79.842052 -481.304089) (xy 79.712621 -481.394176) (xy 79.578794 -481.477592)
			(xy 79.440914 -481.554123) (xy 79.299335 -481.623572) (xy 79.154419 -481.685762) (xy 79.00654 -481.740531)
			(xy 78.856077 -481.787741) (xy 78.703416 -481.82727) (xy 78.548948 -481.859015) (xy 78.393072 -481.882896)
			(xy 78.236185 -481.898852) (xy 78.078692 -481.906842) (xy 77.999844 -481.907342) (xy 77.920996 -481.906835)
			(xy 77.763502 -481.898848) (xy 77.606615 -481.882894) (xy 77.450737 -481.859015) (xy 77.296268 -481.827271)
			(xy 77.143606 -481.787744) (xy 76.993142 -481.740536) (xy 76.845262 -481.685767) (xy 76.700345 -481.623579)
			(xy 76.558765 -481.554131) (xy 76.420884 -481.4776) (xy 76.287055 -481.394185) (xy 76.157624 -481.304098)
			(xy 76.032921 -481.207571) (xy 75.913268 -481.104853) (xy 75.79897 -480.996205) (xy 75.690323 -480.881908)
			(xy 75.587604 -480.762255) (xy 75.491077 -480.637553) (xy 75.40099 -480.508121) (xy 75.317574 -480.374293)
			(xy 75.241043 -480.236412) (xy 75.171594 -480.094832) (xy 75.109406 -479.949916) (xy 75.054637 -479.802036)
			(xy 75.007428 -479.651571) (xy 74.967901 -479.498909) (xy 74.936157 -479.344441) (xy 74.912277 -479.188563)
			(xy 74.896323 -479.031676) (xy 74.888335 -478.874182) (xy 74.887836 -478.795334) (xy 74.887582 -477.804734)
			(xy 0.509016 -477.804734) (xy 0.509016 -480.172014) (xy 6.671831 -480.172014) (xy 6.675786 -480.080177)
			(xy 6.687621 -479.98902) (xy 6.707248 -479.899217) (xy 6.734522 -479.811435) (xy 6.769242 -479.726321)
			(xy 6.81115 -479.644508) (xy 6.859936 -479.5666) (xy 6.915239 -479.493175) (xy 6.976649 -479.424775)
			(xy 7.043711 -479.361908) (xy 7.11593 -479.305038) (xy 7.19277 -479.254587) (xy 7.273663 -479.210928)
			(xy 7.358009 -479.174385) (xy 7.445185 -479.145228) (xy 7.534544 -479.123674) (xy 7.625425 -479.10988)
			(xy 7.717156 -479.10395) (xy 7.809057 -479.105928) (xy 7.900448 -479.115799) (xy 7.990652 -479.133489)
			(xy 8.079001 -479.158869) (xy 8.164841 -479.191749) (xy 8.247537 -479.231887) (xy 8.326477 -479.278986)
			(xy 8.401075 -479.332696) (xy 8.470781 -479.39262) (xy 8.535076 -479.458314) (xy 8.593487 -479.529292)
			(xy 8.645579 -479.605029) (xy 8.690968 -479.684964) (xy 8.729318 -479.768504) (xy 8.760343 -479.855032)
			(xy 8.783816 -479.943907) (xy 8.799562 -480.034471) (xy 8.807464 -480.126053) (xy 8.807958 -480.172014)
			(xy 8.807464 -480.217975) (xy 8.799562 -480.309557) (xy 8.783816 -480.400121) (xy 8.760343 -480.488996)
			(xy 8.729318 -480.575524) (xy 8.690968 -480.659064) (xy 8.645579 -480.738999) (xy 8.593487 -480.814736)
			(xy 8.535076 -480.885714) (xy 8.470781 -480.951408) (xy 8.401075 -481.011332) (xy 8.326477 -481.065042)
			(xy 8.247537 -481.112141) (xy 8.164841 -481.152279) (xy 8.079001 -481.185159) (xy 7.990652 -481.210539)
			(xy 7.900448 -481.228229) (xy 7.809057 -481.2381) (xy 7.717156 -481.240078) (xy 7.625425 -481.234148)
			(xy 7.534544 -481.220354) (xy 7.445185 -481.1988) (xy 7.358009 -481.169643) (xy 7.273663 -481.1331)
			(xy 7.19277 -481.089441) (xy 7.11593 -481.03899) (xy 7.043711 -480.98212) (xy 6.976649 -480.919253)
			(xy 6.915239 -480.850853) (xy 6.859936 -480.777428) (xy 6.81115 -480.69952) (xy 6.769242 -480.617707)
			(xy 6.734522 -480.532593) (xy 6.707248 -480.444811) (xy 6.687621 -480.355008) (xy 6.675786 -480.263851)
			(xy 6.671831 -480.172014) (xy 0.509016 -480.172014) (xy 0.509016 -491.999778) (xy 6.671831 -491.999778)
			(xy 6.675786 -491.907941) (xy 6.687621 -491.816784) (xy 6.707248 -491.726981) (xy 6.734522 -491.639199)
			(xy 6.769242 -491.554085) (xy 6.81115 -491.472272) (xy 6.859936 -491.394364) (xy 6.915239 -491.320939)
			(xy 6.976649 -491.252539) (xy 7.043711 -491.189672) (xy 7.11593 -491.132802) (xy 7.19277 -491.082351)
			(xy 7.273663 -491.038692) (xy 7.358009 -491.002149) (xy 7.445185 -490.972992) (xy 7.534544 -490.951438)
			(xy 7.625425 -490.937644) (xy 7.717156 -490.931714) (xy 7.809057 -490.933692) (xy 7.900448 -490.943563)
			(xy 7.990652 -490.961253) (xy 8.079001 -490.986633) (xy 8.164841 -491.019513) (xy 8.247537 -491.059651)
			(xy 8.326477 -491.10675) (xy 8.401075 -491.16046) (xy 8.470781 -491.220384) (xy 8.535076 -491.286078)
			(xy 8.593487 -491.357056) (xy 8.645579 -491.432793) (xy 8.690968 -491.512728) (xy 8.729318 -491.596268)
			(xy 8.760343 -491.682796) (xy 8.783816 -491.771671) (xy 8.799562 -491.862235) (xy 8.807464 -491.953817)
			(xy 8.807958 -491.999778) (xy 8.807464 -492.045739) (xy 8.799562 -492.137321) (xy 8.783816 -492.227885)
			(xy 8.760343 -492.31676) (xy 8.729318 -492.403288) (xy 8.690968 -492.486828) (xy 8.645579 -492.566763)
			(xy 8.593487 -492.6425) (xy 8.535076 -492.713478) (xy 8.470781 -492.779172) (xy 8.401075 -492.839096)
			(xy 8.326477 -492.892806) (xy 8.247537 -492.939905) (xy 8.164841 -492.980043) (xy 8.079001 -493.012923)
			(xy 7.990652 -493.038303) (xy 7.900448 -493.055993) (xy 7.809057 -493.065864) (xy 7.717156 -493.067842)
			(xy 7.625425 -493.061912) (xy 7.534544 -493.048118) (xy 7.445185 -493.026564) (xy 7.358009 -492.997407)
			(xy 7.273663 -492.960864) (xy 7.19277 -492.917205) (xy 7.11593 -492.866754) (xy 7.043711 -492.809884)
			(xy 6.976649 -492.747017) (xy 6.915239 -492.678617) (xy 6.859936 -492.605192) (xy 6.81115 -492.527284)
			(xy 6.769242 -492.445471) (xy 6.734522 -492.360357) (xy 6.707248 -492.272575) (xy 6.687621 -492.182772)
			(xy 6.675786 -492.091615) (xy 6.671831 -491.999778) (xy 0.509016 -491.999778) (xy 0.509016 -495.86007)
			(xy 39.818564 -495.86007) (xy 39.819058 -495.802661) (xy 39.826902 -495.688113) (xy 39.842544 -495.574366)
			(xy 39.865911 -495.461952) (xy 39.896896 -495.351394) (xy 39.935352 -495.243209) (xy 39.981101 -495.1379)
			(xy 40.03393 -495.035958) (xy 40.093592 -494.937859) (xy 40.159809 -494.84406) (xy 40.232272 -494.754998)
			(xy 40.310645 -494.671089) (xy 40.39456 -494.592723) (xy 40.483627 -494.520266) (xy 40.577431 -494.454056)
			(xy 40.675535 -494.394402) (xy 40.777481 -494.341581) (xy 40.882793 -494.295839) (xy 40.990981 -494.257391)
			(xy 41.101541 -494.226415) (xy 41.213957 -494.203056) (xy 41.327705 -494.187423) (xy 41.442254 -494.179588)
			(xy 41.557072 -494.179588) (xy 41.671621 -494.187423) (xy 41.785369 -494.203056) (xy 41.897785 -494.226415)
			(xy 42.008345 -494.257391) (xy 42.116533 -494.295839) (xy 42.221845 -494.341581) (xy 42.323791 -494.394402)
			(xy 42.421895 -494.454056) (xy 42.515699 -494.520266) (xy 42.604766 -494.592723) (xy 42.688681 -494.671089)
			(xy 42.767054 -494.754998) (xy 42.839517 -494.84406) (xy 42.905734 -494.937859) (xy 42.965396 -495.035958)
			(xy 43.018225 -495.1379) (xy 43.063974 -495.243209) (xy 43.10243 -495.351394) (xy 43.133415 -495.461952)
			(xy 43.156782 -495.574366) (xy 43.172424 -495.688113) (xy 43.180268 -495.802661) (xy 43.180762 -495.86007)
			(xy 43.180576 -495.893253) (xy 43.177909 -495.959567) (xy 43.175428 -495.992658) (xy 43.170272 -496.050942)
			(xy 43.152948 -496.166671) (xy 43.127616 -496.280914) (xy 43.094401 -496.393119) (xy 43.053462 -496.502742)
			(xy 43.004999 -496.609253) (xy 42.949245 -496.712135) (xy 42.886471 -496.810891) (xy 42.816981 -496.905042)
			(xy 42.741111 -496.994132) (xy 42.659229 -497.077729) (xy 42.571732 -497.15543) (xy 42.500813 -497.21008)
			(xy 93.154506 -497.21008) (xy 93.158522 -497.09381) (xy 93.170549 -496.978095) (xy 93.190531 -496.863485)
			(xy 93.218373 -496.750526) (xy 93.253942 -496.639758) (xy 93.297068 -496.531707) (xy 93.347545 -496.426889)
			(xy 93.405134 -496.325804) (xy 93.46956 -496.228932) (xy 93.540515 -496.136736) (xy 93.617662 -496.049655)
			(xy 93.700633 -495.968104) (xy 93.789033 -495.892472) (xy 93.88244 -495.823118) (xy 93.980409 -495.760375)
			(xy 94.082473 -495.704539) (xy 94.188147 -495.655878) (xy 94.296926 -495.614624) (xy 94.408291 -495.580973)
			(xy 94.521714 -495.555085) (xy 94.636651 -495.537084) (xy 94.752557 -495.527055) (xy 94.868879 -495.525047)
			(xy 94.985062 -495.531069) (xy 95.100553 -495.545092) (xy 95.214801 -495.56705) (xy 95.327262 -495.596837)
			(xy 95.4374 -495.634312) (xy 95.54469 -495.679297) (xy 95.648621 -495.731576) (xy 95.748697 -495.790901)
			(xy 95.844443 -495.856989) (xy 95.9354 -495.929525) (xy 96.021136 -496.008164) (xy 96.101243 -496.09253)
			(xy 96.175339 -496.182222) (xy 96.243069 -496.276812) (xy 96.304113 -496.37585) (xy 96.358178 -496.478863)
			(xy 96.405008 -496.58536) (xy 96.444379 -496.694835) (xy 96.476103 -496.806765) (xy 96.500029 -496.920617)
			(xy 96.516043 -497.035849) (xy 96.52407 -497.151911) (xy 96.524572 -497.21008) (xy 96.52407 -497.268249)
			(xy 96.516043 -497.384311) (xy 96.500029 -497.499543) (xy 96.476103 -497.613395) (xy 96.444379 -497.725325)
			(xy 96.405008 -497.8348) (xy 96.358178 -497.941297) (xy 96.304113 -498.04431) (xy 96.243069 -498.143348)
			(xy 96.175339 -498.237938) (xy 96.101243 -498.32763) (xy 96.021136 -498.411996) (xy 95.9354 -498.490635)
			(xy 95.844443 -498.563171) (xy 95.748697 -498.629259) (xy 95.648621 -498.688584) (xy 95.54469 -498.740863)
			(xy 95.4374 -498.785848) (xy 95.327262 -498.823323) (xy 95.214801 -498.85311) (xy 95.100553 -498.875068)
			(xy 94.985062 -498.889091) (xy 94.868879 -498.895113) (xy 94.752557 -498.893105) (xy 94.636651 -498.883076)
			(xy 94.521714 -498.865075) (xy 94.408291 -498.839187) (xy 94.296926 -498.805536) (xy 94.188147 -498.764282)
			(xy 94.082473 -498.715621) (xy 93.980409 -498.659785) (xy 93.88244 -498.597042) (xy 93.789033 -498.527688)
			(xy 93.700633 -498.452056) (xy 93.617662 -498.370505) (xy 93.540515 -498.283424) (xy 93.46956 -498.191228)
			(xy 93.405134 -498.094356) (xy 93.347545 -497.993271) (xy 93.297068 -497.888453) (xy 93.253942 -497.780402)
			(xy 93.218373 -497.669634) (xy 93.190531 -497.556675) (xy 93.170549 -497.442065) (xy 93.158522 -497.32635)
			(xy 93.154506 -497.21008) (xy 42.500813 -497.21008) (xy 42.479042 -497.226857) (xy 42.381609 -497.291665)
			(xy 42.279905 -497.34954) (xy 42.174422 -497.400202) (xy 42.065671 -497.443404) (xy 41.954179 -497.478939)
			(xy 41.840485 -497.506634) (xy 41.725141 -497.526354) (xy 41.608704 -497.538005) (xy 41.491739 -497.54153)
			(xy 41.374812 -497.536912) (xy 41.258489 -497.524173) (xy 41.143334 -497.503375) (xy 41.029905 -497.474618)
			(xy 40.91875 -497.438042) (xy 40.810407 -497.393825) (xy 40.705403 -497.342179) (xy 40.604244 -497.283356)
			(xy 40.507421 -497.21764) (xy 40.415403 -497.145349) (xy 40.328636 -497.066834) (xy 40.247539 -496.982474)
			(xy 40.172506 -496.892679) (xy 40.103899 -496.797883) (xy 40.042051 -496.698544) (xy 39.987262 -496.595145)
			(xy 39.939796 -496.488186) (xy 39.899884 -496.378185) (xy 39.86772 -496.265674) (xy 39.843457 -496.151199)
			(xy 39.827215 -496.035313) (xy 39.819072 -495.918579) (xy 39.818564 -495.86007) (xy 0.509016 -495.86007)
			(xy 0.509016 -500.99976) (xy 6.671831 -500.99976) (xy 6.675786 -500.907923) (xy 6.687621 -500.816766)
			(xy 6.707248 -500.726963) (xy 6.734522 -500.639181) (xy 6.769242 -500.554067) (xy 6.81115 -500.472254)
			(xy 6.859936 -500.394346) (xy 6.915239 -500.320921) (xy 6.976649 -500.252521) (xy 7.043711 -500.189654)
			(xy 7.11593 -500.132784) (xy 7.19277 -500.082333) (xy 7.273663 -500.038674) (xy 7.358009 -500.002131)
			(xy 7.445185 -499.972974) (xy 7.534544 -499.95142) (xy 7.625425 -499.937626) (xy 7.717156 -499.931696)
			(xy 7.809057 -499.933674) (xy 7.900448 -499.943545) (xy 7.990652 -499.961235) (xy 8.079001 -499.986615)
			(xy 8.164841 -500.019495) (xy 8.247537 -500.059633) (xy 8.326477 -500.106732) (xy 8.401075 -500.160442)
			(xy 8.470781 -500.220366) (xy 8.535076 -500.28606) (xy 8.593487 -500.357038) (xy 8.645579 -500.432775)
			(xy 8.690968 -500.51271) (xy 8.729318 -500.59625) (xy 8.760343 -500.682778) (xy 8.783816 -500.771653)
			(xy 8.799562 -500.862217) (xy 8.807464 -500.953799) (xy 8.807958 -500.99976) (xy 8.807464 -501.045721)
			(xy 8.799562 -501.137303) (xy 8.783816 -501.227867) (xy 8.760343 -501.316742) (xy 8.729318 -501.40327)
			(xy 8.690968 -501.48681) (xy 8.645579 -501.566745) (xy 8.593487 -501.642482) (xy 8.535076 -501.71346)
			(xy 8.470781 -501.779154) (xy 8.401075 -501.839078) (xy 8.326477 -501.892788) (xy 8.247537 -501.939887)
			(xy 8.164841 -501.980025) (xy 8.079001 -502.012905) (xy 7.990652 -502.038285) (xy 7.900448 -502.055975)
			(xy 7.809057 -502.065846) (xy 7.717156 -502.067824) (xy 7.625425 -502.061894) (xy 7.534544 -502.0481)
			(xy 7.445185 -502.026546) (xy 7.358009 -501.997389) (xy 7.273663 -501.960846) (xy 7.19277 -501.917187)
			(xy 7.11593 -501.866736) (xy 7.043711 -501.809866) (xy 6.976649 -501.746999) (xy 6.915239 -501.678599)
			(xy 6.859936 -501.605174) (xy 6.81115 -501.527266) (xy 6.769242 -501.445453) (xy 6.734522 -501.360339)
			(xy 6.707248 -501.272557) (xy 6.687621 -501.182754) (xy 6.675786 -501.091597) (xy 6.671831 -500.99976)
			(xy 0.509016 -500.99976) (xy 0.509016 -508.96012) (xy 86.877404 -508.96012) (xy 86.881424 -508.769469)
			(xy 86.893478 -508.579156) (xy 86.913544 -508.389521) (xy 86.941587 -508.2009) (xy 86.977556 -508.01363)
			(xy 87.021388 -507.828042) (xy 87.073005 -507.644467) (xy 87.132315 -507.463231) (xy 87.199213 -507.284656)
			(xy 87.273579 -507.109061) (xy 87.355281 -506.936756) (xy 87.444175 -506.768049) (xy 87.540101 -506.603239)
			(xy 87.64289 -506.44262) (xy 87.752359 -506.286477) (xy 87.868313 -506.135088) (xy 87.990547 -505.988721)
			(xy 88.118841 -505.847637) (xy 88.252969 -505.712088) (xy 88.392693 -505.582313) (xy 88.537763 -505.458543)
			(xy 88.687921 -505.341) (xy 88.842902 -505.229891) (xy 89.002429 -505.125414) (xy 89.166218 -505.027755)
			(xy 89.333978 -504.937088) (xy 89.505412 -504.853574) (xy 89.680214 -504.777361) (xy 89.858073 -504.708585)
			(xy 90.038674 -504.647367) (xy 90.221694 -504.593818) (xy 90.40681 -504.548032) (xy 90.593691 -504.51009)
			(xy 90.782006 -504.480061) (xy 90.971419 -504.457996) (xy 91.161593 -504.443937) (xy 91.352192 -504.437907)
			(xy 91.542875 -504.439917) (xy 91.733304 -504.449964) (xy 91.92314 -504.46803) (xy 92.112046 -504.494083)
			(xy 92.299685 -504.528076) (xy 92.485725 -504.569949) (xy 92.669834 -504.619628) (xy 92.851685 -504.677024)
			(xy 93.030955 -504.742035) (xy 93.207325 -504.814546) (xy 93.380481 -504.894427) (xy 93.550116 -504.981537)
			(xy 93.715928 -505.075721) (xy 93.877622 -505.176812) (xy 94.03491 -505.284628) (xy 94.187513 -505.39898)
			(xy 94.335161 -505.519663) (xy 94.477589 -505.646464) (xy 94.614545 -505.779155) (xy 94.745786 -505.917503)
			(xy 94.871078 -506.06126) (xy 94.990198 -506.210171) (xy 95.102934 -506.363972) (xy 95.209087 -506.522388)
			(xy 95.308467 -506.685139) (xy 95.400897 -506.851934) (xy 95.486214 -507.022478) (xy 95.564266 -507.196466)
			(xy 95.634913 -507.373591) (xy 95.698031 -507.553536) (xy 95.753507 -507.735982) (xy 95.801242 -507.920605)
			(xy 95.841152 -508.107075) (xy 95.873165 -508.295063) (xy 95.897225 -508.484233) (xy 95.913288 -508.674249)
			(xy 95.921327 -508.864773) (xy 95.92183 -508.96012) (xy 95.921327 -509.055467) (xy 95.913288 -509.245991)
			(xy 95.897225 -509.436007) (xy 95.873165 -509.625177) (xy 95.841152 -509.813165) (xy 95.801242 -509.999635)
			(xy 95.753507 -510.184258) (xy 95.698031 -510.366704) (xy 95.634913 -510.546649) (xy 95.564266 -510.723774)
			(xy 95.486214 -510.897762) (xy 95.400897 -511.068306) (xy 95.308467 -511.235101) (xy 95.209087 -511.397852)
			(xy 95.102934 -511.556268) (xy 94.990198 -511.710069) (xy 94.871078 -511.85898) (xy 94.745786 -512.002737)
			(xy 94.614545 -512.141085) (xy 94.477589 -512.273776) (xy 94.335161 -512.400577) (xy 94.187513 -512.52126)
			(xy 94.03491 -512.635612) (xy 93.877622 -512.743428) (xy 93.715928 -512.844519) (xy 93.550116 -512.938703)
			(xy 93.380481 -513.025813) (xy 93.207325 -513.105694) (xy 93.030955 -513.178205) (xy 92.851685 -513.243216)
			(xy 92.669834 -513.300612) (xy 92.485725 -513.350291) (xy 92.299685 -513.392164) (xy 92.112046 -513.426157)
			(xy 91.92314 -513.45221) (xy 91.733304 -513.470276) (xy 91.542875 -513.480323) (xy 91.352192 -513.482333)
			(xy 91.161593 -513.476303) (xy 90.971419 -513.462244) (xy 90.782006 -513.440179) (xy 90.593691 -513.41015)
			(xy 90.40681 -513.372208) (xy 90.221694 -513.326422) (xy 90.038674 -513.272873) (xy 89.858073 -513.211655)
			(xy 89.680214 -513.142879) (xy 89.505412 -513.066666) (xy 89.333978 -512.983152) (xy 89.166218 -512.892485)
			(xy 89.002429 -512.794826) (xy 88.842902 -512.690349) (xy 88.687921 -512.57924) (xy 88.537763 -512.461697)
			(xy 88.392693 -512.337927) (xy 88.252969 -512.208152) (xy 88.118841 -512.072603) (xy 87.990547 -511.931519)
			(xy 87.868313 -511.785152) (xy 87.752359 -511.633763) (xy 87.64289 -511.47762) (xy 87.540101 -511.317001)
			(xy 87.444175 -511.152191) (xy 87.355281 -510.983484) (xy 87.273579 -510.811179) (xy 87.199213 -510.635584)
			(xy 87.132315 -510.457009) (xy 87.073005 -510.275773) (xy 87.021388 -510.092198) (xy 86.977556 -509.90661)
			(xy 86.941587 -509.71934) (xy 86.913544 -509.530719) (xy 86.893478 -509.341084) (xy 86.881424 -509.150771)
			(xy 86.877404 -508.96012) (xy 0.509016 -508.96012) (xy 0.509016 -511.049778) (xy 6.671831 -511.049778)
			(xy 6.675786 -510.957941) (xy 6.687621 -510.866784) (xy 6.707248 -510.776981) (xy 6.734522 -510.689199)
			(xy 6.769242 -510.604085) (xy 6.81115 -510.522272) (xy 6.859936 -510.444364) (xy 6.915239 -510.370939)
			(xy 6.976649 -510.302539) (xy 7.043711 -510.239672) (xy 7.11593 -510.182802) (xy 7.19277 -510.132351)
			(xy 7.273663 -510.088692) (xy 7.358009 -510.052149) (xy 7.445185 -510.022992) (xy 7.534544 -510.001438)
			(xy 7.625425 -509.987644) (xy 7.717156 -509.981714) (xy 7.809057 -509.983692) (xy 7.900448 -509.993563)
			(xy 7.990652 -510.011253) (xy 8.079001 -510.036633) (xy 8.164841 -510.069513) (xy 8.247537 -510.109651)
			(xy 8.326477 -510.15675) (xy 8.401075 -510.21046) (xy 8.470781 -510.270384) (xy 8.535076 -510.336078)
			(xy 8.593487 -510.407056) (xy 8.645579 -510.482793) (xy 8.690968 -510.562728) (xy 8.729318 -510.646268)
			(xy 8.760343 -510.732796) (xy 8.783816 -510.821671) (xy 8.799562 -510.912235) (xy 8.807464 -511.003817)
			(xy 8.807958 -511.049778) (xy 8.807464 -511.095739) (xy 8.799562 -511.187321) (xy 8.783816 -511.277885)
			(xy 8.760343 -511.36676) (xy 8.729318 -511.453288) (xy 8.690968 -511.536828) (xy 8.645579 -511.616763)
			(xy 8.593487 -511.6925) (xy 8.535076 -511.763478) (xy 8.470781 -511.829172) (xy 8.401075 -511.889096)
			(xy 8.326477 -511.942806) (xy 8.247537 -511.989905) (xy 8.164841 -512.030043) (xy 8.079001 -512.062923)
			(xy 7.990652 -512.088303) (xy 7.900448 -512.105993) (xy 7.809057 -512.115864) (xy 7.717156 -512.117842)
			(xy 7.625425 -512.111912) (xy 7.534544 -512.098118) (xy 7.445185 -512.076564) (xy 7.358009 -512.047407)
			(xy 7.273663 -512.010864) (xy 7.19277 -511.967205) (xy 7.11593 -511.916754) (xy 7.043711 -511.859884)
			(xy 6.976649 -511.797017) (xy 6.915239 -511.728617) (xy 6.859936 -511.655192) (xy 6.81115 -511.577284)
			(xy 6.769242 -511.495471) (xy 6.734522 -511.410357) (xy 6.707248 -511.322575) (xy 6.687621 -511.232772)
			(xy 6.675786 -511.141615) (xy 6.671831 -511.049778) (xy 0.509016 -511.049778) (xy 0.509016 -520.04976)
			(xy 6.671831 -520.04976) (xy 6.675786 -519.957923) (xy 6.687621 -519.866766) (xy 6.707248 -519.776963)
			(xy 6.734522 -519.689181) (xy 6.769242 -519.604067) (xy 6.81115 -519.522254) (xy 6.859936 -519.444346)
			(xy 6.915239 -519.370921) (xy 6.976649 -519.302521) (xy 7.043711 -519.239654) (xy 7.11593 -519.182784)
			(xy 7.19277 -519.132333) (xy 7.273663 -519.088674) (xy 7.358009 -519.052131) (xy 7.445185 -519.022974)
			(xy 7.534544 -519.00142) (xy 7.625425 -518.987626) (xy 7.717156 -518.981696) (xy 7.809057 -518.983674)
			(xy 7.900448 -518.993545) (xy 7.990652 -519.011235) (xy 8.079001 -519.036615) (xy 8.113324 -519.049762)
			(xy 75.486773 -519.049762) (xy 75.490798 -518.90757) (xy 75.502861 -518.765834) (xy 75.522924 -518.625008)
			(xy 75.550922 -518.485542) (xy 75.586766 -518.347883) (xy 75.63034 -518.212473) (xy 75.681505 -518.079745)
			(xy 75.740098 -517.950124) (xy 75.805929 -517.824026) (xy 75.87879 -517.701854) (xy 75.958445 -517.584)
			(xy 76.044641 -517.470841) (xy 76.1371 -517.362739) (xy 76.235528 -517.260042) (xy 76.339607 -517.163078)
			(xy 76.449006 -517.072158) (xy 76.563374 -516.987572) (xy 76.682343 -516.909592) (xy 76.805534 -516.838468)
			(xy 76.932551 -516.774427) (xy 77.062988 -516.717675) (xy 77.196427 -516.668393) (xy 77.33244 -516.626739)
			(xy 77.470592 -516.592847) (xy 77.610441 -516.566826) (xy 77.751537 -516.548758) (xy 77.893429 -516.538701)
			(xy 78.035664 -516.536688) (xy 78.177784 -516.542725) (xy 78.319335 -516.556793) (xy 78.459864 -516.578847)
			(xy 78.598919 -516.608816) (xy 78.736057 -516.646604) (xy 78.870837 -516.69209) (xy 79.002828 -516.745128)
			(xy 79.131607 -516.805549) (xy 79.256761 -516.873158) (xy 79.377889 -516.94774) (xy 79.494605 -517.029056)
			(xy 79.606533 -517.116844) (xy 79.713315 -517.210824) (xy 79.814609 -517.310694) (xy 79.91009 -517.416136)
			(xy 79.999454 -517.52681) (xy 80.082412 -517.642363) (xy 80.158701 -517.762424) (xy 80.228075 -517.886609)
			(xy 80.290312 -518.01452) (xy 80.345213 -518.145747) (xy 80.392601 -518.27987) (xy 80.432326 -518.416459)
			(xy 80.464259 -518.555077) (xy 80.4883 -518.695279) (xy 80.504369 -518.836617) (xy 80.512417 -518.978638)
			(xy 80.51292 -519.049762) (xy 80.512417 -519.120886) (xy 80.504369 -519.262907) (xy 80.4883 -519.404245)
			(xy 80.464259 -519.544447) (xy 80.432326 -519.683065) (xy 80.392601 -519.819654) (xy 80.345213 -519.953777)
			(xy 80.290312 -520.085004) (xy 80.228075 -520.212915) (xy 80.158701 -520.3371) (xy 80.082412 -520.457161)
			(xy 79.999454 -520.572714) (xy 79.91009 -520.683388) (xy 79.814609 -520.78883) (xy 79.713315 -520.8887)
			(xy 79.606533 -520.98268) (xy 79.494605 -521.070468) (xy 79.377889 -521.151784) (xy 79.256761 -521.226366)
			(xy 79.131607 -521.293975) (xy 79.002828 -521.354396) (xy 78.870837 -521.407434) (xy 78.736057 -521.45292)
			(xy 78.598919 -521.490708) (xy 78.459864 -521.520677) (xy 78.319335 -521.542731) (xy 78.177784 -521.556799)
			(xy 78.035664 -521.562836) (xy 77.893429 -521.560823) (xy 77.751537 -521.550766) (xy 77.610441 -521.532698)
			(xy 77.470592 -521.506677) (xy 77.33244 -521.472785) (xy 77.196427 -521.431131) (xy 77.062988 -521.381849)
			(xy 76.932551 -521.325097) (xy 76.805534 -521.261056) (xy 76.682343 -521.189932) (xy 76.563374 -521.111952)
			(xy 76.449006 -521.027366) (xy 76.339607 -520.936446) (xy 76.235528 -520.839482) (xy 76.1371 -520.736785)
			(xy 76.044641 -520.628683) (xy 75.958445 -520.515524) (xy 75.87879 -520.39767) (xy 75.805929 -520.275498)
			(xy 75.740098 -520.1494) (xy 75.681505 -520.019779) (xy 75.63034 -519.887051) (xy 75.586766 -519.751641)
			(xy 75.550922 -519.613982) (xy 75.522924 -519.474516) (xy 75.502861 -519.33369) (xy 75.490798 -519.191954)
			(xy 75.486773 -519.049762) (xy 8.113324 -519.049762) (xy 8.164841 -519.069495) (xy 8.247537 -519.109633)
			(xy 8.326477 -519.156732) (xy 8.401075 -519.210442) (xy 8.470781 -519.270366) (xy 8.535076 -519.33606)
			(xy 8.593487 -519.407038) (xy 8.645579 -519.482775) (xy 8.690968 -519.56271) (xy 8.729318 -519.64625)
			(xy 8.760343 -519.732778) (xy 8.783816 -519.821653) (xy 8.799562 -519.912217) (xy 8.807464 -520.003799)
			(xy 8.807958 -520.04976) (xy 8.807464 -520.095721) (xy 8.799562 -520.187303) (xy 8.783816 -520.277867)
			(xy 8.760343 -520.366742) (xy 8.729318 -520.45327) (xy 8.690968 -520.53681) (xy 8.645579 -520.616745)
			(xy 8.593487 -520.692482) (xy 8.535076 -520.76346) (xy 8.470781 -520.829154) (xy 8.401075 -520.889078)
			(xy 8.326477 -520.942788) (xy 8.247537 -520.989887) (xy 8.164841 -521.030025) (xy 8.079001 -521.062905)
			(xy 7.990652 -521.088285) (xy 7.900448 -521.105975) (xy 7.809057 -521.115846) (xy 7.717156 -521.117824)
			(xy 7.625425 -521.111894) (xy 7.534544 -521.0981) (xy 7.445185 -521.076546) (xy 7.358009 -521.047389)
			(xy 7.273663 -521.010846) (xy 7.19277 -520.967187) (xy 7.11593 -520.916736) (xy 7.043711 -520.859866)
			(xy 6.976649 -520.796999) (xy 6.915239 -520.728599) (xy 6.859936 -520.655174) (xy 6.81115 -520.577266)
			(xy 6.769242 -520.495453) (xy 6.734522 -520.410339) (xy 6.707248 -520.322557) (xy 6.687621 -520.232754)
			(xy 6.675786 -520.141597) (xy 6.671831 -520.04976) (xy 0.509016 -520.04976) (xy 0.509016 -524.500094)
			(xy 0.509529 -524.54588) (xy 0.517978 -524.637062) (xy 0.534804 -524.727075) (xy 0.559864 -524.815152)
			(xy 0.592944 -524.900541) (xy 0.633761 -524.982513) (xy 0.681968 -525.06037) (xy 0.737153 -525.133446)
			(xy 0.798845 -525.201119) (xy 0.866518 -525.262811) (xy 0.939594 -525.317996) (xy 1.017451 -525.366203)
			(xy 1.099423 -525.40702) (xy 1.184812 -525.4401) (xy 1.272889 -525.46516) (xy 1.362902 -525.481986)
			(xy 1.454084 -525.490435) (xy 1.49987 -525.490948) (xy 23.50008 -525.490948) (xy 23.563199 -525.491452)
			(xy 23.689186 -525.499396) (xy 23.814426 -525.515233) (xy 23.938425 -525.538903) (xy 24.060692 -525.570311)
			(xy 24.180747 -525.609334) (xy 24.298115 -525.655817) (xy 24.412333 -525.709578) (xy 24.52295 -525.770404)
			(xy 24.62953 -525.838054) (xy 24.731652 -525.912263) (xy 24.828913 -525.992737) (xy 24.920931 -526.079159)
			(xy 25.00734 -526.171188) (xy 25.087801 -526.26846) (xy 25.161996 -526.370592) (xy 25.229633 -526.477181)
			(xy 25.290444 -526.587806) (xy 25.344189 -526.702031) (xy 25.390657 -526.819405) (xy 25.429664 -526.939465)
			(xy 25.461055 -527.061737) (xy 25.484709 -527.185739) (xy 25.50053 -527.310981) (xy 25.508456 -527.436969)
			(xy 25.508966 -527.500088) (xy 25.508966 -528.500086) (xy 25.509507 -528.545875) (xy 25.517982 -528.637061)
			(xy 25.534832 -528.727076) (xy 25.559914 -528.815153) (xy 25.593014 -528.90054) (xy 25.633851 -528.98251)
			(xy 25.682074 -529.060363) (xy 25.737274 -529.133435) (xy 25.79898 -529.201104) (xy 25.866665 -529.262792)
			(xy 25.939752 -529.317973) (xy 26.017618 -529.366176) (xy 26.099598 -529.406991) (xy 26.184994 -529.440069)
			(xy 26.273077 -529.465128) (xy 26.363097 -529.481954) (xy 26.454285 -529.490405) (xy 26.500074 -529.49094)
		)
		(stroke
			(width 0)
			(type solid)
		)
		(fill yes)
		(layer "In6.Cu")
		(net "GND")
	)
	(gr_arc
		(start 1.500124 -3.999992)
		(mid 0.439376 -4.439368)
		(end 0 -5.500116)
		(stroke
			(width 1.016)
			(type default)
		)
		(layer "In6.Cu")
	)
	(gr_line
		(start 1.500124 -3.999992)
		(end 23.50008 -3.999992)
		(stroke
			(width 1.016)
			(type default)
		)
		(layer "In6.Cu")
	)
	(gr_line
		(start 23.50008 -525.999964)
		(end 1.500124 -525.999964)
		(stroke
			(width 1.016)
			(type default)
		)
		(layer "In6.Cu")
	)
	(gr_arc
		(start 23.50008 -3.999992)
		(mid 24.560648 -3.56069)
		(end 24.99995 -2.500122)
		(stroke
			(width 1.016)
			(type default)
		)
		(layer "In6.Cu")
	)
	(gr_line
		(start 24.99995 -528.500086)
		(end 24.99995 -527.500088)
		(stroke
			(width 1.016)
			(type default)
		)
		(layer "In6.Cu")
	)
	(gr_arc
		(start 24.99995 -528.500086)
		(mid 25.439426 -529.560658)
		(end 26.500074 -529.999956)
		(stroke
			(width 1.016)
			(type default)
		)
		(layer "In6.Cu")
	)
	(gr_arc
		(start 24.99995 -527.500088)
		(mid 24.560738 -526.439356)
		(end 23.50008 -525.999964)
		(stroke
			(width 1.016)
			(type default)
		)
		(layer "In6.Cu")
	)
	(gr_line
		(start 24.99995 -2.500122)
		(end 24.99995 -1.500124)
		(stroke
			(width 1.016)
			(type default)
		)
		(layer "In6.Cu")
	)
	(gr_arc
		(start 26.500074 0)
		(mid 25.439325 -0.439375)
		(end 24.99995 -1.500124)
		(stroke
			(width 1.016)
			(type default)
		)
		(layer "In6.Cu")
	)
	(gr_line
		(start 26.500074 0)
		(end 101.000052 0)
		(stroke
			(width 1.016)
			(type default)
		)
		(layer "In6.Cu")
	)
	(gr_line
		(start 101.000052 -529.999956)
		(end 26.500074 -529.999956)
		(stroke
			(width 1.016)
			(type default)
		)
		(layer "In6.Cu")
	)
	(gr_arc
		(start 101.000052 -529.999956)
		(mid 102.41428 -529.414185)
		(end 103.000048 -527.99996)
		(stroke
			(width 1.016)
			(type default)
		)
		(layer "In6.Cu")
	)
	(gr_arc
		(start 103.000048 -1.999996)
		(mid 102.414258 -0.585805)
		(end 101.000052 0)
		(stroke
			(width 1.016)
			(type default)
		)
		(layer "In6.Cu")
	)
	(gr_line
		(start 103.000048 -1.999996)
		(end 103.000048 -527.99996)
		(stroke
			(width 1.016)
			(type default)
		)
		(layer "In6.Cu")
	)
	(gr_line
		(start 0 -524.500094)
		(end 0 -5.500116)
		(stroke
			(width 0.05)
			(type default)
		)
		(layer "Edge.Cuts")
	)
	(gr_arc
		(start 0 -524.500094)
		(mid 0.439393 -525.560749)
		(end 1.500124 -525.999964)
		(stroke
			(width 0.05)
			(type default)
		)
		(layer "Edge.Cuts")
	)
	(gr_arc
		(start 1.500124 -3.999992)
		(mid 0.439376 -4.439368)
		(end 0 -5.500116)
		(stroke
			(width 0.05)
			(type default)
		)
		(layer "Edge.Cuts")
	)
	(gr_line
		(start 1.500124 -3.999992)
		(end 23.50008 -3.999992)
		(stroke
			(width 0.05)
			(type default)
		)
		(layer "Edge.Cuts")
	)
	(gr_line
		(start 23.50008 -525.999964)
		(end 1.500124 -525.999964)
		(stroke
			(width 0.05)
			(type default)
		)
		(layer "Edge.Cuts")
	)
	(gr_arc
		(start 23.50008 -3.999992)
		(mid 24.560648 -3.56069)
		(end 24.99995 -2.500122)
		(stroke
			(width 0.05)
			(type default)
		)
		(layer "Edge.Cuts")
	)
	(gr_line
		(start 24.99995 -528.500086)
		(end 24.99995 -527.500088)
		(stroke
			(width 0.05)
			(type default)
		)
		(layer "Edge.Cuts")
	)
	(gr_arc
		(start 24.99995 -528.500086)
		(mid 25.439338 -529.560746)
		(end 26.500074 -529.999956)
		(stroke
			(width 0.05)
			(type default)
		)
		(layer "Edge.Cuts")
	)
	(gr_arc
		(start 24.99995 -527.500088)
		(mid 24.560664 -526.43943)
		(end 23.50008 -525.999964)
		(stroke
			(width 0.05)
			(type default)
		)
		(layer "Edge.Cuts")
	)
	(gr_line
		(start 24.99995 -2.500122)
		(end 24.99995 -1.500124)
		(stroke
			(width 0.05)
			(type default)
		)
		(layer "Edge.Cuts")
	)
	(gr_arc
		(start 26.500074 0)
		(mid 25.439325 -0.439375)
		(end 24.99995 -1.500124)
		(stroke
			(width 0.05)
			(type default)
		)
		(layer "Edge.Cuts")
	)
	(gr_line
		(start 26.500074 0)
		(end 101.000052 0)
		(stroke
			(width 0.05)
			(type default)
		)
		(layer "Edge.Cuts")
	)
	(gr_arc
		(start 75.3999 -478.799906)
		(mid 78.000098 -481.400104)
		(end 80.600042 -478.799906)
		(stroke
			(width 0.05)
			(type default)
		)
		(layer "Edge.Cuts")
	)
	(gr_line
		(start 75.3999 -477.799908)
		(end 75.3999 -478.799906)
		(stroke
			(width 0.05)
			(type default)
		)
		(layer "Edge.Cuts")
	)
	(gr_line
		(start 80.600042 -478.799906)
		(end 80.600042 -477.799908)
		(stroke
			(width 0.05)
			(type default)
		)
		(layer "Edge.Cuts")
	)
	(gr_arc
		(start 80.600042 -477.799908)
		(mid 78.000098 -475.199964)
		(end 75.3999 -477.799908)
		(stroke
			(width 0.05)
			(type default)
		)
		(layer "Edge.Cuts")
	)
	(gr_line
		(start 101.000052 -529.999956)
		(end 26.500074 -529.999956)
		(stroke
			(width 0.05)
			(type default)
		)
		(layer "Edge.Cuts")
	)
	(gr_arc
		(start 101.000052 -529.999956)
		(mid 102.41428 -529.414185)
		(end 103.000048 -527.99996)
		(stroke
			(width 0.05)
			(type default)
		)
		(layer "Edge.Cuts")
	)
	(gr_arc
		(start 103.000048 -1.999996)
		(mid 102.414258 -0.585805)
		(end 101.000052 0)
		(stroke
			(width 0.05)
			(type default)
		)
		(layer "Edge.Cuts")
	)
	(gr_line
		(start 103.000048 -1.999996)
		(end 103.000048 -527.99996)
		(stroke
			(width 0.05)
			(type default)
		)
		(layer "Edge.Cuts")
	)
	(segment
		(start 20.388326 -178.204622)
		(end 21.471382 -178.204622)
		(width 0.1524)
		(layer "F.Cu")
		(net "N42263600")
	)
	(segment
		(start 18.33372 -175.44034)
		(end 19.314414 -175.44034)
		(width 0.1524)
		(layer "F.Cu")
		(net "N42263600")
	)
	(segment
		(start 21.471382 -178.204622)
		(end 21.471382 -178.79314)
		(width 0.1524)
		(layer "F.Cu")
		(net "N42263600")
	)
	(segment
		(start 22.190202 -179.51196)
		(end 22.190202 -179.957984)
		(width 0.1524)
		(layer "F.Cu")
		(net "N42263600")
	)
	(segment
		(start 23.114 -179.957984)
		(end 23.66391 -179.408074)
		(width 0.1524)
		(layer "F.Cu")
		(net "N42263600")
	)
	(segment
		(start 19.768312 -177.584608)
		(end 20.388326 -178.204622)
		(width 0.1524)
		(layer "F.Cu")
		(net "N42263600")
	)
	(segment
		(start 23.66391 -178.282092)
		(end 23.66391 -179.408074)
		(width 0.1524)
		(layer "F.Cu")
		(net "N42263600")
	)
	(segment
		(start 19.314414 -175.44034)
		(end 19.768312 -175.894238)
		(width 0.1524)
		(layer "F.Cu")
		(net "N42263600")
	)
	(segment
		(start 19.768312 -175.894238)
		(end 19.768312 -177.584608)
		(width 0.1524)
		(layer "F.Cu")
		(net "N42263600")
	)
	(segment
		(start 22.190202 -179.957984)
		(end 23.114 -179.957984)
		(width 0.1524)
		(layer "F.Cu")
		(net "N42263600")
	)
	(segment
		(start 21.471382 -178.79314)
		(end 22.190202 -179.51196)
		(width 0.1524)
		(layer "F.Cu")
		(net "N42263600")
	)
	(segment
		(start 23.58644 -178.204622)
		(end 23.66391 -178.282092)
		(width 0.1524)
		(layer "F.Cu")
		(net "N42263600")
	)
	(via
		(at 23.66391 -179.408074)
		(size 0.762)
		(drill 0.381)
		(layers "F.Cu" "B.Cu")
		(net "N42263600")
	)
	(via
		(at 11.491976 -327.423018)
		(size 0.508)
		(drill 0.254)
		(layers "F.Cu" "B.Cu")
		(net "GND40")
	)
	(segment
		(start 11.491976 -327.423018)
		(end 10.479786 -328.435208)
		(width 0.127)
		(layer "In2.Cu")
		(net "GND40")
	)
	(segment
		(start 7.772908 -328.435208)
		(end 7.538212 -328.669904)
		(width 0.127)
		(layer "In2.Cu")
		(net "GND40")
	)
	(segment
		(start 7.538212 -328.669904)
		(end 6.449822 -328.669904)
		(width 0.127)
		(layer "In2.Cu")
		(net "GND40")
	)
	(segment
		(start 10.479786 -328.435208)
		(end 7.772908 -328.435208)
		(width 0.127)
		(layer "In2.Cu")
		(net "GND40")
	)
	(via
		(at 11.534902 -326.065896)
		(size 0.508)
		(drill 0.254)
		(layers "F.Cu" "B.Cu")
		(net "GND41")
	)
	(segment
		(start 11.534902 -326.065896)
		(end 10.053828 -326.065896)
		(width 0.127)
		(layer "In2.Cu")
		(net "GND41")
	)
	(segment
		(start 10.053828 -326.065896)
		(end 8.449818 -327.669906)
		(width 0.127)
		(layer "In2.Cu")
		(net "GND41")
	)
	(via
		(at 11.491976 -331.669898)
		(size 0.508)
		(drill 0.254)
		(layers "F.Cu" "B.Cu")
		(net "GND39")
	)
	(segment
		(start 8.449818 -331.669898)
		(end 11.491976 -331.669898)
		(width 0.127)
		(layer "In2.Cu")
		(net "GND39")
	)
	(via
		(at 11.501374 -332.966822)
		(size 0.508)
		(drill 0.254)
		(layers "F.Cu" "B.Cu")
		(net "GND38")
	)
	(segment
		(start 11.501374 -332.966822)
		(end 10.798302 -333.669894)
		(width 0.127)
		(layer "In2.Cu")
		(net "GND38")
	)
	(segment
		(start 10.798302 -333.669894)
		(end 8.449818 -333.669894)
		(width 0.127)
		(layer "In2.Cu")
		(net "GND38")
	)
	(via
		(at 11.497818 -328.727562)
		(size 0.508)
		(drill 0.254)
		(layers "F.Cu" "B.Cu")
		(net "GND7")
	)
	(segment
		(start 11.497818 -328.727562)
		(end 11.326622 -328.898758)
		(width 0.127)
		(layer "In2.Cu")
		(net "GND7")
	)
	(segment
		(start 7.929626 -328.898758)
		(end 7.158482 -329.669902)
		(width 0.127)
		(layer "In2.Cu")
		(net "GND7")
	)
	(segment
		(start 11.326622 -328.898758)
		(end 7.929626 -328.898758)
		(width 0.127)
		(layer "In2.Cu")
		(net "GND7")
	)
	(segment
		(start 7.158482 -329.669902)
		(end 1.949958 -329.669902)
		(width 0.127)
		(layer "In2.Cu")
		(net "GND7")
	)
	(via
		(at 11.5189 -330.123038)
		(size 0.508)
		(drill 0.254)
		(layers "F.Cu" "B.Cu")
		(net "GND6")
	)
	(segment
		(start 5.371846 -331.37094)
		(end 4.670806 -330.6699)
		(width 0.127)
		(layer "In2.Cu")
		(net "GND6")
	)
	(segment
		(start 4.670806 -330.6699)
		(end 3.949954 -330.6699)
		(width 0.127)
		(layer "In2.Cu")
		(net "GND6")
	)
	(segment
		(start 11.5189 -330.123038)
		(end 10.704576 -330.937362)
		(width 0.127)
		(layer "In2.Cu")
		(net "GND6")
	)
	(segment
		(start 7.794244 -330.937362)
		(end 7.360666 -331.37094)
		(width 0.127)
		(layer "In2.Cu")
		(net "GND6")
	)
	(segment
		(start 10.704576 -330.937362)
		(end 7.794244 -330.937362)
		(width 0.127)
		(layer "In2.Cu")
		(net "GND6")
	)
	(segment
		(start 7.360666 -331.37094)
		(end 5.371846 -331.37094)
		(width 0.127)
		(layer "In2.Cu")
		(net "GND6")
	)
	(via
		(at 11.577574 -324.71868)
		(size 0.508)
		(drill 0.254)
		(layers "F.Cu" "B.Cu")
		(net "GND8")
	)
	(segment
		(start 11.577574 -324.71868)
		(end 7.883652 -324.71868)
		(width 0.127)
		(layer "In2.Cu")
		(net "GND8")
	)
	(segment
		(start 4.983226 -326.669908)
		(end 3.949954 -326.669908)
		(width 0.127)
		(layer "In2.Cu")
		(net "GND8")
	)
	(segment
		(start 7.883652 -324.71868)
		(end 6.727444 -325.874888)
		(width 0.127)
		(layer "In2.Cu")
		(net "GND8")
	)
	(segment
		(start 5.778246 -325.874888)
		(end 4.983226 -326.669908)
		(width 0.127)
		(layer "In2.Cu")
		(net "GND8")
	)
	(segment
		(start 6.727444 -325.874888)
		(end 5.778246 -325.874888)
		(width 0.127)
		(layer "In2.Cu")
		(net "GND8")
	)
	(segment
		(start 23.61692 -175.44034)
		(end 25.55113 -175.44034)
		(width 0.1524)
		(layer "F.Cu")
		(net "N42264085")
	)
	(segment
		(start 25.55113 -176.040542)
		(end 25.202134 -176.389538)
		(width 0.1524)
		(layer "F.Cu")
		(net "N42264085")
	)
	(segment
		(start 25.55113 -175.44034)
		(end 25.55113 -176.040542)
		(width 0.1524)
		(layer "F.Cu")
		(net "N42264085")
	)
	(segment
		(start 25.202134 -176.389538)
		(end 23.10257 -176.389538)
		(width 0.1524)
		(layer "F.Cu")
		(net "N42264085")
	)
	(segment
		(start 23.10257 -176.389538)
		(end 22.524974 -176.967134)
		(width 0.1524)
		(layer "F.Cu")
		(net "N42264085")
	)
	(segment
		(start 21.471382 -177.404522)
		(end 22.524974 -177.404522)
		(width 0.1524)
		(layer "F.Cu")
		(net "N42264085")
	)
	(segment
		(start 22.524974 -176.967134)
		(end 22.524974 -177.404522)
		(width 0.1524)
		(layer "F.Cu")
		(net "N42264085")
	)
	(via
		(at 25.55113 -175.44034)
		(size 0.762)
		(drill 0.381)
		(layers "F.Cu" "B.Cu")
		(net "N42264085")
	)
	(segment
		(start 38.066218 -186.371992)
		(end 43.011598 -191.317372)
		(width 0.4572)
		(layer "F.Cu")
		(net "PHLOSS")
	)
	(segment
		(start 41.93413 -196.459856)
		(end 41.93413 -199.525382)
		(width 0.4572)
		(layer "F.Cu")
		(net "PHLOSS")
	)
	(segment
		(start 29.365956 -178.75504)
		(end 36.28644 -178.75504)
		(width 0.4572)
		(layer "F.Cu")
		(net "PHLOSS")
	)
	(segment
		(start 29.131768 -215.593422)
		(end 29.131768 -200.497948)
		(width 0.4572)
		(layer "F.Cu")
		(net "PHLOSS")
	)
	(segment
		(start 28.706572 -179.414424)
		(end 29.365956 -178.75504)
		(width 0.4572)
		(layer "F.Cu")
		(net "PHLOSS")
	)
	(segment
		(start 40.447976 -201.011536)
		(end 38.367208 -201.011536)
		(width 0.4572)
		(layer "F.Cu")
		(net "PHLOSS")
	)
	(segment
		(start 29.245306 -215.70696)
		(end 29.131768 -215.593422)
		(width 0.4572)
		(layer "F.Cu")
		(net "PHLOSS")
	)
	(segment
		(start 43.011598 -191.317372)
		(end 43.011598 -195.382388)
		(width 0.4572)
		(layer "F.Cu")
		(net "PHLOSS")
	)
	(segment
		(start 36.28644 -178.75504)
		(end 38.066218 -180.534818)
		(width 0.4572)
		(layer "F.Cu")
		(net "PHLOSS")
	)
	(segment
		(start 37.73551 -200.379838)
		(end 34.428684 -200.379838)
		(width 0.4572)
		(layer "F.Cu")
		(net "PHLOSS")
	)
	(segment
		(start 34.428684 -200.379838)
		(end 33.218882 -199.170036)
		(width 0.4572)
		(layer "F.Cu")
		(net "PHLOSS")
	)
	(segment
		(start 41.93413 -199.525382)
		(end 40.447976 -201.011536)
		(width 0.4572)
		(layer "F.Cu")
		(net "PHLOSS")
	)
	(segment
		(start 29.131768 -200.497948)
		(end 30.45968 -199.170036)
		(width 0.4572)
		(layer "F.Cu")
		(net "PHLOSS")
	)
	(segment
		(start 33.218882 -199.170036)
		(end 30.45968 -199.170036)
		(width 0.4572)
		(layer "F.Cu")
		(net "PHLOSS")
	)
	(segment
		(start 43.011598 -195.382388)
		(end 41.93413 -196.459856)
		(width 0.4572)
		(layer "F.Cu")
		(net "PHLOSS")
	)
	(segment
		(start 23.999698 -177.404522)
		(end 24.462232 -176.941988)
		(width 0.4572)
		(layer "F.Cu")
		(net "PHLOSS")
	)
	(segment
		(start 38.066218 -180.534818)
		(end 38.066218 -186.371992)
		(width 0.4572)
		(layer "F.Cu")
		(net "PHLOSS")
	)
	(segment
		(start 23.58644 -177.404522)
		(end 23.999698 -177.404522)
		(width 0.4572)
		(layer "F.Cu")
		(net "PHLOSS")
	)
	(segment
		(start 38.367208 -201.011536)
		(end 37.73551 -200.379838)
		(width 0.4572)
		(layer "F.Cu")
		(net "PHLOSS")
	)
	(via
		(at 24.462232 -176.941988)
		(size 0.508)
		(drill 0.254)
		(layers "F.Cu" "B.Cu")
		(net "PHLOSS")
	)
	(via
		(at 29.245306 -215.70696)
		(size 0.508)
		(drill 0.254)
		(layers "F.Cu" "B.Cu")
		(net "PHLOSS")
	)
	(via
		(at 26.15184 -170.897042)
		(size 0.508)
		(drill 0.254)
		(layers "F.Cu" "B.Cu")
		(net "PHLOSS")
	)
	(via
		(at 28.706572 -179.414424)
		(size 0.508)
		(drill 0.254)
		(layers "F.Cu" "B.Cu")
		(net "PHLOSS")
	)
	(segment
		(start 36.76904 -109.533944)
		(end 31.695644 -109.533944)
		(width 0.4572)
		(layer "B.Cu")
		(net "PHLOSS")
	)
	(segment
		(start 26.15184 -114.39525)
		(end 29.777182 -110.769908)
		(width 0.4572)
		(layer "B.Cu")
		(net "PHLOSS")
	)
	(segment
		(start 38.255702 -461.102202)
		(end 38.255702 -446.648332)
		(width 0.4572)
		(layer "B.Cu")
		(net "PHLOSS")
	)
	(segment
		(start 34.428938 -374.621806)
		(end 33.080706 -375.970038)
		(width 0.4572)
		(layer "B.Cu")
		(net "PHLOSS")
	)
	(segment
		(start 28.706572 -179.414424)
		(end 26.234136 -176.941988)
		(width 0.4572)
		(layer "B.Cu")
		(net "PHLOSS")
	)
	(segment
		(start 37.605462 -247.548654)
		(end 37.605462 -276.382226)
		(width 0.4572)
		(layer "B.Cu")
		(net "PHLOSS")
	)
	(segment
		(start 29.285692 -21.196046)
		(end 27.285442 -21.196046)
		(width 0.4572)
		(layer "B.Cu")
		(net "PHLOSS")
	)
	(segment
		(start 37.62375 -233.485436)
		(end 39.778686 -235.640372)
		(width 0.4572)
		(layer "B.Cu")
		(net "PHLOSS")
	)
	(segment
		(start 32.965136 -287.56991)
		(end 30.45968 -287.56991)
		(width 0.4572)
		(layer "B.Cu")
		(net "PHLOSS")
	)
	(segment
		(start 45.12945 -245.598188)
		(end 39.555928 -245.598188)
		(width 0.4572)
		(layer "B.Cu")
		(net "PHLOSS")
	)
	(segment
		(start 30.45968 -287.56991)
		(end 27.635962 -290.393628)
		(width 0.4572)
		(layer "B.Cu")
		(net "PHLOSS")
	)
	(segment
		(start 29.672788 -233.485436)
		(end 37.62375 -233.485436)
		(width 0.4572)
		(layer "B.Cu")
		(net "PHLOSS")
	)
	(segment
		(start 36.23056 -444.62319)
		(end 34.242756 -444.62319)
		(width 0.4572)
		(layer "B.Cu")
		(net "PHLOSS")
	)
	(segment
		(start 33.722564 -463.071464)
		(end 36.28644 -463.071464)
		(width 0.4572)
		(layer "B.Cu")
		(net "PHLOSS")
	)
	(segment
		(start 32.508444 -355.891592)
		(end 37.281866 -355.891592)
		(width 0.4572)
		(layer "B.Cu")
		(net "PHLOSS")
	)
	(segment
		(start 27.635962 -351.01911)
		(end 32.508444 -355.891592)
		(width 0.4572)
		(layer "B.Cu")
		(net "PHLOSS")
	)
	(segment
		(start 27.635962 -290.393628)
		(end 27.635962 -351.01911)
		(width 0.4572)
		(layer "B.Cu")
		(net "PHLOSS")
	)
	(segment
		(start 37.346636 -108.956348)
		(end 36.76904 -109.533944)
		(width 0.4572)
		(layer "B.Cu")
		(net "PHLOSS")
	)
	(segment
		(start 26.15184 -170.897042)
		(end 26.15184 -114.39525)
		(width 0.4572)
		(layer "B.Cu")
		(net "PHLOSS")
	)
	(segment
		(start 26.068274 -22.413214)
		(end 26.068274 -84.5185)
		(width 0.4572)
		(layer "B.Cu")
		(net "PHLOSS")
	)
	(segment
		(start 34.242756 -444.62319)
		(end 27.870658 -438.251092)
		(width 0.4572)
		(layer "B.Cu")
		(net "PHLOSS")
	)
	(segment
		(start 33.080706 -375.970038)
		(end 30.45968 -375.970038)
		(width 0.4572)
		(layer "B.Cu")
		(net "PHLOSS")
	)
	(segment
		(start 37.995606 -373.11711)
		(end 36.49091 -374.621806)
		(width 0.4572)
		(layer "B.Cu")
		(net "PHLOSS")
	)
	(segment
		(start 44.460414 -235.640372)
		(end 46.002702 -237.18266)
		(width 0.4572)
		(layer "B.Cu")
		(net "PHLOSS")
	)
	(segment
		(start 37.281866 -355.891592)
		(end 37.995606 -356.605332)
		(width 0.4572)
		(layer "B.Cu")
		(net "PHLOSS")
	)
	(segment
		(start 37.700712 -289.795712)
		(end 36.826952 -288.921952)
		(width 0.4572)
		(layer "B.Cu")
		(net "PHLOSS")
	)
	(segment
		(start 38.255702 -446.648332)
		(end 36.23056 -444.62319)
		(width 0.4572)
		(layer "B.Cu")
		(net "PHLOSS")
	)
	(segment
		(start 32.424116 -464.369912)
		(end 33.722564 -463.071464)
		(width 0.4572)
		(layer "B.Cu")
		(net "PHLOSS")
	)
	(segment
		(start 35.590734 -91.291664)
		(end 37.346636 -93.047566)
		(width 0.4572)
		(layer "B.Cu")
		(net "PHLOSS")
	)
	(segment
		(start 37.346636 -93.047566)
		(end 37.346636 -108.956348)
		(width 0.4572)
		(layer "B.Cu")
		(net "PHLOSS")
	)
	(segment
		(start 27.870658 -438.251092)
		(end 27.870658 -377.807982)
		(width 0.4572)
		(layer "B.Cu")
		(net "PHLOSS")
	)
	(segment
		(start 27.285442 -21.196046)
		(end 26.068274 -22.413214)
		(width 0.4572)
		(layer "B.Cu")
		(net "PHLOSS")
	)
	(segment
		(start 46.002702 -237.18266)
		(end 46.002702 -244.724936)
		(width 0.4572)
		(layer "B.Cu")
		(net "PHLOSS")
	)
	(segment
		(start 29.777182 -110.769908)
		(end 30.45968 -110.769908)
		(width 0.4572)
		(layer "B.Cu")
		(net "PHLOSS")
	)
	(segment
		(start 30.45968 -464.369912)
		(end 32.424116 -464.369912)
		(width 0.4572)
		(layer "B.Cu")
		(net "PHLOSS")
	)
	(segment
		(start 29.245306 -233.057954)
		(end 29.672788 -233.485436)
		(width 0.4572)
		(layer "B.Cu")
		(net "PHLOSS")
	)
	(segment
		(start 30.45968 -22.370034)
		(end 29.285692 -21.196046)
		(width 0.4572)
		(layer "B.Cu")
		(net "PHLOSS")
	)
	(segment
		(start 31.695644 -109.533944)
		(end 30.45968 -110.769908)
		(width 0.4572)
		(layer "B.Cu")
		(net "PHLOSS")
	)
	(segment
		(start 29.245306 -215.70696)
		(end 29.245306 -233.057954)
		(width 0.4572)
		(layer "B.Cu")
		(net "PHLOSS")
	)
	(segment
		(start 36.49091 -374.621806)
		(end 34.428938 -374.621806)
		(width 0.4572)
		(layer "B.Cu")
		(net "PHLOSS")
	)
	(segment
		(start 37.995606 -356.605332)
		(end 37.995606 -373.11711)
		(width 0.4572)
		(layer "B.Cu")
		(net "PHLOSS")
	)
	(segment
		(start 36.826952 -288.921952)
		(end 34.317178 -288.921952)
		(width 0.4572)
		(layer "B.Cu")
		(net "PHLOSS")
	)
	(segment
		(start 39.778686 -235.640372)
		(end 44.460414 -235.640372)
		(width 0.4572)
		(layer "B.Cu")
		(net "PHLOSS")
	)
	(segment
		(start 37.605462 -276.382226)
		(end 42.605198 -281.381962)
		(width 0.4572)
		(layer "B.Cu")
		(net "PHLOSS")
	)
	(segment
		(start 46.002702 -244.724936)
		(end 45.12945 -245.598188)
		(width 0.4572)
		(layer "B.Cu")
		(net "PHLOSS")
	)
	(segment
		(start 26.234136 -176.941988)
		(end 24.462232 -176.941988)
		(width 0.4572)
		(layer "B.Cu")
		(net "PHLOSS")
	)
	(segment
		(start 27.870658 -377.807982)
		(end 29.708602 -375.970038)
		(width 0.4572)
		(layer "B.Cu")
		(net "PHLOSS")
	)
	(segment
		(start 26.068274 -84.5185)
		(end 32.841438 -91.291664)
		(width 0.4572)
		(layer "B.Cu")
		(net "PHLOSS")
	)
	(segment
		(start 32.841438 -91.291664)
		(end 35.590734 -91.291664)
		(width 0.4572)
		(layer "B.Cu")
		(net "PHLOSS")
	)
	(segment
		(start 39.555928 -245.598188)
		(end 37.605462 -247.548654)
		(width 0.4572)
		(layer "B.Cu")
		(net "PHLOSS")
	)
	(segment
		(start 36.28644 -463.071464)
		(end 38.255702 -461.102202)
		(width 0.4572)
		(layer "B.Cu")
		(net "PHLOSS")
	)
	(segment
		(start 42.605198 -281.381962)
		(end 42.605198 -287.565846)
		(width 0.4572)
		(layer "B.Cu")
		(net "PHLOSS")
	)
	(segment
		(start 42.605198 -287.565846)
		(end 40.375332 -289.795712)
		(width 0.4572)
		(layer "B.Cu")
		(net "PHLOSS")
	)
	(segment
		(start 29.708602 -375.970038)
		(end 30.45968 -375.970038)
		(width 0.4572)
		(layer "B.Cu")
		(net "PHLOSS")
	)
	(segment
		(start 34.317178 -288.921952)
		(end 32.965136 -287.56991)
		(width 0.4572)
		(layer "B.Cu")
		(net "PHLOSS")
	)
	(segment
		(start 40.375332 -289.795712)
		(end 37.700712 -289.795712)
		(width 0.4572)
		(layer "B.Cu")
		(net "PHLOSS")
	)
	(segment
		(start 26.15184 -175.25238)
		(end 26.15184 -170.897042)
		(width 0.4572)
		(layer "In5.Cu")
		(net "PHLOSS")
	)
	(segment
		(start 24.462232 -176.941988)
		(end 26.15184 -175.25238)
		(width 0.4572)
		(layer "In5.Cu")
		(net "PHLOSS")
	)
	(segment
		(start 20.415504 -452.257922)
		(end 20.415504 -451.004686)
		(width 0.5588)
		(layer "F.Cu")
		(net "P3V3_BUF")
	)
	(via
		(at 95.105474 -482.954838)
		(size 0.508)
		(drill 0.254)
		(layers "F.Cu" "B.Cu")
		(net "P3V3_BUF")
	)
	(via
		(at 20.415504 -451.004686)
		(size 0.508)
		(drill 0.254)
		(layers "F.Cu" "B.Cu")
		(net "P3V3_BUF")
	)
	(via
		(at 20.415504 -449.215764)
		(size 0.508)
		(drill 0.254)
		(layers "F.Cu" "B.Cu")
		(net "P3V3_BUF")
	)
	(via
		(at 20.415504 -450.112892)
		(size 0.508)
		(drill 0.254)
		(layers "F.Cu" "B.Cu")
		(net "P3V3_BUF")
	)
	(segment
		(start 98.418904 -347.029786)
		(end 98.418904 -348.04477)
		(width 0.3556)
		(layer "B.Cu")
		(net "P3V3_BUF")
	)
	(segment
		(start 97.82175 -83.951572)
		(end 97.827084 -83.956906)
		(width 0.508)
		(layer "B.Cu")
		(net "P3V3_BUF")
	)
	(segment
		(start 93.815916 -172.716444)
		(end 93.815916 -174.670974)
		(width 0.3556)
		(layer "B.Cu")
		(net "P3V3_BUF")
	)
	(segment
		(start 96.70034 -83.364324)
		(end 96.298004 -82.961988)
		(width 0.3556)
		(layer "B.Cu")
		(net "P3V3_BUF")
	)
	(segment
		(start 99.04476 -86.13013)
		(end 98.206052 -86.968838)
		(width 1.016)
		(layer "B.Cu")
		(net "P3V3_BUF")
	)
	(segment
		(start 97.630488 -221.290642)
		(end 97.630488 -281.466544)
		(width 1.016)
		(layer "B.Cu")
		(net "P3V3_BUF")
	)
	(segment
		(start 95.4659 -169.695114)
		(end 95.4659 -170.91787)
		(width 0.508)
		(layer "B.Cu")
		(net "P3V3_BUF")
	)
	(segment
		(start 95.428054 -180.590698)
		(end 99.013518 -184.176162)
		(width 1.016)
		(layer "B.Cu")
		(net "P3V3_BUF")
	)
	(segment
		(start 99.038664 -313.44362)
		(end 99.038664 -339.953346)
		(width 1.016)
		(layer "B.Cu")
		(net "P3V3_BUF")
	)
	(segment
		(start 94.503494 -473.554806)
		(end 98.556318 -469.501982)
		(width 1.016)
		(layer "B.Cu")
		(net "P3V3_BUF")
	)
	(segment
		(start 96.203008 -168.958006)
		(end 95.4659 -169.695114)
		(width 0.508)
		(layer "B.Cu")
		(net "P3V3_BUF")
	)
	(segment
		(start 99.038664 -339.953346)
		(end 99.41433 -340.329012)
		(width 1.016)
		(layer "B.Cu")
		(net "P3V3_BUF")
	)
	(segment
		(start 95.257874 -83.296252)
		(end 95.257874 -83.792314)
		(width 0.3556)
		(layer "B.Cu")
		(net "P3V3_BUF")
	)
	(segment
		(start 98.206052 -166.954962)
		(end 96.203008 -168.958006)
		(width 1.016)
		(layer "B.Cu")
		(net "P3V3_BUF")
	)
	(segment
		(start 96.75241 -83.951572)
		(end 96.70034 -83.899502)
		(width 0.3556)
		(layer "B.Cu")
		(net "P3V3_BUF")
	)
	(segment
		(start 95.428054 -176.283112)
		(end 95.428054 -180.590698)
		(width 1.016)
		(layer "B.Cu")
		(net "P3V3_BUF")
	)
	(segment
		(start 96.209358 -483.043992)
		(end 95.194628 -483.043992)
		(width 0.508)
		(layer "B.Cu")
		(net "P3V3_BUF")
	)
	(segment
		(start 95.194628 -483.043992)
		(end 95.105474 -482.954838)
		(width 0.508)
		(layer "B.Cu")
		(net "P3V3_BUF")
	)
	(segment
		(start 99.41433 -346.03436)
		(end 98.418904 -347.029786)
		(width 0.3556)
		(layer "B.Cu")
		(net "P3V3_BUF")
	)
	(segment
		(start 95.105474 -481.54971)
		(end 94.503494 -480.94773)
		(width 1.016)
		(layer "B.Cu")
		(net "P3V3_BUF")
	)
	(segment
		(start 93.044518 -296.461434)
		(end 93.044518 -307.449474)
		(width 1.016)
		(layer "B.Cu")
		(net "P3V3_BUF")
	)
	(segment
		(start 95.105474 -482.954838)
		(end 93.632782 -482.954838)
		(width 0.3556)
		(layer "B.Cu")
		(net "P3V3_BUF")
	)
	(segment
		(start 98.363786 -83.956906)
		(end 99.04476 -84.63788)
		(width 0.508)
		(layer "B.Cu")
		(net "P3V3_BUF")
	)
	(segment
		(start 98.206052 -86.968838)
		(end 98.206052 -166.954962)
		(width 1.016)
		(layer "B.Cu")
		(net "P3V3_BUF")
	)
	(segment
		(start 95.105474 -482.954838)
		(end 95.105474 -481.54971)
		(width 1.016)
		(layer "B.Cu")
		(net "P3V3_BUF")
	)
	(segment
		(start 99.013518 -190.816992)
		(end 100.942902 -192.746376)
		(width 1.016)
		(layer "B.Cu")
		(net "P3V3_BUF")
	)
	(segment
		(start 96.298004 -82.961988)
		(end 95.592138 -82.961988)
		(width 0.3556)
		(layer "B.Cu")
		(net "P3V3_BUF")
	)
	(segment
		(start 93.632782 -482.954838)
		(end 93.303598 -483.284022)
		(width 0.3556)
		(layer "B.Cu")
		(net "P3V3_BUF")
	)
	(segment
		(start 93.303598 -483.284022)
		(end 93.303598 -483.871524)
		(width 0.3556)
		(layer "B.Cu")
		(net "P3V3_BUF")
	)
	(segment
		(start 100.942902 -217.978228)
		(end 97.630488 -221.290642)
		(width 1.016)
		(layer "B.Cu")
		(net "P3V3_BUF")
	)
	(segment
		(start 93.815916 -171.430188)
		(end 93.815916 -172.716444)
		(width 0.3556)
		(layer "B.Cu")
		(net "P3V3_BUF")
	)
	(segment
		(start 93.044518 -307.449474)
		(end 99.038664 -313.44362)
		(width 1.016)
		(layer "B.Cu")
		(net "P3V3_BUF")
	)
	(segment
		(start 95.592138 -82.961988)
		(end 95.257874 -83.296252)
		(width 0.3556)
		(layer "B.Cu")
		(net "P3V3_BUF")
	)
	(segment
		(start 98.418904 -349.817182)
		(end 98.418904 -348.04477)
		(width 0.3556)
		(layer "B.Cu")
		(net "P3V3_BUF")
	)
	(segment
		(start 98.813112 -290.69284)
		(end 93.044518 -296.461434)
		(width 1.016)
		(layer "B.Cu")
		(net "P3V3_BUF")
	)
	(segment
		(start 97.630488 -281.466544)
		(end 98.813112 -282.649168)
		(width 1.016)
		(layer "B.Cu")
		(net "P3V3_BUF")
	)
	(segment
		(start 99.41433 -340.329012)
		(end 99.41433 -346.03436)
		(width 1.016)
		(layer "B.Cu")
		(net "P3V3_BUF")
	)
	(segment
		(start 96.75241 -83.951572)
		(end 97.82175 -83.951572)
		(width 0.508)
		(layer "B.Cu")
		(net "P3V3_BUF")
	)
	(segment
		(start 99.013518 -184.176162)
		(end 99.013518 -190.816992)
		(width 1.016)
		(layer "B.Cu")
		(net "P3V3_BUF")
	)
	(segment
		(start 93.897704 -174.752762)
		(end 95.428054 -176.283112)
		(width 1.016)
		(layer "B.Cu")
		(net "P3V3_BUF")
	)
	(segment
		(start 95.4659 -170.91787)
		(end 94.328234 -170.91787)
		(width 0.3556)
		(layer "B.Cu")
		(net "P3V3_BUF")
	)
	(segment
		(start 93.815916 -174.670974)
		(end 93.897704 -174.752762)
		(width 0.3556)
		(layer "B.Cu")
		(net "P3V3_BUF")
	)
	(segment
		(start 100.942902 -192.746376)
		(end 100.942902 -217.978228)
		(width 1.016)
		(layer "B.Cu")
		(net "P3V3_BUF")
	)
	(segment
		(start 98.813112 -282.649168)
		(end 98.813112 -290.69284)
		(width 1.016)
		(layer "B.Cu")
		(net "P3V3_BUF")
	)
	(segment
		(start 98.556318 -469.501982)
		(end 98.556318 -351.120964)
		(width 1.016)
		(layer "B.Cu")
		(net "P3V3_BUF")
	)
	(segment
		(start 99.04476 -84.63788)
		(end 99.04476 -86.13013)
		(width 1.016)
		(layer "B.Cu")
		(net "P3V3_BUF")
	)
	(segment
		(start 94.503494 -480.94773)
		(end 94.503494 -473.554806)
		(width 1.016)
		(layer "B.Cu")
		(net "P3V3_BUF")
	)
	(segment
		(start 96.70034 -83.899502)
		(end 96.70034 -83.364324)
		(width 0.3556)
		(layer "B.Cu")
		(net "P3V3_BUF")
	)
	(segment
		(start 98.556318 -351.120964)
		(end 98.556318 -349.954596)
		(width 0.3556)
		(layer "B.Cu")
		(net "P3V3_BUF")
	)
	(segment
		(start 94.328234 -170.91787)
		(end 93.815916 -171.430188)
		(width 0.3556)
		(layer "B.Cu")
		(net "P3V3_BUF")
	)
	(segment
		(start 97.827084 -83.956906)
		(end 98.363786 -83.956906)
		(width 0.508)
		(layer "B.Cu")
		(net "P3V3_BUF")
	)
	(segment
		(start 98.556318 -349.954596)
		(end 98.418904 -349.817182)
		(width 0.3556)
		(layer "B.Cu")
		(net "P3V3_BUF")
	)
	(segment
		(start 95.105474 -482.954838)
		(end 97.744026 -480.316286)
		(width 1.016)
		(layer "In5.Cu")
		(net "P3V3_BUF")
	)
	(segment
		(start 95.43034 -455.11339)
		(end 85.697314 -455.11339)
		(width 1.016)
		(layer "In5.Cu")
		(net "P3V3_BUF")
	)
	(segment
		(start 42.58056 -445.591946)
		(end 41.552876 -444.564262)
		(width 1.016)
		(layer "In5.Cu")
		(net "P3V3_BUF")
	)
	(segment
		(start 84.068666 -448.620896)
		(end 81.039716 -445.591946)
		(width 1.016)
		(layer "In5.Cu")
		(net "P3V3_BUF")
	)
	(segment
		(start 97.744026 -457.427076)
		(end 95.43034 -455.11339)
		(width 1.016)
		(layer "In5.Cu")
		(net "P3V3_BUF")
	)
	(segment
		(start 84.068666 -453.484742)
		(end 84.068666 -448.620896)
		(width 1.016)
		(layer "In5.Cu")
		(net "P3V3_BUF")
	)
	(segment
		(start 41.552876 -444.564262)
		(end 25.067006 -444.564262)
		(width 1.016)
		(layer "In5.Cu")
		(net "P3V3_BUF")
	)
	(segment
		(start 97.744026 -480.316286)
		(end 97.744026 -457.427076)
		(width 1.016)
		(layer "In5.Cu")
		(net "P3V3_BUF")
	)
	(segment
		(start 85.697314 -455.11339)
		(end 84.068666 -453.484742)
		(width 1.016)
		(layer "In5.Cu")
		(net "P3V3_BUF")
	)
	(segment
		(start 81.039716 -445.591946)
		(end 42.58056 -445.591946)
		(width 1.016)
		(layer "In5.Cu")
		(net "P3V3_BUF")
	)
	(segment
		(start 20.415504 -449.215764)
		(end 20.415504 -450.112892)
		(width 1.016)
		(layer "In5.Cu")
		(net "P3V3_BUF")
	)
	(segment
		(start 20.415504 -450.112892)
		(end 20.415504 -451.004686)
		(width 1.016)
		(layer "In5.Cu")
		(net "P3V3_BUF")
	)
	(segment
		(start 25.067006 -444.564262)
		(end 20.415504 -449.215764)
		(width 1.016)
		(layer "In5.Cu")
		(net "P3V3_BUF")
	)
	(segment
		(start 20.724114 -444.049658)
		(end 19.69643 -444.049658)
		(width 0.1524)
		(layer "F.Cu")
		(net "N42242336")
	)
	(segment
		(start 19.69643 -444.049658)
		(end 19.100292 -444.645796)
		(width 0.1524)
		(layer "F.Cu")
		(net "N42242336")
	)
	(segment
		(start 19.612356 -445.745108)
		(end 20.408646 -445.745108)
		(width 0.1524)
		(layer "F.Cu")
		(net "N42242336")
	)
	(segment
		(start 19.100292 -445.233044)
		(end 19.612356 -445.745108)
		(width 0.1524)
		(layer "F.Cu")
		(net "N42242336")
	)
	(segment
		(start 19.100292 -444.645796)
		(end 19.100292 -445.233044)
		(width 0.1524)
		(layer "F.Cu")
		(net "N42242336")
	)
	(via
		(at 19.100292 -444.645796)
		(size 0.762)
		(drill 0.381)
		(layers "F.Cu" "B.Cu")
		(net "N42242336")
	)
	(segment
		(start 23.820374 -450.373496)
		(end 23.374604 -450.819266)
		(width 0.1524)
		(layer "F.Cu")
		(net "N42242090")
	)
	(segment
		(start 21.685504 -451.756018)
		(end 22.334474 -451.107048)
		(width 0.1524)
		(layer "F.Cu")
		(net "N42242090")
	)
	(segment
		(start 22.899878 -445.745108)
		(end 23.820374 -446.665604)
		(width 0.1524)
		(layer "F.Cu")
		(net "N42242090")
	)
	(segment
		(start 23.820374 -446.665604)
		(end 23.820374 -450.373496)
		(width 0.1524)
		(layer "F.Cu")
		(net "N42242090")
	)
	(segment
		(start 21.441918 -445.745108)
		(end 22.510496 -445.745108)
		(width 0.1524)
		(layer "F.Cu")
		(net "N42242090")
	)
	(segment
		(start 23.086822 -451.107048)
		(end 23.374604 -450.819266)
		(width 0.1524)
		(layer "F.Cu")
		(net "N42242090")
	)
	(segment
		(start 22.510496 -445.745108)
		(end 22.899878 -445.745108)
		(width 0.1524)
		(layer "F.Cu")
		(net "N42242090")
	)
	(segment
		(start 22.334474 -451.107048)
		(end 23.086822 -451.107048)
		(width 0.1524)
		(layer "F.Cu")
		(net "N42242090")
	)
	(segment
		(start 21.685504 -452.257922)
		(end 21.685504 -451.756018)
		(width 0.1524)
		(layer "F.Cu")
		(net "N42242090")
	)
	(via
		(at 23.374604 -450.819266)
		(size 0.762)
		(drill 0.381)
		(layers "F.Cu" "B.Cu")
		(net "N42242090")
	)
	(segment
		(start 16.346424 -454.17105)
		(end 16.785082 -454.17105)
		(width 0.1524)
		(layer "F.Cu")
		(net "N42241895")
	)
	(segment
		(start 17.875504 -453.080628)
		(end 17.875504 -452.257922)
		(width 0.1524)
		(layer "F.Cu")
		(net "N42241895")
	)
	(segment
		(start 15.909798 -452.87819)
		(end 15.909798 -453.734424)
		(width 0.1524)
		(layer "F.Cu")
		(net "N42241895")
	)
	(segment
		(start 16.785082 -454.17105)
		(end 17.875504 -453.080628)
		(width 0.1524)
		(layer "F.Cu")
		(net "N42241895")
	)
	(segment
		(start 15.909798 -453.734424)
		(end 16.346424 -454.17105)
		(width 0.1524)
		(layer "F.Cu")
		(net "N42241895")
	)
	(via
		(at 16.346424 -454.17105)
		(size 0.762)
		(drill 0.381)
		(layers "F.Cu" "B.Cu")
		(net "N42241895")
	)
	(segment
		(start 6.448806 -227.670614)
		(end 11.630406 -227.670614)
		(width 0.1524)
		(layer "F.Cu")
		(net "TP_T1_BLAD4_EN")
	)
	(via
		(at 11.630406 -227.670614)
		(size 0.762)
		(drill 0.381)
		(layers "F.Cu" "B.Cu")
		(net "TP_T1_BLAD4_EN")
	)
	(segment
		(start 7.701534 -231.62514)
		(end 6.747002 -230.670608)
		(width 0.1524)
		(layer "F.Cu")
		(net "TP_T2_BLAD4_EN")
	)
	(segment
		(start 11.679174 -231.62514)
		(end 7.701534 -231.62514)
		(width 0.1524)
		(layer "F.Cu")
		(net "TP_T2_BLAD4_EN")
	)
	(segment
		(start 6.747002 -230.670608)
		(end 1.948942 -230.670608)
		(width 0.1524)
		(layer "F.Cu")
		(net "TP_T2_BLAD4_EN")
	)
	(via
		(at 11.679174 -231.62514)
		(size 0.762)
		(drill 0.381)
		(layers "F.Cu" "B.Cu")
		(net "TP_T2_BLAD4_EN")
	)
	(segment
		(start 12.21359 -233.677968)
		(end 7.87273 -233.677968)
		(width 0.1524)
		(layer "F.Cu")
		(net "TP_T2_BLAD2_EN")
	)
	(segment
		(start 7.87273 -233.677968)
		(end 6.865366 -232.670604)
		(width 0.1524)
		(layer "F.Cu")
		(net "TP_T2_BLAD2_EN")
	)
	(segment
		(start 6.865366 -232.670604)
		(end 1.948942 -232.670604)
		(width 0.1524)
		(layer "F.Cu")
		(net "TP_T2_BLAD2_EN")
	)
	(via
		(at 12.21359 -233.677968)
		(size 0.762)
		(drill 0.381)
		(layers "F.Cu" "B.Cu")
		(net "TP_T2_BLAD2_EN")
	)
	(segment
		(start 10.375138 -242.11153)
		(end 9.816084 -242.670584)
		(width 0.1524)
		(layer "F.Cu")
		(net "TP_T3_BLAD4_EN")
	)
	(segment
		(start 9.816084 -242.670584)
		(end 8.448802 -242.670584)
		(width 0.1524)
		(layer "F.Cu")
		(net "TP_T3_BLAD4_EN")
	)
	(segment
		(start 13.19784 -242.11153)
		(end 10.375138 -242.11153)
		(width 0.1524)
		(layer "F.Cu")
		(net "TP_T3_BLAD4_EN")
	)
	(via
		(at 13.19784 -242.11153)
		(size 0.762)
		(drill 0.381)
		(layers "F.Cu" "B.Cu")
		(net "TP_T3_BLAD4_EN")
	)
	(segment
		(start 9.890252 -244.67058)
		(end 8.448802 -244.67058)
		(width 0.1524)
		(layer "F.Cu")
		(net "TP_T3_BLAD2_EN")
	)
	(segment
		(start 12.15009 -243.864892)
		(end 10.69594 -243.864892)
		(width 0.1524)
		(layer "F.Cu")
		(net "TP_T3_BLAD2_EN")
	)
	(segment
		(start 10.69594 -243.864892)
		(end 9.890252 -244.67058)
		(width 0.1524)
		(layer "F.Cu")
		(net "TP_T3_BLAD2_EN")
	)
	(via
		(at 12.15009 -243.864892)
		(size 0.762)
		(drill 0.381)
		(layers "F.Cu" "B.Cu")
		(net "TP_T3_BLAD2_EN")
	)
	(segment
		(start 6.876034 -244.76329)
		(end 5.486146 -244.76329)
		(width 0.1524)
		(layer "F.Cu")
		(net "TP_T4_BLAD4_EN")
	)
	(segment
		(start 5.486146 -244.76329)
		(end 4.578858 -245.670578)
		(width 0.1524)
		(layer "F.Cu")
		(net "TP_T4_BLAD4_EN")
	)
	(segment
		(start 12.991846 -245.768622)
		(end 7.881366 -245.768622)
		(width 0.1524)
		(layer "F.Cu")
		(net "TP_T4_BLAD4_EN")
	)
	(segment
		(start 7.881366 -245.768622)
		(end 6.876034 -244.76329)
		(width 0.1524)
		(layer "F.Cu")
		(net "TP_T4_BLAD4_EN")
	)
	(segment
		(start 4.578858 -245.670578)
		(end 3.948938 -245.670578)
		(width 0.1524)
		(layer "F.Cu")
		(net "TP_T4_BLAD4_EN")
	)
	(via
		(at 12.991846 -245.768622)
		(size 0.762)
		(drill 0.381)
		(layers "F.Cu" "B.Cu")
		(net "TP_T4_BLAD4_EN")
	)
	(segment
		(start 8.137652 -247.801892)
		(end 6.940296 -246.604536)
		(width 0.1524)
		(layer "F.Cu")
		(net "TP_T4_BLAD2_EN")
	)
	(segment
		(start 11.965686 -247.801892)
		(end 8.137652 -247.801892)
		(width 0.1524)
		(layer "F.Cu")
		(net "TP_T4_BLAD2_EN")
	)
	(segment
		(start 5.678678 -246.604536)
		(end 4.61264 -247.670574)
		(width 0.1524)
		(layer "F.Cu")
		(net "TP_T4_BLAD2_EN")
	)
	(segment
		(start 4.61264 -247.670574)
		(end 3.948938 -247.670574)
		(width 0.1524)
		(layer "F.Cu")
		(net "TP_T4_BLAD2_EN")
	)
	(segment
		(start 6.940296 -246.604536)
		(end 5.678678 -246.604536)
		(width 0.1524)
		(layer "F.Cu")
		(net "TP_T4_BLAD2_EN")
	)
	(via
		(at 11.965686 -247.801892)
		(size 0.762)
		(drill 0.381)
		(layers "F.Cu" "B.Cu")
		(net "TP_T4_BLAD2_EN")
	)
	(segment
		(start 6.448806 -259.67055)
		(end 12.243562 -259.67055)
		(width 0.1524)
		(layer "F.Cu")
		(net "TP_T5_BLAD4_EN")
	)
	(via
		(at 12.243562 -259.67055)
		(size 0.762)
		(drill 0.381)
		(layers "F.Cu" "B.Cu")
		(net "TP_T5_BLAD4_EN")
	)
	(segment
		(start 8.449818 -269.669768)
		(end 12.058396 -269.669768)
		(width 0.1524)
		(layer "F.Cu")
		(net "TP_T5_BLAD2_EN")
	)
	(via
		(at 12.058396 -269.669768)
		(size 0.762)
		(drill 0.381)
		(layers "F.Cu" "B.Cu")
		(net "TP_T5_BLAD2_EN")
	)
	(segment
		(start 8.043926 -272.797778)
		(end 7.20979 -273.631914)
		(width 0.1524)
		(layer "F.Cu")
		(net "TP_T6_BLAD4_EN")
	)
	(segment
		(start 4.344416 -272.669762)
		(end 3.949954 -272.669762)
		(width 0.1524)
		(layer "F.Cu")
		(net "TP_T6_BLAD4_EN")
	)
	(segment
		(start 5.306568 -273.631914)
		(end 4.344416 -272.669762)
		(width 0.1524)
		(layer "F.Cu")
		(net "TP_T6_BLAD4_EN")
	)
	(segment
		(start 7.20979 -273.631914)
		(end 5.306568 -273.631914)
		(width 0.1524)
		(layer "F.Cu")
		(net "TP_T6_BLAD4_EN")
	)
	(segment
		(start 11.67892 -272.797778)
		(end 8.043926 -272.797778)
		(width 0.1524)
		(layer "F.Cu")
		(net "TP_T6_BLAD4_EN")
	)
	(segment
		(start 12.10691 -273.225768)
		(end 11.67892 -272.797778)
		(width 0.1524)
		(layer "F.Cu")
		(net "TP_T6_BLAD4_EN")
	)
	(via
		(at 12.10691 -273.225768)
		(size 0.762)
		(drill 0.381)
		(layers "F.Cu" "B.Cu")
		(net "TP_T6_BLAD4_EN")
	)
	(segment
		(start 11.122914 -274.722336)
		(end 8.001254 -274.722336)
		(width 0.1524)
		(layer "F.Cu")
		(net "TP_T6_BLAD2_EN")
	)
	(segment
		(start 8.001254 -274.722336)
		(end 7.20979 -275.5138)
		(width 0.1524)
		(layer "F.Cu")
		(net "TP_T6_BLAD2_EN")
	)
	(segment
		(start 4.291584 -274.669758)
		(end 3.949954 -274.669758)
		(width 0.1524)
		(layer "F.Cu")
		(net "TP_T6_BLAD2_EN")
	)
	(segment
		(start 12.149582 -275.749004)
		(end 11.122914 -274.722336)
		(width 0.1524)
		(layer "F.Cu")
		(net "TP_T6_BLAD2_EN")
	)
	(segment
		(start 7.20979 -275.5138)
		(end 5.135626 -275.5138)
		(width 0.1524)
		(layer "F.Cu")
		(net "TP_T6_BLAD2_EN")
	)
	(segment
		(start 5.135626 -275.5138)
		(end 4.291584 -274.669758)
		(width 0.1524)
		(layer "F.Cu")
		(net "TP_T6_BLAD2_EN")
	)
	(via
		(at 12.149582 -275.749004)
		(size 0.762)
		(drill 0.381)
		(layers "F.Cu" "B.Cu")
		(net "TP_T6_BLAD2_EN")
	)
	(segment
		(start 11.47826 -283.66974)
		(end 12.043156 -283.104844)
		(width 0.1524)
		(layer "F.Cu")
		(net "TP_T7_BLAD4_EN")
	)
	(segment
		(start 8.449818 -283.66974)
		(end 11.47826 -283.66974)
		(width 0.1524)
		(layer "F.Cu")
		(net "TP_T7_BLAD4_EN")
	)
	(via
		(at 12.043156 -283.104844)
		(size 0.762)
		(drill 0.381)
		(layers "F.Cu" "B.Cu")
		(net "TP_T7_BLAD4_EN")
	)
	(segment
		(start 11.188954 -285.669736)
		(end 11.957558 -284.901132)
		(width 0.1524)
		(layer "F.Cu")
		(net "TP_T7_BLAD2_EN")
	)
	(segment
		(start 8.449818 -285.669736)
		(end 11.188954 -285.669736)
		(width 0.1524)
		(layer "F.Cu")
		(net "TP_T7_BLAD2_EN")
	)
	(via
		(at 11.957558 -284.901132)
		(size 0.762)
		(drill 0.381)
		(layers "F.Cu" "B.Cu")
		(net "TP_T7_BLAD2_EN")
	)
	(segment
		(start 7.958836 -286.82569)
		(end 7.114794 -287.669732)
		(width 0.1524)
		(layer "F.Cu")
		(net "TP_T8_BLAD4_EN")
	)
	(segment
		(start 11.935968 -286.82569)
		(end 7.958836 -286.82569)
		(width 0.1524)
		(layer "F.Cu")
		(net "TP_T8_BLAD4_EN")
	)
	(segment
		(start 7.114794 -287.669732)
		(end 1.949958 -287.669732)
		(width 0.1524)
		(layer "F.Cu")
		(net "TP_T8_BLAD4_EN")
	)
	(via
		(at 11.935968 -286.82569)
		(size 0.762)
		(drill 0.381)
		(layers "F.Cu" "B.Cu")
		(net "TP_T8_BLAD4_EN")
	)
	(segment
		(start 12.07516 -288.73958)
		(end 7.990586 -288.73958)
		(width 0.1524)
		(layer "F.Cu")
		(net "TP_T8_BLAD2_EN")
	)
	(segment
		(start 7.060438 -289.669728)
		(end 1.949958 -289.669728)
		(width 0.1524)
		(layer "F.Cu")
		(net "TP_T8_BLAD2_EN")
	)
	(segment
		(start 7.990586 -288.73958)
		(end 7.060438 -289.669728)
		(width 0.1524)
		(layer "F.Cu")
		(net "TP_T8_BLAD2_EN")
	)
	(via
		(at 12.07516 -288.73958)
		(size 0.762)
		(drill 0.381)
		(layers "F.Cu" "B.Cu")
		(net "TP_T8_BLAD2_EN")
	)
	(segment
		(start 6.449822 -299.21962)
		(end 6.449822 -298.669964)
		(width 0.1524)
		(layer "F.Cu")
		(net "TP_T9_BLAD4_EN")
	)
	(segment
		(start 9.113266 -300.771052)
		(end 8.001254 -300.771052)
		(width 0.1524)
		(layer "F.Cu")
		(net "TP_T9_BLAD4_EN")
	)
	(segment
		(start 8.001254 -300.771052)
		(end 6.449822 -299.21962)
		(width 0.1524)
		(layer "F.Cu")
		(net "TP_T9_BLAD4_EN")
	)
	(segment
		(start 11.827764 -303.48555)
		(end 9.113266 -300.771052)
		(width 0.1524)
		(layer "F.Cu")
		(net "TP_T9_BLAD4_EN")
	)
	(via
		(at 11.827764 -303.48555)
		(size 0.762)
		(drill 0.381)
		(layers "F.Cu" "B.Cu")
		(net "TP_T9_BLAD4_EN")
	)
	(segment
		(start 8.052308 -302.7172)
		(end 6.449822 -301.114714)
		(width 0.1524)
		(layer "F.Cu")
		(net "TP_T9_BLAD2_EN")
	)
	(segment
		(start 11.63701 -305.397916)
		(end 8.956294 -302.7172)
		(width 0.1524)
		(layer "F.Cu")
		(net "TP_T9_BLAD2_EN")
	)
	(segment
		(start 8.956294 -302.7172)
		(end 8.052308 -302.7172)
		(width 0.1524)
		(layer "F.Cu")
		(net "TP_T9_BLAD2_EN")
	)
	(segment
		(start 6.449822 -301.114714)
		(end 6.449822 -300.66996)
		(width 0.1524)
		(layer "F.Cu")
		(net "TP_T9_BLAD2_EN")
	)
	(via
		(at 11.63701 -305.397916)
		(size 0.762)
		(drill 0.381)
		(layers "F.Cu" "B.Cu")
		(net "TP_T9_BLAD2_EN")
	)
	(segment
		(start 8.560562 -304.641758)
		(end 8.009636 -304.641758)
		(width 0.1524)
		(layer "F.Cu")
		(net "TP_T10_BLAD4_EN")
	)
	(segment
		(start 12.663424 -307.012594)
		(end 10.931398 -307.012594)
		(width 0.1524)
		(layer "F.Cu")
		(net "TP_T10_BLAD4_EN")
	)
	(segment
		(start 5.293868 -303.679352)
		(end 4.284472 -302.669956)
		(width 0.1524)
		(layer "F.Cu")
		(net "TP_T10_BLAD4_EN")
	)
	(segment
		(start 4.284472 -302.669956)
		(end 3.949954 -302.669956)
		(width 0.1524)
		(layer "F.Cu")
		(net "TP_T10_BLAD4_EN")
	)
	(segment
		(start 10.931398 -307.012594)
		(end 8.560562 -304.641758)
		(width 0.1524)
		(layer "F.Cu")
		(net "TP_T10_BLAD4_EN")
	)
	(segment
		(start 7.04723 -303.679352)
		(end 5.293868 -303.679352)
		(width 0.1524)
		(layer "F.Cu")
		(net "TP_T10_BLAD4_EN")
	)
	(segment
		(start 8.009636 -304.641758)
		(end 7.04723 -303.679352)
		(width 0.1524)
		(layer "F.Cu")
		(net "TP_T10_BLAD4_EN")
	)
	(via
		(at 12.663424 -307.012594)
		(size 0.762)
		(drill 0.381)
		(layers "F.Cu" "B.Cu")
		(net "TP_T10_BLAD4_EN")
	)
	(segment
		(start 7.132828 -305.710844)
		(end 5.33654 -305.710844)
		(width 0.1524)
		(layer "F.Cu")
		(net "TP_T10_BLAD2_EN")
	)
	(segment
		(start 4.295648 -304.669952)
		(end 3.949954 -304.669952)
		(width 0.1524)
		(layer "F.Cu")
		(net "TP_T10_BLAD2_EN")
	)
	(segment
		(start 8.095234 -306.67325)
		(end 7.132828 -305.710844)
		(width 0.1524)
		(layer "F.Cu")
		(net "TP_T10_BLAD2_EN")
	)
	(segment
		(start 11.059414 -308.830218)
		(end 8.902446 -306.67325)
		(width 0.1524)
		(layer "F.Cu")
		(net "TP_T10_BLAD2_EN")
	)
	(segment
		(start 11.76528 -308.830218)
		(end 11.059414 -308.830218)
		(width 0.1524)
		(layer "F.Cu")
		(net "TP_T10_BLAD2_EN")
	)
	(segment
		(start 8.902446 -306.67325)
		(end 8.095234 -306.67325)
		(width 0.1524)
		(layer "F.Cu")
		(net "TP_T10_BLAD2_EN")
	)
	(segment
		(start 5.33654 -305.710844)
		(end 4.295648 -304.669952)
		(width 0.1524)
		(layer "F.Cu")
		(net "TP_T10_BLAD2_EN")
	)
	(via
		(at 11.76528 -308.830218)
		(size 0.762)
		(drill 0.381)
		(layers "F.Cu" "B.Cu")
		(net "TP_T10_BLAD2_EN")
	)
	(segment
		(start 10.945622 -313.669934)
		(end 11.786616 -312.82894)
		(width 0.1524)
		(layer "F.Cu")
		(net "TP_T11_BLAD4_EN")
	)
	(segment
		(start 8.449818 -313.669934)
		(end 10.945622 -313.669934)
		(width 0.1524)
		(layer "F.Cu")
		(net "TP_T11_BLAD4_EN")
	)
	(via
		(at 11.786616 -312.82894)
		(size 0.762)
		(drill 0.381)
		(layers "F.Cu" "B.Cu")
		(net "TP_T11_BLAD4_EN")
	)
	(segment
		(start 8.449818 -315.66993)
		(end 11.612372 -315.66993)
		(width 0.1524)
		(layer "F.Cu")
		(net "TP_T11_BLAD2_EN")
	)
	(via
		(at 11.612372 -315.66993)
		(size 0.762)
		(drill 0.381)
		(layers "F.Cu" "B.Cu")
		(net "TP_T11_BLAD2_EN")
	)
	(segment
		(start 11.850624 -313.87669)
		(end 11.144758 -314.582556)
		(width 0.1524)
		(layer "F.Cu")
		(net "TP_T12_BLAD4_EN")
	)
	(segment
		(start 6.226556 -315.45911)
		(end 5.307076 -316.37859)
		(width 0.1524)
		(layer "F.Cu")
		(net "TP_T12_BLAD4_EN")
	)
	(segment
		(start 11.144758 -314.582556)
		(end 8.129778 -314.582556)
		(width 0.1524)
		(layer "F.Cu")
		(net "TP_T12_BLAD4_EN")
	)
	(segment
		(start 4.721606 -317.669926)
		(end 1.949958 -317.669926)
		(width 0.1524)
		(layer "F.Cu")
		(net "TP_T12_BLAD4_EN")
	)
	(segment
		(start 14.095984 -313.87669)
		(end 11.850624 -313.87669)
		(width 0.1524)
		(layer "F.Cu")
		(net "TP_T12_BLAD4_EN")
	)
	(segment
		(start 5.307076 -316.37859)
		(end 5.307076 -317.084456)
		(width 0.1524)
		(layer "F.Cu")
		(net "TP_T12_BLAD4_EN")
	)
	(segment
		(start 7.253224 -315.45911)
		(end 6.226556 -315.45911)
		(width 0.1524)
		(layer "F.Cu")
		(net "TP_T12_BLAD4_EN")
	)
	(segment
		(start 5.307076 -317.084456)
		(end 4.721606 -317.669926)
		(width 0.1524)
		(layer "F.Cu")
		(net "TP_T12_BLAD4_EN")
	)
	(segment
		(start 8.129778 -314.582556)
		(end 7.253224 -315.45911)
		(width 0.1524)
		(layer "F.Cu")
		(net "TP_T12_BLAD4_EN")
	)
	(via
		(at 14.095984 -313.87669)
		(size 0.762)
		(drill 0.381)
		(layers "F.Cu" "B.Cu")
		(net "TP_T12_BLAD4_EN")
	)
	(segment
		(start 5.41401 -318.174878)
		(end 5.41401 -318.77381)
		(width 0.1524)
		(layer "F.Cu")
		(net "TP_T12_BLAD2_EN")
	)
	(segment
		(start 4.517898 -319.669922)
		(end 1.949958 -319.669922)
		(width 0.1524)
		(layer "F.Cu")
		(net "TP_T12_BLAD2_EN")
	)
	(segment
		(start 13.646912 -316.40018)
		(end 11.358626 -316.40018)
		(width 0.1524)
		(layer "F.Cu")
		(net "TP_T12_BLAD2_EN")
	)
	(segment
		(start 6.953758 -317.469266)
		(end 6.119622 -317.469266)
		(width 0.1524)
		(layer "F.Cu")
		(net "TP_T12_BLAD2_EN")
	)
	(segment
		(start 11.037824 -316.720982)
		(end 7.702042 -316.720982)
		(width 0.1524)
		(layer "F.Cu")
		(net "TP_T12_BLAD2_EN")
	)
	(segment
		(start 11.358626 -316.40018)
		(end 11.037824 -316.720982)
		(width 0.1524)
		(layer "F.Cu")
		(net "TP_T12_BLAD2_EN")
	)
	(segment
		(start 7.702042 -316.720982)
		(end 6.953758 -317.469266)
		(width 0.1524)
		(layer "F.Cu")
		(net "TP_T12_BLAD2_EN")
	)
	(segment
		(start 13.882116 -316.164976)
		(end 13.646912 -316.40018)
		(width 0.1524)
		(layer "F.Cu")
		(net "TP_T12_BLAD2_EN")
	)
	(segment
		(start 6.119622 -317.469266)
		(end 5.41401 -318.174878)
		(width 0.1524)
		(layer "F.Cu")
		(net "TP_T12_BLAD2_EN")
	)
	(segment
		(start 5.41401 -318.77381)
		(end 4.517898 -319.669922)
		(width 0.1524)
		(layer "F.Cu")
		(net "TP_T12_BLAD2_EN")
	)
	(via
		(at 13.882116 -316.164976)
		(size 0.762)
		(drill 0.381)
		(layers "F.Cu" "B.Cu")
		(net "TP_T12_BLAD2_EN")
	)
	(via
		(at 91.469972 -485.752394)
		(size 0.6604)
		(drill 0.3302)
		(layers "F.Cu" "B.Cu")
		(net "B24_PSU_ALERT_N")
	)
	(segment
		(start 90.239596 -486.98277)
		(end 90.239596 -493.165384)
		(width 0.1524)
		(layer "B.Cu")
		(net "B24_PSU_ALERT_N")
	)
	(segment
		(start 90.239596 -493.165384)
		(end 89.44991 -493.95507)
		(width 0.1524)
		(layer "B.Cu")
		(net "B24_PSU_ALERT_N")
	)
	(segment
		(start 92.003626 -485.21874)
		(end 91.469972 -485.752394)
		(width 0.1524)
		(layer "B.Cu")
		(net "B24_PSU_ALERT_N")
	)
	(segment
		(start 91.469972 -485.752394)
		(end 90.239596 -486.98277)
		(width 0.1524)
		(layer "B.Cu")
		(net "B24_PSU_ALERT_N")
	)
	(segment
		(start 92.003626 -483.871524)
		(end 92.003626 -485.21874)
		(width 0.1524)
		(layer "B.Cu")
		(net "B24_PSU_ALERT_N")
	)
	(via
		(at 89.846404 -486.20807)
		(size 0.6604)
		(drill 0.3302)
		(layers "F.Cu" "B.Cu")
		(net "B23_PSU_ALERT_N")
	)
	(segment
		(start 90.703654 -483.871524)
		(end 90.703654 -485.35082)
		(width 0.1524)
		(layer "B.Cu")
		(net "B23_PSU_ALERT_N")
	)
	(segment
		(start 88.490044 -493.76203)
		(end 89.846404 -492.40567)
		(width 0.1524)
		(layer "B.Cu")
		(net "B23_PSU_ALERT_N")
	)
	(segment
		(start 89.846404 -492.40567)
		(end 89.846404 -486.20807)
		(width 0.1524)
		(layer "B.Cu")
		(net "B23_PSU_ALERT_N")
	)
	(segment
		(start 89.44991 -495.334798)
		(end 88.490044 -494.374932)
		(width 0.1524)
		(layer "B.Cu")
		(net "B23_PSU_ALERT_N")
	)
	(segment
		(start 88.490044 -494.374932)
		(end 88.490044 -493.76203)
		(width 0.1524)
		(layer "B.Cu")
		(net "B23_PSU_ALERT_N")
	)
	(segment
		(start 90.703654 -485.35082)
		(end 89.846404 -486.20807)
		(width 0.1524)
		(layer "B.Cu")
		(net "B23_PSU_ALERT_N")
	)
	(segment
		(start 89.44991 -496.49507)
		(end 89.44991 -495.334798)
		(width 0.1524)
		(layer "B.Cu")
		(net "B23_PSU_ALERT_N")
	)
	(via
		(at 88.16467 -476.298514)
		(size 0.6604)
		(drill 0.3302)
		(layers "F.Cu" "B.Cu")
		(net "B22_PSU_ALERT_N")
	)
	(segment
		(start 88.545924 -452.565262)
		(end 89.084658 -453.103996)
		(width 0.1524)
		(layer "B.Cu")
		(net "B22_PSU_ALERT_N")
	)
	(segment
		(start 88.722454 -476.856298)
		(end 88.722454 -480.810062)
		(width 0.1524)
		(layer "B.Cu")
		(net "B22_PSU_ALERT_N")
	)
	(segment
		(start 88.16467 -474.598238)
		(end 88.16467 -476.298514)
		(width 0.1524)
		(layer "B.Cu")
		(net "B22_PSU_ALERT_N")
	)
	(segment
		(start 89.44991 -450.92747)
		(end 88.545924 -451.831456)
		(width 0.1524)
		(layer "B.Cu")
		(net "B22_PSU_ALERT_N")
	)
	(segment
		(start 89.084658 -454.227946)
		(end 85.071966 -458.240638)
		(width 0.1524)
		(layer "B.Cu")
		(net "B22_PSU_ALERT_N")
	)
	(segment
		(start 85.071966 -471.505534)
		(end 88.16467 -474.598238)
		(width 0.1524)
		(layer "B.Cu")
		(net "B22_PSU_ALERT_N")
	)
	(segment
		(start 89.44991 -449.50507)
		(end 89.44991 -450.92747)
		(width 0.1524)
		(layer "B.Cu")
		(net "B22_PSU_ALERT_N")
	)
	(segment
		(start 88.16467 -476.298514)
		(end 88.722454 -476.856298)
		(width 0.1524)
		(layer "B.Cu")
		(net "B22_PSU_ALERT_N")
	)
	(segment
		(start 85.071966 -458.240638)
		(end 85.071966 -471.505534)
		(width 0.1524)
		(layer "B.Cu")
		(net "B22_PSU_ALERT_N")
	)
	(segment
		(start 88.722454 -480.810062)
		(end 89.403682 -481.49129)
		(width 0.1524)
		(layer "B.Cu")
		(net "B22_PSU_ALERT_N")
	)
	(segment
		(start 89.084658 -453.103996)
		(end 89.084658 -454.227946)
		(width 0.1524)
		(layer "B.Cu")
		(net "B22_PSU_ALERT_N")
	)
	(segment
		(start 89.403682 -481.49129)
		(end 89.403682 -483.871524)
		(width 0.1524)
		(layer "B.Cu")
		(net "B22_PSU_ALERT_N")
	)
	(segment
		(start 88.545924 -451.831456)
		(end 88.545924 -452.565262)
		(width 0.1524)
		(layer "B.Cu")
		(net "B22_PSU_ALERT_N")
	)
	(via
		(at 89.7255 -476.074232)
		(size 0.6604)
		(drill 0.3302)
		(layers "F.Cu" "B.Cu")
		(net "B21_PSU_ALERT_N")
	)
	(segment
		(start 89.7255 -475.656148)
		(end 89.7255 -476.074232)
		(width 0.1524)
		(layer "B.Cu")
		(net "B21_PSU_ALERT_N")
	)
	(segment
		(start 85.427566 -471.358214)
		(end 89.7255 -475.656148)
		(width 0.1524)
		(layer "B.Cu")
		(net "B21_PSU_ALERT_N")
	)
	(segment
		(start 89.44991 -452.04507)
		(end 89.44991 -454.448164)
		(width 0.1524)
		(layer "B.Cu")
		(net "B21_PSU_ALERT_N")
	)
	(segment
		(start 89.7255 -476.074232)
		(end 89.7255 -476.682562)
		(width 0.1524)
		(layer "B.Cu")
		(net "B21_PSU_ALERT_N")
	)
	(segment
		(start 85.427566 -458.470508)
		(end 85.427566 -471.358214)
		(width 0.1524)
		(layer "B.Cu")
		(net "B21_PSU_ALERT_N")
	)
	(segment
		(start 89.7255 -476.682562)
		(end 90.053668 -477.01073)
		(width 0.1524)
		(layer "B.Cu")
		(net "B21_PSU_ALERT_N")
	)
	(segment
		(start 89.44991 -454.448164)
		(end 85.427566 -458.470508)
		(width 0.1524)
		(layer "B.Cu")
		(net "B21_PSU_ALERT_N")
	)
	(segment
		(start 90.053668 -477.01073)
		(end 90.053668 -478.029524)
		(width 0.1524)
		(layer "B.Cu")
		(net "B21_PSU_ALERT_N")
	)
	(via
		(at 91.703906 -476.423736)
		(size 0.6604)
		(drill 0.3302)
		(layers "F.Cu" "B.Cu")
		(net "B20_PSU_ALERT_N")
	)
	(segment
		(start 88.60155 -407.922476)
		(end 88.982804 -408.30373)
		(width 0.1524)
		(layer "B.Cu")
		(net "B20_PSU_ALERT_N")
	)
	(segment
		(start 91.35364 -476.774002)
		(end 91.35364 -478.029524)
		(width 0.1524)
		(layer "B.Cu")
		(net "B20_PSU_ALERT_N")
	)
	(segment
		(start 97.05213 -417.665916)
		(end 97.05213 -469.186006)
		(width 0.1524)
		(layer "B.Cu")
		(net "B20_PSU_ALERT_N")
	)
	(segment
		(start 97.05213 -469.186006)
		(end 92.298012 -473.940124)
		(width 0.1524)
		(layer "B.Cu")
		(net "B20_PSU_ALERT_N")
	)
	(segment
		(start 88.982804 -409.59659)
		(end 97.05213 -417.665916)
		(width 0.1524)
		(layer "B.Cu")
		(net "B20_PSU_ALERT_N")
	)
	(segment
		(start 89.44991 -405.05507)
		(end 89.047574 -405.457406)
		(width 0.1524)
		(layer "B.Cu")
		(net "B20_PSU_ALERT_N")
	)
	(segment
		(start 89.047574 -405.457406)
		(end 89.047574 -406.67813)
		(width 0.1524)
		(layer "B.Cu")
		(net "B20_PSU_ALERT_N")
	)
	(segment
		(start 88.982804 -408.30373)
		(end 88.982804 -409.59659)
		(width 0.1524)
		(layer "B.Cu")
		(net "B20_PSU_ALERT_N")
	)
	(segment
		(start 89.047574 -406.67813)
		(end 88.60155 -407.124154)
		(width 0.1524)
		(layer "B.Cu")
		(net "B20_PSU_ALERT_N")
	)
	(segment
		(start 92.298012 -473.940124)
		(end 92.298012 -475.82963)
		(width 0.1524)
		(layer "B.Cu")
		(net "B20_PSU_ALERT_N")
	)
	(segment
		(start 88.60155 -407.124154)
		(end 88.60155 -407.922476)
		(width 0.1524)
		(layer "B.Cu")
		(net "B20_PSU_ALERT_N")
	)
	(segment
		(start 92.298012 -475.82963)
		(end 91.703906 -476.423736)
		(width 0.1524)
		(layer "B.Cu")
		(net "B20_PSU_ALERT_N")
	)
	(segment
		(start 91.703906 -476.423736)
		(end 91.35364 -476.774002)
		(width 0.1524)
		(layer "B.Cu")
		(net "B20_PSU_ALERT_N")
	)
	(via
		(at 92.944188 -475.101158)
		(size 0.6604)
		(drill 0.3302)
		(layers "F.Cu" "B.Cu")
		(net "B19_PSU_ALERT_N")
	)
	(segment
		(start 92.944188 -473.796868)
		(end 97.40773 -469.333326)
		(width 0.1524)
		(layer "B.Cu")
		(net "B19_PSU_ALERT_N")
	)
	(segment
		(start 97.40773 -417.518596)
		(end 89.34323 -409.454096)
		(width 0.1524)
		(layer "B.Cu")
		(net "B19_PSU_ALERT_N")
	)
	(segment
		(start 97.40773 -469.333326)
		(end 97.40773 -417.518596)
		(width 0.1524)
		(layer "B.Cu")
		(net "B19_PSU_ALERT_N")
	)
	(segment
		(start 89.34323 -407.70175)
		(end 89.44991 -407.59507)
		(width 0.1524)
		(layer "B.Cu")
		(net "B19_PSU_ALERT_N")
	)
	(segment
		(start 89.34323 -409.454096)
		(end 89.34323 -407.70175)
		(width 0.1524)
		(layer "B.Cu")
		(net "B19_PSU_ALERT_N")
	)
	(segment
		(start 92.653612 -478.029524)
		(end 92.653612 -475.391734)
		(width 0.1524)
		(layer "B.Cu")
		(net "B19_PSU_ALERT_N")
	)
	(segment
		(start 92.944188 -475.101158)
		(end 92.944188 -473.796868)
		(width 0.1524)
		(layer "B.Cu")
		(net "B19_PSU_ALERT_N")
	)
	(segment
		(start 92.653612 -475.391734)
		(end 92.944188 -475.101158)
		(width 0.1524)
		(layer "B.Cu")
		(net "B19_PSU_ALERT_N")
	)
	(via
		(at 96.616012 -349.815912)
		(size 0.6604)
		(drill 0.3302)
		(layers "F.Cu" "B.Cu")
		(net "B18_PSU_ALERT_N")
	)
	(segment
		(start 97.118932 -348.04477)
		(end 97.118932 -348.926658)
		(width 0.1524)
		(layer "B.Cu")
		(net "B18_PSU_ALERT_N")
	)
	(segment
		(start 97.118932 -348.926658)
		(end 96.616012 -349.429578)
		(width 0.1524)
		(layer "B.Cu")
		(net "B18_PSU_ALERT_N")
	)
	(segment
		(start 96.616012 -349.429578)
		(end 96.616012 -349.815912)
		(width 0.1524)
		(layer "B.Cu")
		(net "B18_PSU_ALERT_N")
	)
	(segment
		(start 89.266268 -359.596944)
		(end 89.266268 -360.421428)
		(width 0.1524)
		(layer "B.Cu")
		(net "B18_PSU_ALERT_N")
	)
	(segment
		(start 96.616012 -352.2472)
		(end 89.266268 -359.596944)
		(width 0.1524)
		(layer "B.Cu")
		(net "B18_PSU_ALERT_N")
	)
	(segment
		(start 96.616012 -349.815912)
		(end 96.616012 -352.2472)
		(width 0.1524)
		(layer "B.Cu")
		(net "B18_PSU_ALERT_N")
	)
	(segment
		(start 89.266268 -360.421428)
		(end 89.44991 -360.60507)
		(width 0.1524)
		(layer "B.Cu")
		(net "B18_PSU_ALERT_N")
	)
	(via
		(at 96.007936 -351.318068)
		(size 0.6604)
		(drill 0.3302)
		(layers "F.Cu" "B.Cu")
		(net "B17_PSU_ALERT_N")
	)
	(segment
		(start 89.44991 -362.02874)
		(end 89.44991 -363.14507)
		(width 0.1524)
		(layer "B.Cu")
		(net "B17_PSU_ALERT_N")
	)
	(segment
		(start 96.007936 -351.318068)
		(end 96.228154 -351.538286)
		(width 0.1524)
		(layer "B.Cu")
		(net "B17_PSU_ALERT_N")
	)
	(segment
		(start 88.53678 -359.777792)
		(end 88.53678 -361.11561)
		(width 0.1524)
		(layer "B.Cu")
		(net "B17_PSU_ALERT_N")
	)
	(segment
		(start 95.81896 -348.04477)
		(end 95.81896 -348.861126)
		(width 0.1524)
		(layer "B.Cu")
		(net "B17_PSU_ALERT_N")
	)
	(segment
		(start 88.53678 -361.11561)
		(end 89.44991 -362.02874)
		(width 0.1524)
		(layer "B.Cu")
		(net "B17_PSU_ALERT_N")
	)
	(segment
		(start 95.81896 -348.861126)
		(end 96.007936 -349.050102)
		(width 0.1524)
		(layer "B.Cu")
		(net "B17_PSU_ALERT_N")
	)
	(segment
		(start 96.228154 -352.086418)
		(end 88.53678 -359.777792)
		(width 0.1524)
		(layer "B.Cu")
		(net "B17_PSU_ALERT_N")
	)
	(segment
		(start 96.007936 -349.050102)
		(end 96.007936 -351.318068)
		(width 0.1524)
		(layer "B.Cu")
		(net "B17_PSU_ALERT_N")
	)
	(segment
		(start 96.228154 -351.538286)
		(end 96.228154 -352.086418)
		(width 0.1524)
		(layer "B.Cu")
		(net "B17_PSU_ALERT_N")
	)
	(via
		(at 94.868746 -340.54542)
		(size 0.6604)
		(drill 0.3302)
		(layers "F.Cu" "B.Cu")
		(net "B16_PSU_ALERT_N")
	)
	(segment
		(start 96.534732 -337.48853)
		(end 96.534732 -336.169762)
		(width 0.1524)
		(layer "B.Cu")
		(net "B16_PSU_ALERT_N")
	)
	(segment
		(start 89.345008 -319.872614)
		(end 88.415876 -318.943482)
		(width 0.1524)
		(layer "B.Cu")
		(net "B16_PSU_ALERT_N")
	)
	(segment
		(start 94.518988 -348.04477)
		(end 94.518988 -347.069918)
		(width 0.1524)
		(layer "B.Cu")
		(net "B16_PSU_ALERT_N")
	)
	(segment
		(start 89.345008 -321.40144)
		(end 89.345008 -319.872614)
		(width 0.1524)
		(layer "B.Cu")
		(net "B16_PSU_ALERT_N")
	)
	(segment
		(start 94.518988 -347.069918)
		(end 93.962474 -346.513404)
		(width 0.1524)
		(layer "B.Cu")
		(net "B16_PSU_ALERT_N")
	)
	(segment
		(start 90.602816 -322.659248)
		(end 89.345008 -321.40144)
		(width 0.1524)
		(layer "B.Cu")
		(net "B16_PSU_ALERT_N")
	)
	(segment
		(start 97.01784 -335.686654)
		(end 97.01784 -327.680828)
		(width 0.1524)
		(layer "B.Cu")
		(net "B16_PSU_ALERT_N")
	)
	(segment
		(start 97.01784 -327.680828)
		(end 91.99626 -322.659248)
		(width 0.1524)
		(layer "B.Cu")
		(net "B16_PSU_ALERT_N")
	)
	(segment
		(start 93.962474 -341.451692)
		(end 94.868746 -340.54542)
		(width 0.1524)
		(layer "B.Cu")
		(net "B16_PSU_ALERT_N")
	)
	(segment
		(start 94.868746 -340.54542)
		(end 95.678752 -339.735414)
		(width 0.1524)
		(layer "B.Cu")
		(net "B16_PSU_ALERT_N")
	)
	(segment
		(start 89.44991 -317.352426)
		(end 89.44991 -316.15507)
		(width 0.1524)
		(layer "B.Cu")
		(net "B16_PSU_ALERT_N")
	)
	(segment
		(start 88.415876 -318.38646)
		(end 89.44991 -317.352426)
		(width 0.1524)
		(layer "B.Cu")
		(net "B16_PSU_ALERT_N")
	)
	(segment
		(start 93.962474 -346.513404)
		(end 93.962474 -341.451692)
		(width 0.1524)
		(layer "B.Cu")
		(net "B16_PSU_ALERT_N")
	)
	(segment
		(start 88.415876 -318.943482)
		(end 88.415876 -318.38646)
		(width 0.1524)
		(layer "B.Cu")
		(net "B16_PSU_ALERT_N")
	)
	(segment
		(start 95.678752 -338.34451)
		(end 96.534732 -337.48853)
		(width 0.1524)
		(layer "B.Cu")
		(net "B16_PSU_ALERT_N")
	)
	(segment
		(start 95.678752 -339.735414)
		(end 95.678752 -338.34451)
		(width 0.1524)
		(layer "B.Cu")
		(net "B16_PSU_ALERT_N")
	)
	(segment
		(start 91.99626 -322.659248)
		(end 90.602816 -322.659248)
		(width 0.1524)
		(layer "B.Cu")
		(net "B16_PSU_ALERT_N")
	)
	(segment
		(start 96.534732 -336.169762)
		(end 97.01784 -335.686654)
		(width 0.1524)
		(layer "B.Cu")
		(net "B16_PSU_ALERT_N")
	)
	(via
		(at 96.241616 -338.796376)
		(size 0.6604)
		(drill 0.3302)
		(layers "F.Cu" "B.Cu")
		(net "B15_PSU_ALERT_N")
	)
	(segment
		(start 97.389442 -335.840578)
		(end 96.906334 -336.323686)
		(width 0.1524)
		(layer "B.Cu")
		(net "B15_PSU_ALERT_N")
	)
	(segment
		(start 89.44991 -318.69507)
		(end 89.772236 -319.017396)
		(width 0.1524)
		(layer "B.Cu")
		(net "B15_PSU_ALERT_N")
	)
	(segment
		(start 96.906334 -337.643978)
		(end 96.241616 -338.308696)
		(width 0.1524)
		(layer "B.Cu")
		(net "B15_PSU_ALERT_N")
	)
	(segment
		(start 96.241616 -338.308696)
		(end 96.241616 -338.796376)
		(width 0.1524)
		(layer "B.Cu")
		(net "B15_PSU_ALERT_N")
	)
	(segment
		(start 89.772236 -321.303142)
		(end 90.75674 -322.287646)
		(width 0.1524)
		(layer "B.Cu")
		(net "B15_PSU_ALERT_N")
	)
	(segment
		(start 92.150184 -322.287646)
		(end 97.389442 -327.526904)
		(width 0.1524)
		(layer "B.Cu")
		(net "B15_PSU_ALERT_N")
	)
	(segment
		(start 96.241616 -340.166198)
		(end 95.168974 -341.23884)
		(width 0.1524)
		(layer "B.Cu")
		(net "B15_PSU_ALERT_N")
	)
	(segment
		(start 89.772236 -319.017396)
		(end 89.772236 -321.303142)
		(width 0.1524)
		(layer "B.Cu")
		(net "B15_PSU_ALERT_N")
	)
	(segment
		(start 90.75674 -322.287646)
		(end 92.150184 -322.287646)
		(width 0.1524)
		(layer "B.Cu")
		(net "B15_PSU_ALERT_N")
	)
	(segment
		(start 96.241616 -338.796376)
		(end 96.241616 -340.166198)
		(width 0.1524)
		(layer "B.Cu")
		(net "B15_PSU_ALERT_N")
	)
	(segment
		(start 95.168974 -341.23884)
		(end 95.168974 -342.20277)
		(width 0.1524)
		(layer "B.Cu")
		(net "B15_PSU_ALERT_N")
	)
	(segment
		(start 96.906334 -336.323686)
		(end 96.906334 -337.643978)
		(width 0.1524)
		(layer "B.Cu")
		(net "B15_PSU_ALERT_N")
	)
	(segment
		(start 97.389442 -327.526904)
		(end 97.389442 -335.840578)
		(width 0.1524)
		(layer "B.Cu")
		(net "B15_PSU_ALERT_N")
	)
	(via
		(at 96.95815 -340.56066)
		(size 0.6604)
		(drill 0.3302)
		(layers "F.Cu" "B.Cu")
		(net "B14_PSU_ALERT_N")
	)
	(segment
		(start 88.434672 -274.46859)
		(end 89.187274 -275.221192)
		(width 0.1524)
		(layer "B.Cu")
		(net "B14_PSU_ALERT_N")
	)
	(segment
		(start 89.187274 -275.221192)
		(end 89.187274 -276.372828)
		(width 0.1524)
		(layer "B.Cu")
		(net "B14_PSU_ALERT_N")
	)
	(segment
		(start 89.44991 -272.970244)
		(end 88.434672 -273.985482)
		(width 0.1524)
		(layer "B.Cu")
		(net "B14_PSU_ALERT_N")
	)
	(segment
		(start 97.621344 -283.209238)
		(end 97.621344 -290.02736)
		(width 0.1524)
		(layer "B.Cu")
		(net "B14_PSU_ALERT_N")
	)
	(segment
		(start 91.973654 -277.561548)
		(end 97.621344 -283.209238)
		(width 0.1524)
		(layer "B.Cu")
		(net "B14_PSU_ALERT_N")
	)
	(segment
		(start 96.95815 -341.036402)
		(end 96.468946 -341.525606)
		(width 0.1524)
		(layer "B.Cu")
		(net "B14_PSU_ALERT_N")
	)
	(segment
		(start 97.751646 -314.104274)
		(end 97.751646 -337.41995)
		(width 0.1524)
		(layer "B.Cu")
		(net "B14_PSU_ALERT_N")
	)
	(segment
		(start 96.95815 -338.213446)
		(end 96.95815 -340.56066)
		(width 0.1524)
		(layer "B.Cu")
		(net "B14_PSU_ALERT_N")
	)
	(segment
		(start 96.95815 -340.56066)
		(end 96.95815 -341.036402)
		(width 0.1524)
		(layer "B.Cu")
		(net "B14_PSU_ALERT_N")
	)
	(segment
		(start 91.857322 -308.20995)
		(end 97.751646 -314.104274)
		(width 0.1524)
		(layer "B.Cu")
		(net "B14_PSU_ALERT_N")
	)
	(segment
		(start 89.187274 -276.372828)
		(end 90.375994 -277.561548)
		(width 0.1524)
		(layer "B.Cu")
		(net "B14_PSU_ALERT_N")
	)
	(segment
		(start 91.857322 -295.791382)
		(end 91.857322 -308.20995)
		(width 0.1524)
		(layer "B.Cu")
		(net "B14_PSU_ALERT_N")
	)
	(segment
		(start 88.434672 -273.985482)
		(end 88.434672 -274.46859)
		(width 0.1524)
		(layer "B.Cu")
		(net "B14_PSU_ALERT_N")
	)
	(segment
		(start 89.44991 -271.70507)
		(end 89.44991 -272.970244)
		(width 0.1524)
		(layer "B.Cu")
		(net "B14_PSU_ALERT_N")
	)
	(segment
		(start 97.621344 -290.02736)
		(end 91.857322 -295.791382)
		(width 0.1524)
		(layer "B.Cu")
		(net "B14_PSU_ALERT_N")
	)
	(segment
		(start 90.375994 -277.561548)
		(end 91.973654 -277.561548)
		(width 0.1524)
		(layer "B.Cu")
		(net "B14_PSU_ALERT_N")
	)
	(segment
		(start 97.751646 -337.41995)
		(end 96.95815 -338.213446)
		(width 0.1524)
		(layer "B.Cu")
		(net "B14_PSU_ALERT_N")
	)
	(segment
		(start 96.468946 -341.525606)
		(end 96.468946 -342.20277)
		(width 0.1524)
		(layer "B.Cu")
		(net "B14_PSU_ALERT_N")
	)
	(via
		(at 97.856294 -339.010244)
		(size 0.6604)
		(drill 0.3302)
		(layers "F.Cu" "B.Cu")
		(net "B13_PSU_ALERT_N")
	)
	(segment
		(start 98.00209 -283.051504)
		(end 92.131388 -277.180802)
		(width 0.1524)
		(layer "B.Cu")
		(net "B13_PSU_ALERT_N")
	)
	(segment
		(start 98.00209 -290.185094)
		(end 98.00209 -283.051504)
		(width 0.1524)
		(layer "B.Cu")
		(net "B13_PSU_ALERT_N")
	)
	(segment
		(start 97.856294 -339.010244)
		(end 97.856294 -339.726524)
		(width 0.1524)
		(layer "B.Cu")
		(net "B13_PSU_ALERT_N")
	)
	(segment
		(start 89.605104 -274.400264)
		(end 89.44991 -274.24507)
		(width 0.1524)
		(layer "B.Cu")
		(net "B13_PSU_ALERT_N")
	)
	(segment
		(start 97.768918 -341.46236)
		(end 97.768918 -342.20277)
		(width 0.1524)
		(layer "B.Cu")
		(net "B13_PSU_ALERT_N")
	)
	(segment
		(start 97.54616 -340.036658)
		(end 97.54616 -341.239602)
		(width 0.1524)
		(layer "B.Cu")
		(net "B13_PSU_ALERT_N")
	)
	(segment
		(start 97.856294 -337.921346)
		(end 98.132392 -337.645248)
		(width 0.1524)
		(layer "B.Cu")
		(net "B13_PSU_ALERT_N")
	)
	(segment
		(start 92.238068 -308.052216)
		(end 92.238068 -295.949116)
		(width 0.1524)
		(layer "B.Cu")
		(net "B13_PSU_ALERT_N")
	)
	(segment
		(start 90.533728 -277.180802)
		(end 89.605104 -276.252178)
		(width 0.1524)
		(layer "B.Cu")
		(net "B13_PSU_ALERT_N")
	)
	(segment
		(start 97.856294 -339.010244)
		(end 97.856294 -337.921346)
		(width 0.1524)
		(layer "B.Cu")
		(net "B13_PSU_ALERT_N")
	)
	(segment
		(start 92.238068 -295.949116)
		(end 98.00209 -290.185094)
		(width 0.1524)
		(layer "B.Cu")
		(net "B13_PSU_ALERT_N")
	)
	(segment
		(start 89.605104 -276.252178)
		(end 89.605104 -274.400264)
		(width 0.1524)
		(layer "B.Cu")
		(net "B13_PSU_ALERT_N")
	)
	(segment
		(start 97.54616 -341.239602)
		(end 97.768918 -341.46236)
		(width 0.1524)
		(layer "B.Cu")
		(net "B13_PSU_ALERT_N")
	)
	(segment
		(start 98.132392 -313.94654)
		(end 92.238068 -308.052216)
		(width 0.1524)
		(layer "B.Cu")
		(net "B13_PSU_ALERT_N")
	)
	(segment
		(start 98.132392 -337.645248)
		(end 98.132392 -313.94654)
		(width 0.1524)
		(layer "B.Cu")
		(net "B13_PSU_ALERT_N")
	)
	(segment
		(start 97.856294 -339.726524)
		(end 97.54616 -340.036658)
		(width 0.1524)
		(layer "B.Cu")
		(net "B13_PSU_ALERT_N")
	)
	(segment
		(start 92.131388 -277.180802)
		(end 90.533728 -277.180802)
		(width 0.1524)
		(layer "B.Cu")
		(net "B13_PSU_ALERT_N")
	)
	(via
		(at 93.64472 -176.445672)
		(size 0.6604)
		(drill 0.3302)
		(layers "F.Cu" "B.Cu")
		(net "B12_PSU_ALERT_N")
	)
	(segment
		(start 90.393774 -226.311206)
		(end 89.44991 -227.25507)
		(width 0.1524)
		(layer "B.Cu")
		(net "B12_PSU_ALERT_N")
	)
	(segment
		(start 98.129598 -191.200786)
		(end 99.978718 -193.049906)
		(width 0.1524)
		(layer "B.Cu")
		(net "B12_PSU_ALERT_N")
	)
	(segment
		(start 93.64472 -176.445672)
		(end 94.567502 -177.368454)
		(width 0.1524)
		(layer "B.Cu")
		(net "B12_PSU_ALERT_N")
	)
	(segment
		(start 94.567502 -181.145688)
		(end 98.129598 -184.707784)
		(width 0.1524)
		(layer "B.Cu")
		(net "B12_PSU_ALERT_N")
	)
	(segment
		(start 99.978718 -216.515188)
		(end 90.393774 -226.100132)
		(width 0.1524)
		(layer "B.Cu")
		(net "B12_PSU_ALERT_N")
	)
	(segment
		(start 98.129598 -184.707784)
		(end 98.129598 -191.200786)
		(width 0.1524)
		(layer "B.Cu")
		(net "B12_PSU_ALERT_N")
	)
	(segment
		(start 92.515944 -172.716444)
		(end 92.515944 -174.83455)
		(width 0.1524)
		(layer "B.Cu")
		(net "B12_PSU_ALERT_N")
	)
	(segment
		(start 93.64472 -175.963326)
		(end 93.64472 -176.445672)
		(width 0.1524)
		(layer "B.Cu")
		(net "B12_PSU_ALERT_N")
	)
	(segment
		(start 94.567502 -177.368454)
		(end 94.567502 -181.145688)
		(width 0.1524)
		(layer "B.Cu")
		(net "B12_PSU_ALERT_N")
	)
	(segment
		(start 90.393774 -226.100132)
		(end 90.393774 -226.311206)
		(width 0.1524)
		(layer "B.Cu")
		(net "B12_PSU_ALERT_N")
	)
	(segment
		(start 92.515944 -174.83455)
		(end 93.64472 -175.963326)
		(width 0.1524)
		(layer "B.Cu")
		(net "B12_PSU_ALERT_N")
	)
	(segment
		(start 99.978718 -193.049906)
		(end 99.978718 -216.515188)
		(width 0.1524)
		(layer "B.Cu")
		(net "B12_PSU_ALERT_N")
	)
	(via
		(at 92.082874 -176.381918)
		(size 0.6604)
		(drill 0.3302)
		(layers "F.Cu" "B.Cu")
		(net "B11_PSU_ALERT_N")
	)
	(segment
		(start 88.471502 -226.518724)
		(end 88.471502 -227.540566)
		(width 0.1524)
		(layer "B.Cu")
		(net "B11_PSU_ALERT_N")
	)
	(segment
		(start 91.702636 -176.00168)
		(end 91.702636 -174.507906)
		(width 0.1524)
		(layer "B.Cu")
		(net "B11_PSU_ALERT_N")
	)
	(segment
		(start 89.141554 -225.848672)
		(end 88.471502 -226.518724)
		(width 0.1524)
		(layer "B.Cu")
		(net "B11_PSU_ALERT_N")
	)
	(segment
		(start 92.67952 -176.381918)
		(end 94.145862 -177.84826)
		(width 0.1524)
		(layer "B.Cu")
		(net "B11_PSU_ALERT_N")
	)
	(segment
		(start 89.233248 -229.578408)
		(end 89.44991 -229.79507)
		(width 0.1524)
		(layer "B.Cu")
		(net "B11_PSU_ALERT_N")
	)
	(segment
		(start 99.623118 -193.197226)
		(end 99.623118 -216.367868)
		(width 0.1524)
		(layer "B.Cu")
		(net "B11_PSU_ALERT_N")
	)
	(segment
		(start 94.145862 -177.84826)
		(end 94.145862 -181.226968)
		(width 0.1524)
		(layer "B.Cu")
		(net "B11_PSU_ALERT_N")
	)
	(segment
		(start 97.773998 -191.348106)
		(end 99.623118 -193.197226)
		(width 0.1524)
		(layer "B.Cu")
		(net "B11_PSU_ALERT_N")
	)
	(segment
		(start 99.623118 -216.367868)
		(end 90.142314 -225.848672)
		(width 0.1524)
		(layer "B.Cu")
		(net "B11_PSU_ALERT_N")
	)
	(segment
		(start 91.215972 -174.021242)
		(end 91.215972 -172.716444)
		(width 0.1524)
		(layer "B.Cu")
		(net "B11_PSU_ALERT_N")
	)
	(segment
		(start 89.233248 -228.302312)
		(end 89.233248 -229.578408)
		(width 0.1524)
		(layer "B.Cu")
		(net "B11_PSU_ALERT_N")
	)
	(segment
		(start 97.773998 -184.855104)
		(end 97.773998 -191.348106)
		(width 0.1524)
		(layer "B.Cu")
		(net "B11_PSU_ALERT_N")
	)
	(segment
		(start 94.145862 -181.226968)
		(end 97.773998 -184.855104)
		(width 0.1524)
		(layer "B.Cu")
		(net "B11_PSU_ALERT_N")
	)
	(segment
		(start 92.082874 -176.381918)
		(end 92.67952 -176.381918)
		(width 0.1524)
		(layer "B.Cu")
		(net "B11_PSU_ALERT_N")
	)
	(segment
		(start 90.142314 -225.848672)
		(end 89.141554 -225.848672)
		(width 0.1524)
		(layer "B.Cu")
		(net "B11_PSU_ALERT_N")
	)
	(segment
		(start 92.082874 -176.381918)
		(end 91.702636 -176.00168)
		(width 0.1524)
		(layer "B.Cu")
		(net "B11_PSU_ALERT_N")
	)
	(segment
		(start 91.702636 -174.507906)
		(end 91.215972 -174.021242)
		(width 0.1524)
		(layer "B.Cu")
		(net "B11_PSU_ALERT_N")
	)
	(segment
		(start 88.471502 -227.540566)
		(end 89.233248 -228.302312)
		(width 0.1524)
		(layer "B.Cu")
		(net "B11_PSU_ALERT_N")
	)
	(via
		(at 89.498932 -177.384202)
		(size 0.6604)
		(drill 0.3302)
		(layers "F.Cu" "B.Cu")
		(net "B10_PSU_ALERT_N")
	)
	(segment
		(start 89.087452 -177.795682)
		(end 89.087452 -182.442358)
		(width 0.1524)
		(layer "B.Cu")
		(net "B10_PSU_ALERT_N")
	)
	(segment
		(start 89.916 -172.716444)
		(end 89.916 -176.967134)
		(width 0.1524)
		(layer "B.Cu")
		(net "B10_PSU_ALERT_N")
	)
	(segment
		(start 89.498932 -177.384202)
		(end 89.087452 -177.795682)
		(width 0.1524)
		(layer "B.Cu")
		(net "B10_PSU_ALERT_N")
	)
	(segment
		(start 89.916 -176.967134)
		(end 89.498932 -177.384202)
		(width 0.1524)
		(layer "B.Cu")
		(net "B10_PSU_ALERT_N")
	)
	(segment
		(start 89.087452 -182.442358)
		(end 89.450164 -182.80507)
		(width 0.1524)
		(layer "B.Cu")
		(net "B10_PSU_ALERT_N")
	)
	(via
		(at 88.195658 -176.295812)
		(size 0.6604)
		(drill 0.3302)
		(layers "F.Cu" "B.Cu")
		(net "B9_PSU_ALERT_N")
	)
	(segment
		(start 88.195658 -176.295812)
		(end 88.195658 -182.88)
		(width 0.1524)
		(layer "B.Cu")
		(net "B9_PSU_ALERT_N")
	)
	(segment
		(start 90.565986 -168.55694)
		(end 90.565986 -166.874444)
		(width 0.1524)
		(layer "B.Cu")
		(net "B9_PSU_ALERT_N")
	)
	(segment
		(start 88.195658 -182.88)
		(end 89.450164 -184.134506)
		(width 0.1524)
		(layer "B.Cu")
		(net "B9_PSU_ALERT_N")
	)
	(segment
		(start 88.81872 -175.67275)
		(end 88.81872 -170.304206)
		(width 0.1524)
		(layer "B.Cu")
		(net "B9_PSU_ALERT_N")
	)
	(segment
		(start 88.195658 -176.295812)
		(end 88.81872 -175.67275)
		(width 0.1524)
		(layer "B.Cu")
		(net "B9_PSU_ALERT_N")
	)
	(segment
		(start 88.81872 -170.304206)
		(end 90.565986 -168.55694)
		(width 0.1524)
		(layer "B.Cu")
		(net "B9_PSU_ALERT_N")
	)
	(segment
		(start 89.450164 -184.134506)
		(end 89.450164 -185.34507)
		(width 0.1524)
		(layer "B.Cu")
		(net "B9_PSU_ALERT_N")
	)
	(via
		(at 91.163394 -165.23462)
		(size 0.6604)
		(drill 0.3302)
		(layers "F.Cu" "B.Cu")
		(net "B8_PSU_ALERT_N")
	)
	(segment
		(start 87.162132 -141.896084)
		(end 89.450164 -139.608052)
		(width 0.1524)
		(layer "B.Cu")
		(net "B8_PSU_ALERT_N")
	)
	(segment
		(start 91.163394 -165.23462)
		(end 90.501724 -164.57295)
		(width 0.1524)
		(layer "B.Cu")
		(net "B8_PSU_ALERT_N")
	)
	(segment
		(start 84.96935 -153.990548)
		(end 82.107278 -151.128476)
		(width 0.1524)
		(layer "B.Cu")
		(net "B8_PSU_ALERT_N")
	)
	(segment
		(start 82.107278 -151.128476)
		(end 82.107278 -147.786344)
		(width 0.1524)
		(layer "B.Cu")
		(net "B8_PSU_ALERT_N")
	)
	(segment
		(start 87.162132 -142.73149)
		(end 87.162132 -141.896084)
		(width 0.1524)
		(layer "B.Cu")
		(net "B8_PSU_ALERT_N")
	)
	(segment
		(start 82.107278 -147.786344)
		(end 87.162132 -142.73149)
		(width 0.1524)
		(layer "B.Cu")
		(net "B8_PSU_ALERT_N")
	)
	(segment
		(start 91.865958 -166.874444)
		(end 91.865958 -165.937184)
		(width 0.1524)
		(layer "B.Cu")
		(net "B8_PSU_ALERT_N")
	)
	(segment
		(start 89.450164 -139.608052)
		(end 89.450164 -138.35507)
		(width 0.1524)
		(layer "B.Cu")
		(net "B8_PSU_ALERT_N")
	)
	(segment
		(start 84.96935 -160.293812)
		(end 84.96935 -153.990548)
		(width 0.1524)
		(layer "B.Cu")
		(net "B8_PSU_ALERT_N")
	)
	(segment
		(start 90.501724 -164.57295)
		(end 89.248488 -164.57295)
		(width 0.1524)
		(layer "B.Cu")
		(net "B8_PSU_ALERT_N")
	)
	(segment
		(start 89.248488 -164.57295)
		(end 84.96935 -160.293812)
		(width 0.1524)
		(layer "B.Cu")
		(net "B8_PSU_ALERT_N")
	)
	(segment
		(start 91.865958 -165.937184)
		(end 91.163394 -165.23462)
		(width 0.1524)
		(layer "B.Cu")
		(net "B8_PSU_ALERT_N")
	)
	(via
		(at 92.545662 -165.230556)
		(size 0.6604)
		(drill 0.3302)
		(layers "F.Cu" "B.Cu")
		(net "B7_PSU_ALERT_N")
	)
	(segment
		(start 91.17711 -163.862004)
		(end 89.278968 -163.862004)
		(width 0.1524)
		(layer "B.Cu")
		(net "B7_PSU_ALERT_N")
	)
	(segment
		(start 88.760046 -142.964662)
		(end 89.450164 -142.274544)
		(width 0.1524)
		(layer "B.Cu")
		(net "B7_PSU_ALERT_N")
	)
	(segment
		(start 92.545662 -165.230556)
		(end 92.545662 -165.424358)
		(width 0.1524)
		(layer "B.Cu")
		(net "B7_PSU_ALERT_N")
	)
	(segment
		(start 82.50809 -147.95246)
		(end 87.495888 -142.964662)
		(width 0.1524)
		(layer "B.Cu")
		(net "B7_PSU_ALERT_N")
	)
	(segment
		(start 92.545662 -165.424358)
		(end 93.16593 -166.044626)
		(width 0.1524)
		(layer "B.Cu")
		(net "B7_PSU_ALERT_N")
	)
	(segment
		(start 89.450164 -142.274544)
		(end 89.450164 -140.89507)
		(width 0.1524)
		(layer "B.Cu")
		(net "B7_PSU_ALERT_N")
	)
	(segment
		(start 93.16593 -166.044626)
		(end 93.16593 -166.874444)
		(width 0.1524)
		(layer "B.Cu")
		(net "B7_PSU_ALERT_N")
	)
	(segment
		(start 87.495888 -142.964662)
		(end 88.760046 -142.964662)
		(width 0.1524)
		(layer "B.Cu")
		(net "B7_PSU_ALERT_N")
	)
	(segment
		(start 85.370162 -159.953198)
		(end 85.370162 -153.824432)
		(width 0.1524)
		(layer "B.Cu")
		(net "B7_PSU_ALERT_N")
	)
	(segment
		(start 92.545662 -165.230556)
		(end 91.17711 -163.862004)
		(width 0.1524)
		(layer "B.Cu")
		(net "B7_PSU_ALERT_N")
	)
	(segment
		(start 82.50809 -150.96236)
		(end 82.50809 -147.95246)
		(width 0.1524)
		(layer "B.Cu")
		(net "B7_PSU_ALERT_N")
	)
	(segment
		(start 89.278968 -163.862004)
		(end 85.370162 -159.953198)
		(width 0.1524)
		(layer "B.Cu")
		(net "B7_PSU_ALERT_N")
	)
	(segment
		(start 85.370162 -153.824432)
		(end 82.50809 -150.96236)
		(width 0.1524)
		(layer "B.Cu")
		(net "B7_PSU_ALERT_N")
	)
	(via
		(at 93.237304 -86.3854)
		(size 0.6604)
		(drill 0.3302)
		(layers "F.Cu" "B.Cu")
		(net "B6_PSU_ALERT_N")
	)
	(segment
		(start 93.237304 -86.3854)
		(end 93.237304 -87.228934)
		(width 0.1524)
		(layer "B.Cu")
		(net "B6_PSU_ALERT_N")
	)
	(segment
		(start 89.595452 -90.870786)
		(end 89.595452 -93.759528)
		(width 0.1524)
		(layer "B.Cu")
		(net "B6_PSU_ALERT_N")
	)
	(segment
		(start 89.595452 -93.759528)
		(end 89.44991 -93.90507)
		(width 0.1524)
		(layer "B.Cu")
		(net "B6_PSU_ALERT_N")
	)
	(segment
		(start 93.237304 -86.3854)
		(end 93.237304 -85.303868)
		(width 0.1524)
		(layer "B.Cu")
		(net "B6_PSU_ALERT_N")
	)
	(segment
		(start 93.237304 -87.228934)
		(end 89.595452 -90.870786)
		(width 0.1524)
		(layer "B.Cu")
		(net "B6_PSU_ALERT_N")
	)
	(segment
		(start 93.237304 -85.303868)
		(end 93.957902 -84.58327)
		(width 0.1524)
		(layer "B.Cu")
		(net "B6_PSU_ALERT_N")
	)
	(segment
		(start 93.957902 -84.58327)
		(end 93.957902 -83.792314)
		(width 0.1524)
		(layer "B.Cu")
		(net "B6_PSU_ALERT_N")
	)
	(via
		(at 91.575382 -86.13013)
		(size 0.6604)
		(drill 0.3302)
		(layers "F.Cu" "B.Cu")
		(net "B5_PSU_ALERT_N")
	)
	(segment
		(start 88.508586 -93.09227)
		(end 88.508586 -94.150942)
		(width 0.1524)
		(layer "B.Cu")
		(net "B5_PSU_ALERT_N")
	)
	(segment
		(start 91.575382 -85.69198)
		(end 92.65793 -84.609432)
		(width 0.1524)
		(layer "B.Cu")
		(net "B5_PSU_ALERT_N")
	)
	(segment
		(start 89.44991 -95.092266)
		(end 89.44991 -96.44507)
		(width 0.1524)
		(layer "B.Cu")
		(net "B5_PSU_ALERT_N")
	)
	(segment
		(start 92.154248 -86.708996)
		(end 92.154248 -87.483188)
		(width 0.1524)
		(layer "B.Cu")
		(net "B5_PSU_ALERT_N")
	)
	(segment
		(start 89.177622 -90.459814)
		(end 89.177622 -92.423234)
		(width 0.1524)
		(layer "B.Cu")
		(net "B5_PSU_ALERT_N")
	)
	(segment
		(start 92.65793 -84.609432)
		(end 92.65793 -83.792314)
		(width 0.1524)
		(layer "B.Cu")
		(net "B5_PSU_ALERT_N")
	)
	(segment
		(start 91.575382 -86.13013)
		(end 92.154248 -86.708996)
		(width 0.1524)
		(layer "B.Cu")
		(net "B5_PSU_ALERT_N")
	)
	(segment
		(start 89.177622 -92.423234)
		(end 88.508586 -93.09227)
		(width 0.1524)
		(layer "B.Cu")
		(net "B5_PSU_ALERT_N")
	)
	(segment
		(start 88.508586 -94.150942)
		(end 89.44991 -95.092266)
		(width 0.1524)
		(layer "B.Cu")
		(net "B5_PSU_ALERT_N")
	)
	(segment
		(start 91.575382 -86.13013)
		(end 91.575382 -85.69198)
		(width 0.1524)
		(layer "B.Cu")
		(net "B5_PSU_ALERT_N")
	)
	(segment
		(start 92.154248 -87.483188)
		(end 89.177622 -90.459814)
		(width 0.1524)
		(layer "B.Cu")
		(net "B5_PSU_ALERT_N")
	)
	(via
		(at 90.635074 -76.188824)
		(size 0.6604)
		(drill 0.3302)
		(layers "F.Cu" "B.Cu")
		(net "B4_PSU_ALERT_N")
	)
	(segment
		(start 89.075768 -53.95849)
		(end 85.322664 -57.711594)
		(width 0.1524)
		(layer "B.Cu")
		(net "B4_PSU_ALERT_N")
	)
	(segment
		(start 89.44991 -50.816002)
		(end 88.638888 -51.627024)
		(width 0.1524)
		(layer "B.Cu")
		(net "B4_PSU_ALERT_N")
	)
	(segment
		(start 89.075768 -52.95519)
		(end 89.075768 -53.95849)
		(width 0.1524)
		(layer "B.Cu")
		(net "B4_PSU_ALERT_N")
	)
	(segment
		(start 85.322664 -57.711594)
		(end 85.322664 -68.31838)
		(width 0.1524)
		(layer "B.Cu")
		(net "B4_PSU_ALERT_N")
	)
	(segment
		(start 91.07297 -75.750928)
		(end 90.635074 -76.188824)
		(width 0.1524)
		(layer "B.Cu")
		(net "B4_PSU_ALERT_N")
	)
	(segment
		(start 91.357958 -83.792314)
		(end 91.357958 -79.449676)
		(width 0.1524)
		(layer "B.Cu")
		(net "B4_PSU_ALERT_N")
	)
	(segment
		(start 91.357958 -79.449676)
		(end 90.793824 -78.885542)
		(width 0.1524)
		(layer "B.Cu")
		(net "B4_PSU_ALERT_N")
	)
	(segment
		(start 89.44991 -49.45507)
		(end 89.44991 -50.816002)
		(width 0.1524)
		(layer "B.Cu")
		(net "B4_PSU_ALERT_N")
	)
	(segment
		(start 91.07297 -74.068686)
		(end 91.07297 -75.750928)
		(width 0.1524)
		(layer "B.Cu")
		(net "B4_PSU_ALERT_N")
	)
	(segment
		(start 90.793824 -76.347574)
		(end 90.635074 -76.188824)
		(width 0.1524)
		(layer "B.Cu")
		(net "B4_PSU_ALERT_N")
	)
	(segment
		(start 88.638888 -52.51831)
		(end 89.075768 -52.95519)
		(width 0.1524)
		(layer "B.Cu")
		(net "B4_PSU_ALERT_N")
	)
	(segment
		(start 85.322664 -68.31838)
		(end 91.07297 -74.068686)
		(width 0.1524)
		(layer "B.Cu")
		(net "B4_PSU_ALERT_N")
	)
	(segment
		(start 88.638888 -51.627024)
		(end 88.638888 -52.51831)
		(width 0.1524)
		(layer "B.Cu")
		(net "B4_PSU_ALERT_N")
	)
	(segment
		(start 90.793824 -78.885542)
		(end 90.793824 -76.347574)
		(width 0.1524)
		(layer "B.Cu")
		(net "B4_PSU_ALERT_N")
	)
	(via
		(at 92.005658 -76.04252)
		(size 0.6604)
		(drill 0.3302)
		(layers "F.Cu" "B.Cu")
		(net "B3_PSU_ALERT_N")
	)
	(segment
		(start 91.453716 -75.490578)
		(end 92.005658 -76.04252)
		(width 0.1524)
		(layer "B.Cu")
		(net "B3_PSU_ALERT_N")
	)
	(segment
		(start 89.44991 -51.99507)
		(end 89.44991 -54.122828)
		(width 0.1524)
		(layer "B.Cu")
		(net "B3_PSU_ALERT_N")
	)
	(segment
		(start 85.70341 -68.160646)
		(end 91.453716 -73.910952)
		(width 0.1524)
		(layer "B.Cu")
		(net "B3_PSU_ALERT_N")
	)
	(segment
		(start 91.453716 -73.910952)
		(end 91.453716 -75.490578)
		(width 0.1524)
		(layer "B.Cu")
		(net "B3_PSU_ALERT_N")
	)
	(segment
		(start 91.677744 -76.370434)
		(end 91.677744 -76.91755)
		(width 0.1524)
		(layer "B.Cu")
		(net "B3_PSU_ALERT_N")
	)
	(segment
		(start 92.007944 -77.24775)
		(end 92.007944 -77.950314)
		(width 0.1524)
		(layer "B.Cu")
		(net "B3_PSU_ALERT_N")
	)
	(segment
		(start 89.44991 -54.122828)
		(end 85.70341 -57.869328)
		(width 0.1524)
		(layer "B.Cu")
		(net "B3_PSU_ALERT_N")
	)
	(segment
		(start 92.005658 -76.04252)
		(end 91.677744 -76.370434)
		(width 0.1524)
		(layer "B.Cu")
		(net "B3_PSU_ALERT_N")
	)
	(segment
		(start 91.677744 -76.91755)
		(end 92.007944 -77.24775)
		(width 0.1524)
		(layer "B.Cu")
		(net "B3_PSU_ALERT_N")
	)
	(segment
		(start 85.70341 -57.869328)
		(end 85.70341 -68.160646)
		(width 0.1524)
		(layer "B.Cu")
		(net "B3_PSU_ALERT_N")
	)
	(via
		(at 93.610176 -76.31938)
		(size 0.6604)
		(drill 0.3302)
		(layers "F.Cu" "B.Cu")
		(net "B2_PSU_ALERT_N")
	)
	(segment
		(start 88.546178 -7.206742)
		(end 88.546178 -7.912862)
		(width 0.1524)
		(layer "B.Cu")
		(net "B2_PSU_ALERT_N")
	)
	(segment
		(start 89.029032 -9.73328)
		(end 88.397334 -10.364978)
		(width 0.1524)
		(layer "B.Cu")
		(net "B2_PSU_ALERT_N")
	)
	(segment
		(start 82.489548 -11.795506)
		(end 82.489548 -14.619478)
		(width 0.1524)
		(layer "B.Cu")
		(net "B2_PSU_ALERT_N")
	)
	(segment
		(start 84.40293 -16.53286)
		(end 84.40293 -23.035006)
		(width 0.1524)
		(layer "B.Cu")
		(net "B2_PSU_ALERT_N")
	)
	(segment
		(start 89.029032 -8.395716)
		(end 89.029032 -9.73328)
		(width 0.1524)
		(layer "B.Cu")
		(net "B2_PSU_ALERT_N")
	)
	(segment
		(start 89.44991 -5.00507)
		(end 89.44991 -6.30301)
		(width 0.1524)
		(layer "B.Cu")
		(net "B2_PSU_ALERT_N")
	)
	(segment
		(start 89.44991 -6.30301)
		(end 88.546178 -7.206742)
		(width 0.1524)
		(layer "B.Cu")
		(net "B2_PSU_ALERT_N")
	)
	(segment
		(start 93.307916 -77.065378)
		(end 93.610176 -76.763118)
		(width 0.1524)
		(layer "B.Cu")
		(net "B2_PSU_ALERT_N")
	)
	(segment
		(start 94.031054 -75.898502)
		(end 93.610176 -76.31938)
		(width 0.1524)
		(layer "B.Cu")
		(net "B2_PSU_ALERT_N")
	)
	(segment
		(start 97.258886 -69.888608)
		(end 94.031054 -73.11644)
		(width 0.1524)
		(layer "B.Cu")
		(net "B2_PSU_ALERT_N")
	)
	(segment
		(start 88.397334 -10.364978)
		(end 83.920076 -10.364978)
		(width 0.1524)
		(layer "B.Cu")
		(net "B2_PSU_ALERT_N")
	)
	(segment
		(start 94.031054 -73.11644)
		(end 94.031054 -75.898502)
		(width 0.1524)
		(layer "B.Cu")
		(net "B2_PSU_ALERT_N")
	)
	(segment
		(start 93.307916 -77.950314)
		(end 93.307916 -77.065378)
		(width 0.1524)
		(layer "B.Cu")
		(net "B2_PSU_ALERT_N")
	)
	(segment
		(start 83.920076 -10.364978)
		(end 82.489548 -11.795506)
		(width 0.1524)
		(layer "B.Cu")
		(net "B2_PSU_ALERT_N")
	)
	(segment
		(start 88.546178 -7.912862)
		(end 89.029032 -8.395716)
		(width 0.1524)
		(layer "B.Cu")
		(net "B2_PSU_ALERT_N")
	)
	(segment
		(start 97.258886 -35.890962)
		(end 97.258886 -69.888608)
		(width 0.1524)
		(layer "B.Cu")
		(net "B2_PSU_ALERT_N")
	)
	(segment
		(start 84.40293 -23.035006)
		(end 97.258886 -35.890962)
		(width 0.1524)
		(layer "B.Cu")
		(net "B2_PSU_ALERT_N")
	)
	(segment
		(start 82.489548 -14.619478)
		(end 84.40293 -16.53286)
		(width 0.1524)
		(layer "B.Cu")
		(net "B2_PSU_ALERT_N")
	)
	(segment
		(start 93.610176 -76.763118)
		(end 93.610176 -76.31938)
		(width 0.1524)
		(layer "B.Cu")
		(net "B2_PSU_ALERT_N")
	)
	(via
		(at 94.981268 -76.332842)
		(size 0.6604)
		(drill 0.3302)
		(layers "F.Cu" "B.Cu")
		(net "B1_PSU_ALERT_N")
	)
	(segment
		(start 94.981268 -76.128372)
		(end 94.981268 -76.332842)
		(width 0.1524)
		(layer "B.Cu")
		(net "B1_PSU_ALERT_N")
	)
	(segment
		(start 97.616772 -70.036944)
		(end 94.38894 -73.264776)
		(width 0.1524)
		(layer "B.Cu")
		(net "B1_PSU_ALERT_N")
	)
	(segment
		(start 82.847434 -14.471142)
		(end 84.760816 -16.384524)
		(width 0.1524)
		(layer "B.Cu")
		(net "B1_PSU_ALERT_N")
	)
	(segment
		(start 89.44991 -9.818624)
		(end 88.54567 -10.722864)
		(width 0.1524)
		(layer "B.Cu")
		(net "B1_PSU_ALERT_N")
	)
	(segment
		(start 94.38894 -73.264776)
		(end 94.38894 -75.536044)
		(width 0.1524)
		(layer "B.Cu")
		(net "B1_PSU_ALERT_N")
	)
	(segment
		(start 84.760816 -16.384524)
		(end 84.760816 -22.88667)
		(width 0.1524)
		(layer "B.Cu")
		(net "B1_PSU_ALERT_N")
	)
	(segment
		(start 94.607888 -76.706222)
		(end 94.981268 -76.332842)
		(width 0.1524)
		(layer "B.Cu")
		(net "B1_PSU_ALERT_N")
	)
	(segment
		(start 82.847434 -11.943842)
		(end 82.847434 -14.471142)
		(width 0.1524)
		(layer "B.Cu")
		(net "B1_PSU_ALERT_N")
	)
	(segment
		(start 94.38894 -75.536044)
		(end 94.981268 -76.128372)
		(width 0.1524)
		(layer "B.Cu")
		(net "B1_PSU_ALERT_N")
	)
	(segment
		(start 89.44991 -7.54507)
		(end 89.44991 -9.818624)
		(width 0.1524)
		(layer "B.Cu")
		(net "B1_PSU_ALERT_N")
	)
	(segment
		(start 94.607888 -77.950314)
		(end 94.607888 -76.706222)
		(width 0.1524)
		(layer "B.Cu")
		(net "B1_PSU_ALERT_N")
	)
	(segment
		(start 97.616772 -35.742626)
		(end 97.616772 -70.036944)
		(width 0.1524)
		(layer "B.Cu")
		(net "B1_PSU_ALERT_N")
	)
	(segment
		(start 88.54567 -10.722864)
		(end 84.068412 -10.722864)
		(width 0.1524)
		(layer "B.Cu")
		(net "B1_PSU_ALERT_N")
	)
	(segment
		(start 84.760816 -22.88667)
		(end 97.616772 -35.742626)
		(width 0.1524)
		(layer "B.Cu")
		(net "B1_PSU_ALERT_N")
	)
	(segment
		(start 84.068412 -10.722864)
		(end 82.847434 -11.943842)
		(width 0.1524)
		(layer "B.Cu")
		(net "B1_PSU_ALERT_N")
	)
	(segment
		(start 4.204208 -414.566862)
		(end 4.204208 -412.060644)
		(width 0.1524)
		(layer "F.Cu")
		(net "N42132933")
	)
	(segment
		(start 4.204208 -412.060644)
		(end 3.574542 -411.430978)
		(width 0.1524)
		(layer "F.Cu")
		(net "N42132933")
	)
	(segment
		(start 3.731514 -398.674082)
		(end 3.574542 -398.831054)
		(width 0.1524)
		(layer "F.Cu")
		(net "N42132358")
	)
	(segment
		(start 3.731514 -396.058136)
		(end 3.731514 -398.674082)
		(width 0.1524)
		(layer "F.Cu")
		(net "N42132358")
	)
	(segment
		(start 2.678938 -409.83662)
		(end 3.574542 -408.941016)
		(width 0.1524)
		(layer "F.Cu")
		(net "N42132545")
	)
	(segment
		(start 2.832862 -414.60039)
		(end 2.678938 -414.446466)
		(width 0.1524)
		(layer "F.Cu")
		(net "N42132545")
	)
	(segment
		(start 2.678938 -414.446466)
		(end 2.678938 -409.83662)
		(width 0.1524)
		(layer "F.Cu")
		(net "N42132545")
	)
	(segment
		(start 3.414014 -127.48641)
		(end 3.414014 -129.93751)
		(width 0.1524)
		(layer "F.Cu")
		(net "N42130542")
	)
	(segment
		(start 3.414014 -129.93751)
		(end 3.574542 -130.098038)
		(width 0.1524)
		(layer "F.Cu")
		(net "N42130542")
	)
	(segment
		(start 2.455926 -141.326616)
		(end 2.455926 -143.605758)
		(width 0.1524)
		(layer "F.Cu")
		(net "N42126673")
	)
	(segment
		(start 2.772156 -143.921988)
		(end 2.772156 -145.557494)
		(width 0.1524)
		(layer "F.Cu")
		(net "N42126673")
	)
	(segment
		(start 3.574542 -140.208)
		(end 2.455926 -141.326616)
		(width 0.1524)
		(layer "F.Cu")
		(net "N42126673")
	)
	(segment
		(start 2.455926 -143.605758)
		(end 2.772156 -143.921988)
		(width 0.1524)
		(layer "F.Cu")
		(net "N42126673")
	)
	(segment
		(start 4.059936 -143.183356)
		(end 3.574542 -142.697962)
		(width 0.1524)
		(layer "F.Cu")
		(net "N42126764")
	)
	(segment
		(start 4.059936 -145.574258)
		(end 4.059936 -143.183356)
		(width 0.1524)
		(layer "F.Cu")
		(net "N42126764")
	)
	(segment
		(start 7.154418 -194.417696)
		(end 6.12648 -194.417696)
		(width 0.127)
		(layer "In5.Cu")
		(net "UART_DSR_P5_L_N")
	)
	(segment
		(start 21.074888 -160.038542)
		(end 11.609832 -169.503598)
		(width 0.127)
		(layer "In5.Cu")
		(net "UART_DSR_P5_L_N")
	)
	(segment
		(start 12.113768 -70.801484)
		(end 12.113768 -73.791064)
		(width 0.127)
		(layer "In5.Cu")
		(net "UART_DSR_P5_L_N")
	)
	(segment
		(start 5.383784 -195.160392)
		(end 5.383784 -206.235808)
		(width 0.127)
		(layer "In5.Cu")
		(net "UART_DSR_P5_L_N")
	)
	(segment
		(start 16.504666 -69.723)
		(end 13.192252 -69.723)
		(width 0.127)
		(layer "In5.Cu")
		(net "UART_DSR_P5_L_N")
	)
	(segment
		(start 5.1562 -94.300802)
		(end 5.1562 -111.562134)
		(width 0.127)
		(layer "In5.Cu")
		(net "UART_DSR_P5_L_N")
	)
	(segment
		(start 11.609832 -191.16548)
		(end 9.234678 -193.540634)
		(width 0.127)
		(layer "In5.Cu")
		(net "UART_DSR_P5_L_N")
	)
	(segment
		(start 21.074888 -132.569458)
		(end 21.074888 -160.038542)
		(width 0.127)
		(layer "In5.Cu")
		(net "UART_DSR_P5_L_N")
	)
	(segment
		(start 6.12648 -194.417696)
		(end 5.383784 -195.160392)
		(width 0.127)
		(layer "In5.Cu")
		(net "UART_DSR_P5_L_N")
	)
	(segment
		(start 17.634458 -129.129028)
		(end 21.074888 -132.569458)
		(width 0.127)
		(layer "In5.Cu")
		(net "UART_DSR_P5_L_N")
	)
	(segment
		(start 5.383784 -206.235808)
		(end 3.948938 -207.670654)
		(width 0.127)
		(layer "In5.Cu")
		(net "UART_DSR_P5_L_N")
	)
	(segment
		(start 8.590026 -121.225564)
		(end 16.49349 -129.129028)
		(width 0.127)
		(layer "In5.Cu")
		(net "UART_DSR_P5_L_N")
	)
	(segment
		(start 8.03148 -193.540634)
		(end 7.154418 -194.417696)
		(width 0.127)
		(layer "In5.Cu")
		(net "UART_DSR_P5_L_N")
	)
	(segment
		(start 5.1562 -111.562134)
		(end 8.590026 -114.99596)
		(width 0.127)
		(layer "In5.Cu")
		(net "UART_DSR_P5_L_N")
	)
	(segment
		(start 10.892028 -75.012804)
		(end 10.892028 -90.715846)
		(width 0.127)
		(layer "In5.Cu")
		(net "UART_DSR_P5_L_N")
	)
	(segment
		(start 10.892028 -90.715846)
		(end 8.654034 -92.95384)
		(width 0.127)
		(layer "In5.Cu")
		(net "UART_DSR_P5_L_N")
	)
	(segment
		(start 6.503162 -92.95384)
		(end 5.1562 -94.300802)
		(width 0.127)
		(layer "In5.Cu")
		(net "UART_DSR_P5_L_N")
	)
	(segment
		(start 13.192252 -69.723)
		(end 12.113768 -70.801484)
		(width 0.127)
		(layer "In5.Cu")
		(net "UART_DSR_P5_L_N")
	)
	(segment
		(start 9.234678 -193.540634)
		(end 8.03148 -193.540634)
		(width 0.127)
		(layer "In5.Cu")
		(net "UART_DSR_P5_L_N")
	)
	(segment
		(start 16.49349 -129.129028)
		(end 17.634458 -129.129028)
		(width 0.127)
		(layer "In5.Cu")
		(net "UART_DSR_P5_L_N")
	)
	(segment
		(start 8.654034 -92.95384)
		(end 6.503162 -92.95384)
		(width 0.127)
		(layer "In5.Cu")
		(net "UART_DSR_P5_L_N")
	)
	(segment
		(start 8.590026 -114.99596)
		(end 8.590026 -121.225564)
		(width 0.127)
		(layer "In5.Cu")
		(net "UART_DSR_P5_L_N")
	)
	(segment
		(start 12.113768 -73.791064)
		(end 10.892028 -75.012804)
		(width 0.127)
		(layer "In5.Cu")
		(net "UART_DSR_P5_L_N")
	)
	(segment
		(start 11.609832 -169.503598)
		(end 11.609832 -191.16548)
		(width 0.127)
		(layer "In5.Cu")
		(net "UART_DSR_P5_L_N")
	)
	(segment
		(start 15.261336 -105.51033)
		(end 15.261336 -109.26445)
		(width 0.1524)
		(layer "B.Cu")
		(net "UART_DSR_P6_L_N")
	)
	(segment
		(start 9.617456 -208.73085)
		(end 8.791194 -209.557112)
		(width 0.1524)
		(layer "B.Cu")
		(net "UART_DSR_P6_L_N")
	)
	(segment
		(start 10.277094 -205.980792)
		(end 9.617456 -206.64043)
		(width 0.1524)
		(layer "B.Cu")
		(net "UART_DSR_P6_L_N")
	)
	(segment
		(start 19.588988 -194.669156)
		(end 10.277094 -203.98105)
		(width 0.1524)
		(layer "B.Cu")
		(net "UART_DSR_P6_L_N")
	)
	(segment
		(start 21.407628 -132.203698)
		(end 21.407628 -141.177264)
		(width 0.1524)
		(layer "B.Cu")
		(net "UART_DSR_P6_L_N")
	)
	(segment
		(start 8.851646 -115.67414)
		(end 8.851646 -119.647716)
		(width 0.1524)
		(layer "B.Cu")
		(net "UART_DSR_P6_L_N")
	)
	(segment
		(start 7.841996 -209.557112)
		(end 6.448806 -208.163922)
		(width 0.1524)
		(layer "B.Cu")
		(net "UART_DSR_P6_L_N")
	)
	(segment
		(start 8.851646 -119.647716)
		(end 21.407628 -132.203698)
		(width 0.1524)
		(layer "B.Cu")
		(net "UART_DSR_P6_L_N")
	)
	(segment
		(start 6.448806 -208.163922)
		(end 6.448806 -207.670654)
		(width 0.1524)
		(layer "B.Cu")
		(net "UART_DSR_P6_L_N")
	)
	(segment
		(start 10.277094 -203.98105)
		(end 10.277094 -205.980792)
		(width 0.1524)
		(layer "B.Cu")
		(net "UART_DSR_P6_L_N")
	)
	(segment
		(start 16.504666 -104.267)
		(end 15.261336 -105.51033)
		(width 0.1524)
		(layer "B.Cu")
		(net "UART_DSR_P6_L_N")
	)
	(segment
		(start 21.407628 -141.177264)
		(end 19.588988 -142.995904)
		(width 0.1524)
		(layer "B.Cu")
		(net "UART_DSR_P6_L_N")
	)
	(segment
		(start 19.588988 -142.995904)
		(end 19.588988 -194.669156)
		(width 0.1524)
		(layer "B.Cu")
		(net "UART_DSR_P6_L_N")
	)
	(segment
		(start 15.261336 -109.26445)
		(end 8.851646 -115.67414)
		(width 0.1524)
		(layer "B.Cu")
		(net "UART_DSR_P6_L_N")
	)
	(segment
		(start 8.791194 -209.557112)
		(end 7.841996 -209.557112)
		(width 0.1524)
		(layer "B.Cu")
		(net "UART_DSR_P6_L_N")
	)
	(segment
		(start 9.617456 -206.64043)
		(end 9.617456 -208.73085)
		(width 0.1524)
		(layer "B.Cu")
		(net "UART_DSR_P6_L_N")
	)
	(segment
		(start 17.162272 -332.188566)
		(end 15.924784 -333.426054)
		(width 0.1524)
		(layer "F.Cu")
		(net "FRU_A0")
	)
	(segment
		(start 15.924784 -333.426054)
		(end 15.924784 -336.945986)
		(width 0.1524)
		(layer "F.Cu")
		(net "FRU_A0")
	)
	(segment
		(start 17.162526 -330.85532)
		(end 17.162272 -330.855574)
		(width 0.1524)
		(layer "F.Cu")
		(net "FRU_A0")
	)
	(segment
		(start 18.264886 -330.85532)
		(end 17.162526 -330.85532)
		(width 0.1524)
		(layer "F.Cu")
		(net "FRU_A0")
	)
	(segment
		(start 18.264886 -330.85532)
		(end 18.264886 -331.085952)
		(width 0.1524)
		(layer "F.Cu")
		(net "FRU_A0")
	)
	(segment
		(start 18.264886 -331.085952)
		(end 17.162272 -332.188566)
		(width 0.1524)
		(layer "F.Cu")
		(net "FRU_A0")
	)
	(segment
		(start 14.237208 -338.633562)
		(end 13.74902 -338.633562)
		(width 0.1524)
		(layer "F.Cu")
		(net "FRU_A0")
	)
	(segment
		(start 15.924784 -336.945986)
		(end 14.237208 -338.633562)
		(width 0.1524)
		(layer "F.Cu")
		(net "FRU_A0")
	)
	(via
		(at 17.162272 -332.188566)
		(size 0.508)
		(drill 0.254)
		(layers "F.Cu" "B.Cu")
		(net "FRU_A0")
	)
	(segment
		(start 12.784074 -330.88072)
		(end 13.853668 -330.88072)
		(width 0.1524)
		(layer "F.Cu")
		(net "FRU_A2")
	)
	(segment
		(start 14.865604 -335.68259)
		(end 14.865604 -333.496412)
		(width 0.1524)
		(layer "F.Cu")
		(net "FRU_A2")
	)
	(segment
		(start 13.74902 -336.093562)
		(end 14.454632 -336.093562)
		(width 0.1524)
		(layer "F.Cu")
		(net "FRU_A2")
	)
	(segment
		(start 13.853668 -330.88072)
		(end 13.853922 -330.880974)
		(width 0.1524)
		(layer "F.Cu")
		(net "FRU_A2")
	)
	(segment
		(start 12.784074 -330.88072)
		(end 12.784074 -331.414882)
		(width 0.1524)
		(layer "F.Cu")
		(net "FRU_A2")
	)
	(segment
		(start 14.454632 -336.093562)
		(end 14.865604 -335.68259)
		(width 0.1524)
		(layer "F.Cu")
		(net "FRU_A2")
	)
	(segment
		(start 14.865604 -333.496412)
		(end 13.853922 -332.48473)
		(width 0.1524)
		(layer "F.Cu")
		(net "FRU_A2")
	)
	(segment
		(start 12.784074 -331.414882)
		(end 13.853922 -332.48473)
		(width 0.1524)
		(layer "F.Cu")
		(net "FRU_A2")
	)
	(via
		(at 13.853922 -332.48473)
		(size 0.508)
		(drill 0.254)
		(layers "F.Cu" "B.Cu")
		(net "FRU_A2")
	)
	(segment
		(start 15.680436 -340.860888)
		(end 15.713964 -340.894416)
		(width 0.1524)
		(layer "F.Cu")
		(net "FRU_WP")
	)
	(segment
		(start 13.265658 -340.860888)
		(end 15.680436 -340.860888)
		(width 0.1524)
		(layer "F.Cu")
		(net "FRU_WP")
	)
	(segment
		(start 18.948908 -337.363562)
		(end 17.86636 -337.363562)
		(width 0.1524)
		(layer "F.Cu")
		(net "FRU_WP")
	)
	(via
		(at 15.713964 -340.894416)
		(size 0.508)
		(drill 0.254)
		(layers "F.Cu" "B.Cu")
		(net "FRU_WP")
	)
	(via
		(at 17.86636 -337.363562)
		(size 0.508)
		(drill 0.254)
		(layers "F.Cu" "B.Cu")
		(net "FRU_WP")
	)
	(segment
		(start 15.713964 -340.894416)
		(end 15.713964 -339.515958)
		(width 0.127)
		(layer "In2.Cu")
		(net "FRU_WP")
	)
	(segment
		(start 15.713964 -339.515958)
		(end 17.86636 -337.363562)
		(width 0.127)
		(layer "In2.Cu")
		(net "FRU_WP")
	)
	(segment
		(start 14.689582 -337.363562)
		(end 13.74902 -337.363562)
		(width 0.1524)
		(layer "F.Cu")
		(net "FRU_A1")
	)
	(segment
		(start 15.423388 -336.629756)
		(end 14.689582 -337.363562)
		(width 0.1524)
		(layer "F.Cu")
		(net "FRU_A1")
	)
	(segment
		(start 14.923008 -331.743304)
		(end 15.713964 -332.53426)
		(width 0.1524)
		(layer "F.Cu")
		(net "FRU_A1")
	)
	(segment
		(start 14.923008 -330.897484)
		(end 14.923008 -331.743304)
		(width 0.1524)
		(layer "F.Cu")
		(net "FRU_A1")
	)
	(segment
		(start 16.017494 -330.897484)
		(end 14.923008 -330.897484)
		(width 0.1524)
		(layer "F.Cu")
		(net "FRU_A1")
	)
	(segment
		(start 15.423388 -332.824836)
		(end 15.423388 -336.629756)
		(width 0.1524)
		(layer "F.Cu")
		(net "FRU_A1")
	)
	(segment
		(start 15.713964 -332.53426)
		(end 15.423388 -332.824836)
		(width 0.1524)
		(layer "F.Cu")
		(net "FRU_A1")
	)
	(via
		(at 15.713964 -332.53426)
		(size 0.508)
		(drill 0.254)
		(layers "F.Cu" "B.Cu")
		(net "FRU_A1")
	)
	(segment
		(start 4.445 -111.856774)
		(end 7.929626 -115.3414)
		(width 0.127)
		(layer "In5.Cu")
		(net "UART_CTS_P5_L_N")
	)
	(segment
		(start 20.363688 -132.955792)
		(end 20.363688 -159.815022)
		(width 0.127)
		(layer "In5.Cu")
		(net "UART_CTS_P5_L_N")
	)
	(segment
		(start 11.402568 -69.042026)
		(end 11.402568 -73.496424)
		(width 0.127)
		(layer "In5.Cu")
		(net "UART_CTS_P5_L_N")
	)
	(segment
		(start 5.842508 -192.47104)
		(end 4.711954 -193.601594)
		(width 0.127)
		(layer "In5.Cu")
		(net "UART_CTS_P5_L_N")
	)
	(segment
		(start 11.787632 -168.391586)
		(end 10.898632 -169.280586)
		(width 0.127)
		(layer "In5.Cu")
		(net "UART_CTS_P5_L_N")
	)
	(segment
		(start 4.711954 -193.601594)
		(end 4.711954 -202.907646)
		(width 0.127)
		(layer "In5.Cu")
		(net "UART_CTS_P5_L_N")
	)
	(segment
		(start 12.998704 -67.44589)
		(end 11.402568 -69.042026)
		(width 0.127)
		(layer "In5.Cu")
		(net "UART_CTS_P5_L_N")
	)
	(segment
		(start 15.82293 -68.59778)
		(end 14.67104 -67.44589)
		(width 0.127)
		(layer "In5.Cu")
		(net "UART_CTS_P5_L_N")
	)
	(segment
		(start 7.929626 -121.499376)
		(end 16.219678 -129.789428)
		(width 0.127)
		(layer "In5.Cu")
		(net "UART_CTS_P5_L_N")
	)
	(segment
		(start 4.445 -94.006162)
		(end 4.445 -111.856774)
		(width 0.127)
		(layer "In5.Cu")
		(net "UART_CTS_P5_L_N")
	)
	(segment
		(start 17.83842 -67.9196)
		(end 17.16024 -68.59778)
		(width 0.127)
		(layer "In5.Cu")
		(net "UART_CTS_P5_L_N")
	)
	(segment
		(start 10.898632 -190.247524)
		(end 9.565386 -191.58077)
		(width 0.127)
		(layer "In5.Cu")
		(net "UART_CTS_P5_L_N")
	)
	(segment
		(start 7.02056 -192.47104)
		(end 5.842508 -192.47104)
		(width 0.127)
		(layer "In5.Cu")
		(net "UART_CTS_P5_L_N")
	)
	(segment
		(start 9.565386 -191.58077)
		(end 7.91083 -191.58077)
		(width 0.127)
		(layer "In5.Cu")
		(net "UART_CTS_P5_L_N")
	)
	(segment
		(start 11.402568 -73.496424)
		(end 10.180828 -74.718164)
		(width 0.127)
		(layer "In5.Cu")
		(net "UART_CTS_P5_L_N")
	)
	(segment
		(start 17.83842 -63.436754)
		(end 17.83842 -67.9196)
		(width 0.127)
		(layer "In5.Cu")
		(net "UART_CTS_P5_L_N")
	)
	(segment
		(start 14.67104 -67.44589)
		(end 12.998704 -67.44589)
		(width 0.127)
		(layer "In5.Cu")
		(net "UART_CTS_P5_L_N")
	)
	(segment
		(start 4.711954 -202.907646)
		(end 3.948938 -203.670662)
		(width 0.127)
		(layer "In5.Cu")
		(net "UART_CTS_P5_L_N")
	)
	(segment
		(start 6.208522 -92.24264)
		(end 4.445 -94.006162)
		(width 0.127)
		(layer "In5.Cu")
		(net "UART_CTS_P5_L_N")
	)
	(segment
		(start 10.180828 -74.718164)
		(end 10.180828 -90.421206)
		(width 0.127)
		(layer "In5.Cu")
		(net "UART_CTS_P5_L_N")
	)
	(segment
		(start 16.219678 -129.789428)
		(end 17.197324 -129.789428)
		(width 0.127)
		(layer "In5.Cu")
		(net "UART_CTS_P5_L_N")
	)
	(segment
		(start 7.929626 -115.3414)
		(end 7.929626 -121.499376)
		(width 0.127)
		(layer "In5.Cu")
		(net "UART_CTS_P5_L_N")
	)
	(segment
		(start 8.359394 -92.24264)
		(end 6.208522 -92.24264)
		(width 0.127)
		(layer "In5.Cu")
		(net "UART_CTS_P5_L_N")
	)
	(segment
		(start 10.180828 -90.421206)
		(end 8.359394 -92.24264)
		(width 0.127)
		(layer "In5.Cu")
		(net "UART_CTS_P5_L_N")
	)
	(segment
		(start 20.363688 -159.815022)
		(end 11.787632 -168.391586)
		(width 0.127)
		(layer "In5.Cu")
		(net "UART_CTS_P5_L_N")
	)
	(segment
		(start 16.504666 -62.103)
		(end 17.83842 -63.436754)
		(width 0.127)
		(layer "In5.Cu")
		(net "UART_CTS_P5_L_N")
	)
	(segment
		(start 17.16024 -68.59778)
		(end 15.82293 -68.59778)
		(width 0.127)
		(layer "In5.Cu")
		(net "UART_CTS_P5_L_N")
	)
	(segment
		(start 10.898632 -169.280586)
		(end 10.898632 -190.247524)
		(width 0.127)
		(layer "In5.Cu")
		(net "UART_CTS_P5_L_N")
	)
	(segment
		(start 17.197324 -129.789428)
		(end 20.363688 -132.955792)
		(width 0.127)
		(layer "In5.Cu")
		(net "UART_CTS_P5_L_N")
	)
	(segment
		(start 7.91083 -191.58077)
		(end 7.02056 -192.47104)
		(width 0.127)
		(layer "In5.Cu")
		(net "UART_CTS_P5_L_N")
	)
	(segment
		(start 17.455388 -193.663824)
		(end 9.708388 -201.410824)
		(width 0.1524)
		(layer "B.Cu")
		(net "UART_CTS_P6_L_N")
	)
	(segment
		(start 8.076184 -201.410824)
		(end 6.448806 -203.038202)
		(width 0.1524)
		(layer "B.Cu")
		(net "UART_CTS_P6_L_N")
	)
	(segment
		(start 10.890758 -109.907832)
		(end 6.718046 -114.080544)
		(width 0.1524)
		(layer "B.Cu")
		(net "UART_CTS_P6_L_N")
	)
	(segment
		(start 19.274028 -133.087618)
		(end 19.274028 -140.293344)
		(width 0.1524)
		(layer "B.Cu")
		(net "UART_CTS_P6_L_N")
	)
	(segment
		(start 6.718046 -114.080544)
		(end 6.718046 -120.531636)
		(width 0.1524)
		(layer "B.Cu")
		(net "UART_CTS_P6_L_N")
	)
	(segment
		(start 10.890758 -100.392992)
		(end 10.890758 -109.907832)
		(width 0.1524)
		(layer "B.Cu")
		(net "UART_CTS_P6_L_N")
	)
	(segment
		(start 6.718046 -120.531636)
		(end 19.274028 -133.087618)
		(width 0.1524)
		(layer "B.Cu")
		(net "UART_CTS_P6_L_N")
	)
	(segment
		(start 9.708388 -201.410824)
		(end 8.076184 -201.410824)
		(width 0.1524)
		(layer "B.Cu")
		(net "UART_CTS_P6_L_N")
	)
	(segment
		(start 16.23822 -96.380554)
		(end 13.249656 -96.380554)
		(width 0.1524)
		(layer "B.Cu")
		(net "UART_CTS_P6_L_N")
	)
	(segment
		(start 11.726418 -97.903792)
		(end 11.726418 -99.557332)
		(width 0.1524)
		(layer "B.Cu")
		(net "UART_CTS_P6_L_N")
	)
	(segment
		(start 19.274028 -140.293344)
		(end 17.455388 -142.111984)
		(width 0.1524)
		(layer "B.Cu")
		(net "UART_CTS_P6_L_N")
	)
	(segment
		(start 6.448806 -203.038202)
		(end 6.448806 -203.670662)
		(width 0.1524)
		(layer "B.Cu")
		(net "UART_CTS_P6_L_N")
	)
	(segment
		(start 16.504666 -96.647)
		(end 16.23822 -96.380554)
		(width 0.1524)
		(layer "B.Cu")
		(net "UART_CTS_P6_L_N")
	)
	(segment
		(start 13.249656 -96.380554)
		(end 11.726418 -97.903792)
		(width 0.1524)
		(layer "B.Cu")
		(net "UART_CTS_P6_L_N")
	)
	(segment
		(start 17.455388 -142.111984)
		(end 17.455388 -193.663824)
		(width 0.1524)
		(layer "B.Cu")
		(net "UART_CTS_P6_L_N")
	)
	(segment
		(start 11.726418 -99.557332)
		(end 10.890758 -100.392992)
		(width 0.1524)
		(layer "B.Cu")
		(net "UART_CTS_P6_L_N")
	)
	(via
		(at 15.045944 -170.372532)
		(size 0.508)
		(drill 0.254)
		(layers "F.Cu" "B.Cu")
		(net "GND28")
	)
	(segment
		(start 1.948942 -192.67043)
		(end 7.058152 -192.67043)
		(width 0.1524)
		(layer "B.Cu")
		(net "GND28")
	)
	(segment
		(start 15.045944 -187.136278)
		(end 15.045944 -170.372532)
		(width 0.1524)
		(layer "B.Cu")
		(net "GND28")
	)
	(segment
		(start 7.058152 -192.67043)
		(end 7.851648 -193.463926)
		(width 0.1524)
		(layer "B.Cu")
		(net "GND28")
	)
	(segment
		(start 9.072118 -193.463926)
		(end 10.64387 -191.892174)
		(width 0.1524)
		(layer "B.Cu")
		(net "GND28")
	)
	(segment
		(start 10.64387 -191.538352)
		(end 15.045944 -187.136278)
		(width 0.1524)
		(layer "B.Cu")
		(net "GND28")
	)
	(segment
		(start 7.851648 -193.463926)
		(end 9.072118 -193.463926)
		(width 0.1524)
		(layer "B.Cu")
		(net "GND28")
	)
	(segment
		(start 10.64387 -191.892174)
		(end 10.64387 -191.538352)
		(width 0.1524)
		(layer "B.Cu")
		(net "GND28")
	)
	(via
		(at 13.838682 -172.67174)
		(size 0.508)
		(drill 0.254)
		(layers "F.Cu" "B.Cu")
		(net "GND29")
	)
	(segment
		(start 10.026904 -191.639444)
		(end 13.838682 -187.827666)
		(width 0.1524)
		(layer "B.Cu")
		(net "GND29")
	)
	(segment
		(start 3.948938 -191.670432)
		(end 4.816348 -190.803022)
		(width 0.1524)
		(layer "B.Cu")
		(net "GND29")
	)
	(segment
		(start 7.328916 -190.803022)
		(end 8.165338 -191.639444)
		(width 0.1524)
		(layer "B.Cu")
		(net "GND29")
	)
	(segment
		(start 4.816348 -190.803022)
		(end 7.328916 -190.803022)
		(width 0.1524)
		(layer "B.Cu")
		(net "GND29")
	)
	(segment
		(start 13.838682 -187.827666)
		(end 13.838682 -172.67174)
		(width 0.1524)
		(layer "B.Cu")
		(net "GND29")
	)
	(segment
		(start 8.165338 -191.639444)
		(end 10.026904 -191.639444)
		(width 0.1524)
		(layer "B.Cu")
		(net "GND29")
	)
	(segment
		(start 2.130552 -356.285292)
		(end 2.130552 -473.522548)
		(width 0.1524)
		(layer "F.Cu")
		(net "POWER_SW3_PWR_CTR_12V")
	)
	(segment
		(start 2.130552 -473.522548)
		(end 5.780024 -477.17202)
		(width 0.1524)
		(layer "F.Cu")
		(net "POWER_SW3_PWR_CTR_12V")
	)
	(segment
		(start 6.449822 -344.669872)
		(end 6.449822 -345.250516)
		(width 0.1524)
		(layer "F.Cu")
		(net "POWER_SW3_PWR_CTR_12V")
	)
	(segment
		(start 5.669788 -346.03055)
		(end 5.669788 -352.746056)
		(width 0.1524)
		(layer "F.Cu")
		(net "POWER_SW3_PWR_CTR_12V")
	)
	(segment
		(start 6.449822 -345.250516)
		(end 5.669788 -346.03055)
		(width 0.1524)
		(layer "F.Cu")
		(net "POWER_SW3_PWR_CTR_12V")
	)
	(segment
		(start 5.669788 -352.746056)
		(end 2.130552 -356.285292)
		(width 0.1524)
		(layer "F.Cu")
		(net "POWER_SW3_PWR_CTR_12V")
	)
	(segment
		(start 3.665474 -345.63177)
		(end 3.13817 -346.159074)
		(width 0.1524)
		(layer "F.Cu")
		(net "POWER_SW1_PWR_CTR_12V")
	)
	(segment
		(start 3.13817 -353.717352)
		(end 1.368806 -355.486716)
		(width 0.1524)
		(layer "F.Cu")
		(net "POWER_SW1_PWR_CTR_12V")
	)
	(segment
		(start 1.368806 -355.486716)
		(end 1.368806 -512.638548)
		(width 0.1524)
		(layer "F.Cu")
		(net "POWER_SW1_PWR_CTR_12V")
	)
	(segment
		(start 3.13817 -346.159074)
		(end 3.13817 -353.717352)
		(width 0.1524)
		(layer "F.Cu")
		(net "POWER_SW1_PWR_CTR_12V")
	)
	(segment
		(start 4.25704 -345.63177)
		(end 3.665474 -345.63177)
		(width 0.1524)
		(layer "F.Cu")
		(net "POWER_SW1_PWR_CTR_12V")
	)
	(segment
		(start 4.782058 -344.33764)
		(end 4.782058 -345.106752)
		(width 0.1524)
		(layer "F.Cu")
		(net "POWER_SW1_PWR_CTR_12V")
	)
	(segment
		(start 1.368806 -512.638548)
		(end 5.780024 -517.049766)
		(width 0.1524)
		(layer "F.Cu")
		(net "POWER_SW1_PWR_CTR_12V")
	)
	(segment
		(start 6.449822 -342.669876)
		(end 4.782058 -344.33764)
		(width 0.1524)
		(layer "F.Cu")
		(net "POWER_SW1_PWR_CTR_12V")
	)
	(segment
		(start 4.782058 -345.106752)
		(end 4.25704 -345.63177)
		(width 0.1524)
		(layer "F.Cu")
		(net "POWER_SW1_PWR_CTR_12V")
	)
	(segment
		(start 6.371844 -343.669874)
		(end 5.30479 -344.736928)
		(width 0.1524)
		(layer "F.Cu")
		(net "POWER_SW2_PWR_CTR_12V")
	)
	(segment
		(start 5.30479 -345.34856)
		(end 4.923028 -345.730322)
		(width 0.1524)
		(layer "F.Cu")
		(net "POWER_SW2_PWR_CTR_12V")
	)
	(segment
		(start 1.749806 -493.969548)
		(end 5.780024 -497.999766)
		(width 0.1524)
		(layer "F.Cu")
		(net "POWER_SW2_PWR_CTR_12V")
	)
	(segment
		(start 4.923028 -352.97999)
		(end 1.749806 -356.153212)
		(width 0.1524)
		(layer "F.Cu")
		(net "POWER_SW2_PWR_CTR_12V")
	)
	(segment
		(start 4.923028 -345.730322)
		(end 4.923028 -352.97999)
		(width 0.1524)
		(layer "F.Cu")
		(net "POWER_SW2_PWR_CTR_12V")
	)
	(segment
		(start 1.749806 -356.153212)
		(end 1.749806 -493.969548)
		(width 0.1524)
		(layer "F.Cu")
		(net "POWER_SW2_PWR_CTR_12V")
	)
	(segment
		(start 5.30479 -344.736928)
		(end 5.30479 -345.34856)
		(width 0.1524)
		(layer "F.Cu")
		(net "POWER_SW2_PWR_CTR_12V")
	)
	(segment
		(start 8.449818 -343.669874)
		(end 6.371844 -343.669874)
		(width 0.1524)
		(layer "F.Cu")
		(net "POWER_SW2_PWR_CTR_12V")
	)
	(via
		(at 11.93292 -338.034122)
		(size 0.508)
		(drill 0.254)
		(layers "F.Cu" "B.Cu")
		(net "GND36")
	)
	(segment
		(start 10.29716 -339.669882)
		(end 8.449818 -339.669882)
		(width 0.127)
		(layer "In2.Cu")
		(net "GND36")
	)
	(segment
		(start 11.93292 -338.034122)
		(end 10.29716 -339.669882)
		(width 0.127)
		(layer "In2.Cu")
		(net "GND36")
	)
	(segment
		(start 7.84987 -348.434406)
		(end 8.893556 -348.434406)
		(width 0.127)
		(layer "B.Cu")
		(net "LAN2_P2_N")
	)
	(segment
		(start 12.967208 -400.368262)
		(end 12.967208 -403.012402)
		(width 0.127)
		(layer "B.Cu")
		(net "LAN2_P2_N")
	)
	(segment
		(start 6.867144 -347.45168)
		(end 7.84987 -348.434406)
		(width 0.127)
		(layer "B.Cu")
		(net "LAN2_P2_N")
	)
	(segment
		(start 12.967208 -403.012402)
		(end 13.541756 -403.58695)
		(width 0.127)
		(layer "B.Cu")
		(net "LAN2_P2_N")
	)
	(segment
		(start 13.508228 -394.770864)
		(end 13.508228 -399.827242)
		(width 0.127)
		(layer "B.Cu")
		(net "LAN2_P2_N")
	)
	(segment
		(start 8.739632 -390.002268)
		(end 13.508228 -394.770864)
		(width 0.127)
		(layer "B.Cu")
		(net "LAN2_P2_N")
	)
	(segment
		(start 8.739632 -359.718102)
		(end 8.739632 -390.002268)
		(width 0.127)
		(layer "B.Cu")
		(net "LAN2_P2_N")
	)
	(segment
		(start 8.893556 -348.434406)
		(end 9.756902 -349.297752)
		(width 0.127)
		(layer "B.Cu")
		(net "LAN2_P2_N")
	)
	(segment
		(start 2.654554 -348.022672)
		(end 2.824988 -347.965522)
		(width 0.127)
		(layer "B.Cu")
		(net "LAN2_P2_N")
	)
	(segment
		(start 16.213582 -403.58695)
		(end 16.574516 -403.226016)
		(width 0.127)
		(layer "B.Cu")
		(net "LAN2_P2_N")
	)
	(segment
		(start 3.282188 -347.45168)
		(end 6.867144 -347.45168)
		(width 0.127)
		(layer "B.Cu")
		(net "LAN2_P2_N")
	)
	(segment
		(start 2.882138 -347.85173)
		(end 3.282188 -347.45168)
		(width 0.127)
		(layer "B.Cu")
		(net "LAN2_P2_N")
	)
	(segment
		(start 9.756902 -349.297752)
		(end 9.756902 -358.700832)
		(width 0.127)
		(layer "B.Cu")
		(net "LAN2_P2_N")
	)
	(segment
		(start 2.824988 -347.965522)
		(end 2.882138 -347.85173)
		(width 0.127)
		(layer "B.Cu")
		(net "LAN2_P2_N")
	)
	(segment
		(start 9.756902 -358.700832)
		(end 8.739632 -359.718102)
		(width 0.127)
		(layer "B.Cu")
		(net "LAN2_P2_N")
	)
	(segment
		(start 13.541756 -403.58695)
		(end 16.213582 -403.58695)
		(width 0.127)
		(layer "B.Cu")
		(net "LAN2_P2_N")
	)
	(segment
		(start 13.508228 -399.827242)
		(end 12.967208 -400.368262)
		(width 0.127)
		(layer "B.Cu")
		(net "LAN2_P2_N")
	)
	(segment
		(start 1.949958 -347.669866)
		(end 2.654554 -348.022672)
		(width 0.127)
		(layer "B.Cu")
		(net "LAN2_P2_N")
	)
	(segment
		(start 9.350502 -353.639882)
		(end 9.166098 -353.824286)
		(width 0.127)
		(layer "B.Cu")
		(net "LAN2_P2_P")
	)
	(segment
		(start 3.245866 -348.317312)
		(end 3.189224 -348.146878)
		(width 0.127)
		(layer "B.Cu")
		(net "LAN2_P2_P")
	)
	(segment
		(start 13.101828 -399.65884)
		(end 12.560808 -400.19986)
		(width 0.127)
		(layer "B.Cu")
		(net "LAN2_P2_P")
	)
	(segment
		(start 3.216656 -348.092014)
		(end 3.45059 -347.85808)
		(width 0.127)
		(layer "B.Cu")
		(net "LAN2_P2_P")
	)
	(segment
		(start 12.560808 -403.181058)
		(end 13.147548 -403.768052)
		(width 0.127)
		(layer "B.Cu")
		(net "LAN2_P2_P")
	)
	(segment
		(start 9.166098 -356.466902)
		(end 9.350502 -356.651306)
		(width 0.127)
		(layer "B.Cu")
		(net "LAN2_P2_P")
	)
	(segment
		(start 9.350502 -352.509074)
		(end 9.166098 -352.693478)
		(width 0.127)
		(layer "B.Cu")
		(net "LAN2_P2_P")
	)
	(segment
		(start 7.681468 -348.840806)
		(end 8.725154 -348.840806)
		(width 0.127)
		(layer "B.Cu")
		(net "LAN2_P2_P")
	)
	(segment
		(start 9.350502 -354.77069)
		(end 9.166098 -354.955094)
		(width 0.127)
		(layer "B.Cu")
		(net "LAN2_P2_P")
	)
	(segment
		(start 9.166098 -353.824286)
		(end 9.166098 -354.205286)
		(width 0.127)
		(layer "B.Cu")
		(net "LAN2_P2_P")
	)
	(segment
		(start 8.333232 -390.17067)
		(end 13.101828 -394.939266)
		(width 0.127)
		(layer "B.Cu")
		(net "LAN2_P2_P")
	)
	(segment
		(start 9.166098 -355.336094)
		(end 9.350502 -355.520498)
		(width 0.127)
		(layer "B.Cu")
		(net "LAN2_P2_P")
	)
	(segment
		(start 9.166098 -353.074478)
		(end 9.350502 -353.258882)
		(width 0.127)
		(layer "B.Cu")
		(net "LAN2_P2_P")
	)
	(segment
		(start 9.350502 -355.520498)
		(end 9.350502 -355.901498)
		(width 0.127)
		(layer "B.Cu")
		(net "LAN2_P2_P")
	)
	(segment
		(start 13.101828 -394.939266)
		(end 13.101828 -399.65884)
		(width 0.127)
		(layer "B.Cu")
		(net "LAN2_P2_P")
	)
	(segment
		(start 13.147548 -406.149048)
		(end 14.034516 -407.036016)
		(width 0.127)
		(layer "B.Cu")
		(net "LAN2_P2_P")
	)
	(segment
		(start 9.166098 -356.085902)
		(end 9.166098 -356.466902)
		(width 0.127)
		(layer "B.Cu")
		(net "LAN2_P2_P")
	)
	(segment
		(start 8.725154 -348.840806)
		(end 9.350502 -349.466154)
		(width 0.127)
		(layer "B.Cu")
		(net "LAN2_P2_P")
	)
	(segment
		(start 9.166098 -357.21671)
		(end 9.166098 -357.59771)
		(width 0.127)
		(layer "B.Cu")
		(net "LAN2_P2_P")
	)
	(segment
		(start 9.350502 -357.032306)
		(end 9.166098 -357.21671)
		(width 0.127)
		(layer "B.Cu")
		(net "LAN2_P2_P")
	)
	(segment
		(start 9.166098 -357.59771)
		(end 9.350502 -357.782114)
		(width 0.127)
		(layer "B.Cu")
		(net "LAN2_P2_P")
	)
	(segment
		(start 9.350502 -353.258882)
		(end 9.350502 -353.639882)
		(width 0.127)
		(layer "B.Cu")
		(net "LAN2_P2_P")
	)
	(segment
		(start 6.698742 -347.85808)
		(end 7.681468 -348.840806)
		(width 0.127)
		(layer "B.Cu")
		(net "LAN2_P2_P")
	)
	(segment
		(start 9.350502 -355.901498)
		(end 9.166098 -356.085902)
		(width 0.127)
		(layer "B.Cu")
		(net "LAN2_P2_P")
	)
	(segment
		(start 9.166098 -352.693478)
		(end 9.166098 -353.074478)
		(width 0.127)
		(layer "B.Cu")
		(net "LAN2_P2_P")
	)
	(segment
		(start 13.147548 -403.768052)
		(end 13.147548 -406.149048)
		(width 0.127)
		(layer "B.Cu")
		(net "LAN2_P2_P")
	)
	(segment
		(start 9.350502 -349.466154)
		(end 9.350502 -352.509074)
		(width 0.127)
		(layer "B.Cu")
		(net "LAN2_P2_P")
	)
	(segment
		(start 8.333232 -359.5497)
		(end 8.333232 -390.17067)
		(width 0.127)
		(layer "B.Cu")
		(net "LAN2_P2_P")
	)
	(segment
		(start 9.166098 -354.955094)
		(end 9.166098 -355.336094)
		(width 0.127)
		(layer "B.Cu")
		(net "LAN2_P2_P")
	)
	(segment
		(start 9.350502 -356.651306)
		(end 9.350502 -357.032306)
		(width 0.127)
		(layer "B.Cu")
		(net "LAN2_P2_P")
	)
	(segment
		(start 12.560808 -400.19986)
		(end 12.560808 -403.181058)
		(width 0.127)
		(layer "B.Cu")
		(net "LAN2_P2_P")
	)
	(segment
		(start 3.189224 -348.146878)
		(end 3.216656 -348.092014)
		(width 0.127)
		(layer "B.Cu")
		(net "LAN2_P2_P")
	)
	(segment
		(start 9.166098 -354.205286)
		(end 9.350502 -354.38969)
		(width 0.127)
		(layer "B.Cu")
		(net "LAN2_P2_P")
	)
	(segment
		(start 9.350502 -357.782114)
		(end 9.350502 -358.53243)
		(width 0.127)
		(layer "B.Cu")
		(net "LAN2_P2_P")
	)
	(segment
		(start 3.45059 -347.85808)
		(end 6.698742 -347.85808)
		(width 0.127)
		(layer "B.Cu")
		(net "LAN2_P2_P")
	)
	(segment
		(start 9.350502 -354.38969)
		(end 9.350502 -354.77069)
		(width 0.127)
		(layer "B.Cu")
		(net "LAN2_P2_P")
	)
	(segment
		(start 3.949954 -348.669864)
		(end 3.245866 -348.317312)
		(width 0.127)
		(layer "B.Cu")
		(net "LAN2_P2_P")
	)
	(segment
		(start 9.350502 -358.53243)
		(end 8.333232 -359.5497)
		(width 0.127)
		(layer "B.Cu")
		(net "LAN2_P2_P")
	)
	(segment
		(start 14.810232 -411.034738)
		(end 15.67434 -410.17063)
		(width 0.127)
		(layer "B.Cu")
		(net "LAN2_P1_P")
	)
	(segment
		(start 2.535428 -350.914208)
		(end 2.535428 -350.287336)
		(width 0.127)
		(layer "B.Cu")
		(net "LAN2_P1_P")
	)
	(segment
		(start 3.293364 -349.5294)
		(end 4.70916 -349.5294)
		(width 0.127)
		(layer "B.Cu")
		(net "LAN2_P1_P")
	)
	(segment
		(start 12.617958 -411.034738)
		(end 14.810232 -411.034738)
		(width 0.127)
		(layer "B.Cu")
		(net "LAN2_P1_P")
	)
	(segment
		(start 4.70916 -349.5294)
		(end 5.44703 -350.26727)
		(width 0.127)
		(layer "B.Cu")
		(net "LAN2_P1_P")
	)
	(segment
		(start 15.67434 -410.17063)
		(end 15.67434 -409.826968)
		(width 0.127)
		(layer "B.Cu")
		(net "LAN2_P1_P")
	)
	(segment
		(start 2.654554 -351.033334)
		(end 2.535428 -350.914208)
		(width 0.127)
		(layer "B.Cu")
		(net "LAN2_P1_P")
	)
	(segment
		(start 15.423388 -409.576016)
		(end 14.034516 -409.576016)
		(width 0.127)
		(layer "B.Cu")
		(net "LAN2_P1_P")
	)
	(segment
		(start 2.654554 -351.317052)
		(end 2.711196 -351.146618)
		(width 0.127)
		(layer "B.Cu")
		(net "LAN2_P1_P")
	)
	(segment
		(start 5.44703 -350.26727)
		(end 5.44703 -403.86381)
		(width 0.127)
		(layer "B.Cu")
		(net "LAN2_P1_P")
	)
	(segment
		(start 5.44703 -403.86381)
		(end 12.617958 -411.034738)
		(width 0.127)
		(layer "B.Cu")
		(net "LAN2_P1_P")
	)
	(segment
		(start 1.949958 -351.669858)
		(end 2.654554 -351.317052)
		(width 0.127)
		(layer "B.Cu")
		(net "LAN2_P1_P")
	)
	(segment
		(start 2.535428 -350.287336)
		(end 3.293364 -349.5294)
		(width 0.127)
		(layer "B.Cu")
		(net "LAN2_P1_P")
	)
	(segment
		(start 15.67434 -409.826968)
		(end 15.423388 -409.576016)
		(width 0.127)
		(layer "B.Cu")
		(net "LAN2_P1_P")
	)
	(segment
		(start 2.711196 -351.146618)
		(end 2.654554 -351.033334)
		(width 0.127)
		(layer "B.Cu")
		(net "LAN2_P1_P")
	)
	(segment
		(start 3.949954 -350.66986)
		(end 3.245866 -351.022412)
		(width 0.127)
		(layer "B.Cu")
		(net "LAN2_P1_N")
	)
	(segment
		(start 2.988564 -350.792542)
		(end 2.941828 -350.745806)
		(width 0.127)
		(layer "B.Cu")
		(net "LAN2_P1_N")
	)
	(segment
		(start 5.04063 -404.032212)
		(end 12.449556 -411.441138)
		(width 0.127)
		(layer "B.Cu")
		(net "LAN2_P1_N")
	)
	(segment
		(start 3.461766 -349.9358)
		(end 4.540758 -349.9358)
		(width 0.127)
		(layer "B.Cu")
		(net "LAN2_P1_N")
	)
	(segment
		(start 16.08074 -409.658566)
		(end 15.84579 -409.423616)
		(width 0.127)
		(layer "B.Cu")
		(net "LAN2_P1_N")
	)
	(segment
		(start 15.84579 -409.034488)
		(end 16.574516 -408.306016)
		(width 0.127)
		(layer "B.Cu")
		(net "LAN2_P1_N")
	)
	(segment
		(start 2.941828 -350.745806)
		(end 2.941828 -350.455738)
		(width 0.127)
		(layer "B.Cu")
		(net "LAN2_P1_N")
	)
	(segment
		(start 4.540758 -349.9358)
		(end 5.04063 -350.435672)
		(width 0.127)
		(layer "B.Cu")
		(net "LAN2_P1_N")
	)
	(segment
		(start 3.075432 -350.965262)
		(end 3.018282 -350.85147)
		(width 0.127)
		(layer "B.Cu")
		(net "LAN2_P1_N")
	)
	(segment
		(start 3.018282 -350.85147)
		(end 3.018028 -350.85147)
		(width 0.127)
		(layer "B.Cu")
		(net "LAN2_P1_N")
	)
	(segment
		(start 2.941828 -350.455738)
		(end 3.461766 -349.9358)
		(width 0.127)
		(layer "B.Cu")
		(net "LAN2_P1_N")
	)
	(segment
		(start 14.978634 -411.441138)
		(end 16.08074 -410.339032)
		(width 0.127)
		(layer "B.Cu")
		(net "LAN2_P1_N")
	)
	(segment
		(start 3.018028 -350.85147)
		(end 2.988564 -350.792542)
		(width 0.127)
		(layer "B.Cu")
		(net "LAN2_P1_N")
	)
	(segment
		(start 3.245866 -351.022412)
		(end 3.075432 -350.965262)
		(width 0.127)
		(layer "B.Cu")
		(net "LAN2_P1_N")
	)
	(segment
		(start 5.04063 -350.435672)
		(end 5.04063 -404.032212)
		(width 0.127)
		(layer "B.Cu")
		(net "LAN2_P1_N")
	)
	(segment
		(start 16.08074 -410.339032)
		(end 16.08074 -409.658566)
		(width 0.127)
		(layer "B.Cu")
		(net "LAN2_P1_N")
	)
	(segment
		(start 15.84579 -409.423616)
		(end 15.84579 -409.034488)
		(width 0.127)
		(layer "B.Cu")
		(net "LAN2_P1_N")
	)
	(segment
		(start 12.449556 -411.441138)
		(end 14.978634 -411.441138)
		(width 0.127)
		(layer "B.Cu")
		(net "LAN2_P1_N")
	)
	(via
		(at 14.509496 -171.533058)
		(size 0.508)
		(drill 0.254)
		(layers "F.Cu" "B.Cu")
		(net "GND61")
	)
	(segment
		(start 13.209524 -187.791598)
		(end 13.209524 -172.07865)
		(width 0.1524)
		(layer "B.Cu")
		(net "GND61")
	)
	(segment
		(start 13.755116 -171.533058)
		(end 14.509496 -171.533058)
		(width 0.1524)
		(layer "B.Cu")
		(net "GND61")
	)
	(segment
		(start 10.323576 -190.677546)
		(end 13.209524 -187.791598)
		(width 0.1524)
		(layer "B.Cu")
		(net "GND61")
	)
	(segment
		(start 13.209524 -172.07865)
		(end 13.755116 -171.533058)
		(width 0.1524)
		(layer "B.Cu")
		(net "GND61")
	)
	(segment
		(start 8.455914 -190.677546)
		(end 10.323576 -190.677546)
		(width 0.1524)
		(layer "B.Cu")
		(net "GND61")
	)
	(segment
		(start 8.448802 -190.670434)
		(end 8.455914 -190.677546)
		(width 0.1524)
		(layer "B.Cu")
		(net "GND61")
	)
	(via
		(at 11.93292 -335.494122)
		(size 0.508)
		(drill 0.254)
		(layers "F.Cu" "B.Cu")
		(net "GND37")
	)
	(segment
		(start 10.757154 -336.669888)
		(end 11.93292 -335.494122)
		(width 0.127)
		(layer "In2.Cu")
		(net "GND37")
	)
	(segment
		(start 6.449822 -336.669888)
		(end 10.757154 -336.669888)
		(width 0.127)
		(layer "In2.Cu")
		(net "GND37")
	)
	(via
		(at 11.93292 -334.224122)
		(size 0.508)
		(drill 0.254)
		(layers "F.Cu" "B.Cu")
		(net "GND4")
	)
	(segment
		(start 7.917942 -334.873854)
		(end 11.283188 -334.873854)
		(width 0.127)
		(layer "In2.Cu")
		(net "GND4")
	)
	(segment
		(start 1.949958 -335.66989)
		(end 7.121906 -335.66989)
		(width 0.127)
		(layer "In2.Cu")
		(net "GND4")
	)
	(segment
		(start 11.283188 -334.873854)
		(end 11.93292 -334.224122)
		(width 0.127)
		(layer "In2.Cu")
		(net "GND4")
	)
	(segment
		(start 7.121906 -335.66989)
		(end 7.917942 -334.873854)
		(width 0.127)
		(layer "In2.Cu")
		(net "GND4")
	)
	(via
		(at 11.93292 -336.764122)
		(size 0.508)
		(drill 0.254)
		(layers "F.Cu" "B.Cu")
		(net "GND3")
	)
	(segment
		(start 4.833112 -337.786726)
		(end 7.091934 -337.786726)
		(width 0.127)
		(layer "In2.Cu")
		(net "GND3")
	)
	(segment
		(start 7.091934 -337.786726)
		(end 7.818628 -338.51342)
		(width 0.127)
		(layer "In2.Cu")
		(net "GND3")
	)
	(segment
		(start 3.949954 -338.669884)
		(end 4.833112 -337.786726)
		(width 0.127)
		(layer "In2.Cu")
		(net "GND3")
	)
	(segment
		(start 7.818628 -338.51342)
		(end 10.183622 -338.51342)
		(width 0.127)
		(layer "In2.Cu")
		(net "GND3")
	)
	(segment
		(start 10.183622 -338.51342)
		(end 11.93292 -336.764122)
		(width 0.127)
		(layer "In2.Cu")
		(net "GND3")
	)
	(segment
		(start 10.464038 -164.779706)
		(end 10.63625 -164.951918)
		(width 0.127)
		(layer "B.Cu")
		(net "LAN1_P3_P")
	)
	(segment
		(start 10.63625 -161.632646)
		(end 10.63625 -162.013646)
		(width 0.127)
		(layer "B.Cu")
		(net "LAN1_P3_P")
	)
	(segment
		(start 10.464038 -162.566858)
		(end 10.63625 -162.73907)
		(width 0.127)
		(layer "B.Cu")
		(net "LAN1_P3_P")
	)
	(segment
		(start 10.63625 -157.701234)
		(end 10.63625 -158.694374)
		(width 0.127)
		(layer "B.Cu")
		(net "LAN1_P3_P")
	)
	(segment
		(start 10.63625 -166.058342)
		(end 10.63625 -186.25185)
		(width 0.127)
		(layer "B.Cu")
		(net "LAN1_P3_P")
	)
	(segment
		(start 10.464038 -162.185858)
		(end 10.464038 -162.566858)
		(width 0.127)
		(layer "B.Cu")
		(net "LAN1_P3_P")
	)
	(segment
		(start 16.983964 -138.255502)
		(end 15.285974 -138.255502)
		(width 0.127)
		(layer "B.Cu")
		(net "LAN1_P3_P")
	)
	(segment
		(start 9.43864 -187.44946)
		(end 8.081264 -187.44946)
		(width 0.127)
		(layer "B.Cu")
		(net "LAN1_P3_P")
	)
	(segment
		(start 15.599918 -136.544812)
		(end 15.543276 -136.374378)
		(width 0.127)
		(layer "B.Cu")
		(net "LAN1_P3_P")
	)
	(segment
		(start 2.71018 -188.147198)
		(end 2.653538 -188.317632)
		(width 0.127)
		(layer "B.Cu")
		(net "LAN1_P3_P")
	)
	(segment
		(start 10.63625 -164.226494)
		(end 10.464038 -164.398706)
		(width 0.127)
		(layer "B.Cu")
		(net "LAN1_P3_P")
	)
	(segment
		(start 2.534412 -187.326016)
		(end 2.534412 -187.914788)
		(width 0.127)
		(layer "B.Cu")
		(net "LAN1_P3_P")
	)
	(segment
		(start 10.464038 -159.97301)
		(end 10.464038 -160.35401)
		(width 0.127)
		(layer "B.Cu")
		(net "LAN1_P3_P")
	)
	(segment
		(start 10.464038 -164.398706)
		(end 10.464038 -164.779706)
		(width 0.127)
		(layer "B.Cu")
		(net "LAN1_P3_P")
	)
	(segment
		(start 10.63625 -164.951918)
		(end 10.63625 -165.332918)
		(width 0.127)
		(layer "B.Cu")
		(net "LAN1_P3_P")
	)
	(segment
		(start 17.431512 -135.879078)
		(end 17.838674 -136.28624)
		(width 0.127)
		(layer "B.Cu")
		(net "LAN1_P3_P")
	)
	(segment
		(start 17.838674 -137.400792)
		(end 16.983964 -138.255502)
		(width 0.127)
		(layer "B.Cu")
		(net "LAN1_P3_P")
	)
	(segment
		(start 10.464038 -160.35401)
		(end 10.63625 -160.526222)
		(width 0.127)
		(layer "B.Cu")
		(net "LAN1_P3_P")
	)
	(segment
		(start 10.63625 -165.332918)
		(end 10.464038 -165.50513)
		(width 0.127)
		(layer "B.Cu")
		(net "LAN1_P3_P")
	)
	(segment
		(start 10.63625 -158.694374)
		(end 10.464038 -158.866586)
		(width 0.127)
		(layer "B.Cu")
		(net "LAN1_P3_P")
	)
	(segment
		(start 13.140944 -143.458438)
		(end 13.140944 -145.350992)
		(width 0.127)
		(layer "B.Cu")
		(net "LAN1_P3_P")
	)
	(segment
		(start 10.63625 -162.73907)
		(end 10.63625 -163.12007)
		(width 0.127)
		(layer "B.Cu")
		(net "LAN1_P3_P")
	)
	(segment
		(start 10.63625 -163.845494)
		(end 10.63625 -164.226494)
		(width 0.127)
		(layer "B.Cu")
		(net "LAN1_P3_P")
	)
	(segment
		(start 2.534412 -187.914788)
		(end 2.653538 -188.033914)
		(width 0.127)
		(layer "B.Cu")
		(net "LAN1_P3_P")
	)
	(segment
		(start 10.63625 -163.12007)
		(end 10.464038 -163.292282)
		(width 0.127)
		(layer "B.Cu")
		(net "LAN1_P3_P")
	)
	(segment
		(start 15.285974 -138.255502)
		(end 14.233906 -139.30757)
		(width 0.127)
		(layer "B.Cu")
		(net "LAN1_P3_P")
	)
	(segment
		(start 10.464038 -163.673282)
		(end 10.63625 -163.845494)
		(width 0.127)
		(layer "B.Cu")
		(net "LAN1_P3_P")
	)
	(segment
		(start 10.464038 -158.866586)
		(end 10.464038 -159.247586)
		(width 0.127)
		(layer "B.Cu")
		(net "LAN1_P3_P")
	)
	(segment
		(start 15.543276 -136.374378)
		(end 15.599918 -136.261348)
		(width 0.127)
		(layer "B.Cu")
		(net "LAN1_P3_P")
	)
	(segment
		(start 10.63625 -160.907222)
		(end 10.464038 -161.079434)
		(width 0.127)
		(layer "B.Cu")
		(net "LAN1_P3_P")
	)
	(segment
		(start 17.838674 -136.28624)
		(end 17.838674 -137.400792)
		(width 0.127)
		(layer "B.Cu")
		(net "LAN1_P3_P")
	)
	(segment
		(start 10.63625 -159.800798)
		(end 10.464038 -159.97301)
		(width 0.127)
		(layer "B.Cu")
		(net "LAN1_P3_P")
	)
	(segment
		(start 14.233906 -139.30757)
		(end 13.31087 -139.30757)
		(width 0.127)
		(layer "B.Cu")
		(net "LAN1_P3_P")
	)
	(segment
		(start 13.31087 -139.30757)
		(end 12.639294 -139.979146)
		(width 0.127)
		(layer "B.Cu")
		(net "LAN1_P3_P")
	)
	(segment
		(start 9.99744 -157.062424)
		(end 10.63625 -157.701234)
		(width 0.127)
		(layer "B.Cu")
		(net "LAN1_P3_P")
	)
	(segment
		(start 10.63625 -159.419798)
		(end 10.63625 -159.800798)
		(width 0.127)
		(layer "B.Cu")
		(net "LAN1_P3_P")
	)
	(segment
		(start 10.464038 -161.460434)
		(end 10.63625 -161.632646)
		(width 0.127)
		(layer "B.Cu")
		(net "LAN1_P3_P")
	)
	(segment
		(start 12.639294 -139.979146)
		(end 12.639294 -142.956788)
		(width 0.127)
		(layer "B.Cu")
		(net "LAN1_P3_P")
	)
	(segment
		(start 13.140944 -145.350992)
		(end 9.99744 -148.494496)
		(width 0.127)
		(layer "B.Cu")
		(net "LAN1_P3_P")
	)
	(segment
		(start 7.024116 -186.392312)
		(end 3.468116 -186.392312)
		(width 0.127)
		(layer "B.Cu")
		(net "LAN1_P3_P")
	)
	(segment
		(start 2.653538 -188.317632)
		(end 1.948942 -188.670438)
		(width 0.127)
		(layer "B.Cu")
		(net "LAN1_P3_P")
	)
	(segment
		(start 10.63625 -162.013646)
		(end 10.464038 -162.185858)
		(width 0.127)
		(layer "B.Cu")
		(net "LAN1_P3_P")
	)
	(segment
		(start 10.464038 -165.88613)
		(end 10.63625 -166.058342)
		(width 0.127)
		(layer "B.Cu")
		(net "LAN1_P3_P")
	)
	(segment
		(start 10.63625 -160.526222)
		(end 10.63625 -160.907222)
		(width 0.127)
		(layer "B.Cu")
		(net "LAN1_P3_P")
	)
	(segment
		(start 8.081264 -187.44946)
		(end 7.024116 -186.392312)
		(width 0.127)
		(layer "B.Cu")
		(net "LAN1_P3_P")
	)
	(segment
		(start 15.599918 -136.261348)
		(end 15.982188 -135.879078)
		(width 0.127)
		(layer "B.Cu")
		(net "LAN1_P3_P")
	)
	(segment
		(start 10.63625 -186.25185)
		(end 9.43864 -187.44946)
		(width 0.127)
		(layer "B.Cu")
		(net "LAN1_P3_P")
	)
	(segment
		(start 10.464038 -165.50513)
		(end 10.464038 -165.88613)
		(width 0.127)
		(layer "B.Cu")
		(net "LAN1_P3_P")
	)
	(segment
		(start 15.982188 -135.879078)
		(end 17.431512 -135.879078)
		(width 0.127)
		(layer "B.Cu")
		(net "LAN1_P3_P")
	)
	(segment
		(start 3.468116 -186.392312)
		(end 2.534412 -187.326016)
		(width 0.127)
		(layer "B.Cu")
		(net "LAN1_P3_P")
	)
	(segment
		(start 10.464038 -161.079434)
		(end 10.464038 -161.460434)
		(width 0.127)
		(layer "B.Cu")
		(net "LAN1_P3_P")
	)
	(segment
		(start 16.574516 -137.033)
		(end 15.599918 -136.544812)
		(width 0.127)
		(layer "B.Cu")
		(net "LAN1_P3_P")
	)
	(segment
		(start 10.464038 -163.292282)
		(end 10.464038 -163.673282)
		(width 0.127)
		(layer "B.Cu")
		(net "LAN1_P3_P")
	)
	(segment
		(start 10.464038 -159.247586)
		(end 10.63625 -159.419798)
		(width 0.127)
		(layer "B.Cu")
		(net "LAN1_P3_P")
	)
	(segment
		(start 12.639294 -142.956788)
		(end 13.140944 -143.458438)
		(width 0.127)
		(layer "B.Cu")
		(net "LAN1_P3_P")
	)
	(segment
		(start 2.653538 -188.033914)
		(end 2.71018 -188.147198)
		(width 0.127)
		(layer "B.Cu")
		(net "LAN1_P3_P")
	)
	(segment
		(start 9.99744 -148.494496)
		(end 9.99744 -157.062424)
		(width 0.127)
		(layer "B.Cu")
		(net "LAN1_P3_P")
	)
	(segment
		(start 10.568686 -132.581142)
		(end 10.299446 -132.850382)
		(width 0.127)
		(layer "B.Cu")
		(net "LAN1_P4_P")
	)
	(segment
		(start 3.102864 -184.07888)
		(end 3.317494 -184.29351)
		(width 0.127)
		(layer "B.Cu")
		(net "LAN1_P4_P")
	)
	(segment
		(start 9.03351 -133.88721)
		(end 9.03351 -134.116318)
		(width 0.127)
		(layer "B.Cu")
		(net "LAN1_P4_P")
	)
	(segment
		(start 7.406894 -177.714148)
		(end 5.21335 -179.907692)
		(width 0.127)
		(layer "B.Cu")
		(net "LAN1_P4_P")
	)
	(segment
		(start 5.21335 -179.907692)
		(end 5.21335 -182.106316)
		(width 0.127)
		(layer "B.Cu")
		(net "LAN1_P4_P")
	)
	(segment
		(start 5.21335 -182.106316)
		(end 4.432046 -182.88762)
		(width 0.127)
		(layer "B.Cu")
		(net "LAN1_P4_P")
	)
	(segment
		(start 9.801098 -133.34873)
		(end 9.531858 -133.61797)
		(width 0.127)
		(layer "B.Cu")
		(net "LAN1_P4_P")
	)
	(segment
		(start 6.94817 -174.934626)
		(end 7.406894 -175.39335)
		(width 0.127)
		(layer "B.Cu")
		(net "LAN1_P4_P")
	)
	(segment
		(start 5.207508 -151.020272)
		(end 6.94817 -152.760934)
		(width 0.127)
		(layer "B.Cu")
		(net "LAN1_P4_P")
	)
	(segment
		(start 14.798548 -132.458968)
		(end 14.798548 -132.057648)
		(width 0.127)
		(layer "B.Cu")
		(net "LAN1_P4_P")
	)
	(segment
		(start 7.996682 -135.153146)
		(end 7.767574 -135.153146)
		(width 0.127)
		(layer "B.Cu")
		(net "LAN1_P4_P")
	)
	(segment
		(start 10.299446 -132.850382)
		(end 10.070338 -132.850382)
		(width 0.127)
		(layer "B.Cu")
		(net "LAN1_P4_P")
	)
	(segment
		(start 8.535162 -134.385558)
		(end 8.265922 -134.654798)
		(width 0.127)
		(layer "B.Cu")
		(net "LAN1_P4_P")
	)
	(segment
		(start 11.427714 -131.493006)
		(end 10.568686 -132.352034)
		(width 0.127)
		(layer "B.Cu")
		(net "LAN1_P4_P")
	)
	(segment
		(start 3.410712 -182.88762)
		(end 3.102864 -183.195468)
		(width 0.127)
		(layer "B.Cu")
		(net "LAN1_P4_P")
	)
	(segment
		(start 14.034516 -133.223)
		(end 14.798548 -132.458968)
		(width 0.127)
		(layer "B.Cu")
		(net "LAN1_P4_P")
	)
	(segment
		(start 14.798548 -132.057648)
		(end 14.233906 -131.493006)
		(width 0.127)
		(layer "B.Cu")
		(net "LAN1_P4_P")
	)
	(segment
		(start 10.070338 -132.850382)
		(end 9.801098 -133.119622)
		(width 0.127)
		(layer "B.Cu")
		(net "LAN1_P4_P")
	)
	(segment
		(start 6.94817 -152.760934)
		(end 6.94817 -174.934626)
		(width 0.127)
		(layer "B.Cu")
		(net "LAN1_P4_P")
	)
	(segment
		(start 7.406894 -175.39335)
		(end 7.406894 -177.714148)
		(width 0.127)
		(layer "B.Cu")
		(net "LAN1_P4_P")
	)
	(segment
		(start 5.207508 -137.713212)
		(end 5.207508 -151.020272)
		(width 0.127)
		(layer "B.Cu")
		(net "LAN1_P4_P")
	)
	(segment
		(start 4.432046 -182.88762)
		(end 3.410712 -182.88762)
		(width 0.127)
		(layer "B.Cu")
		(net "LAN1_P4_P")
	)
	(segment
		(start 9.531858 -133.61797)
		(end 9.30275 -133.61797)
		(width 0.127)
		(layer "B.Cu")
		(net "LAN1_P4_P")
	)
	(segment
		(start 9.30275 -133.61797)
		(end 9.03351 -133.88721)
		(width 0.127)
		(layer "B.Cu")
		(net "LAN1_P4_P")
	)
	(segment
		(start 10.568686 -132.352034)
		(end 10.568686 -132.581142)
		(width 0.127)
		(layer "B.Cu")
		(net "LAN1_P4_P")
	)
	(segment
		(start 8.265922 -134.883906)
		(end 7.996682 -135.153146)
		(width 0.127)
		(layer "B.Cu")
		(net "LAN1_P4_P")
	)
	(segment
		(start 9.03351 -134.116318)
		(end 8.76427 -134.385558)
		(width 0.127)
		(layer "B.Cu")
		(net "LAN1_P4_P")
	)
	(segment
		(start 3.274822 -185.325004)
		(end 3.948938 -185.670444)
		(width 0.127)
		(layer "B.Cu")
		(net "LAN1_P4_P")
	)
	(segment
		(start 9.801098 -133.119622)
		(end 9.801098 -133.34873)
		(width 0.127)
		(layer "B.Cu")
		(net "LAN1_P4_P")
	)
	(segment
		(start 7.498334 -135.422386)
		(end 7.498334 -135.651494)
		(width 0.127)
		(layer "B.Cu")
		(net "LAN1_P4_P")
	)
	(segment
		(start 14.233906 -131.493006)
		(end 11.427714 -131.493006)
		(width 0.127)
		(layer "B.Cu")
		(net "LAN1_P4_P")
	)
	(segment
		(start 3.317494 -184.29351)
		(end 3.317494 -184.955942)
		(width 0.127)
		(layer "B.Cu")
		(net "LAN1_P4_P")
	)
	(segment
		(start 7.498334 -135.651494)
		(end 7.229094 -135.920734)
		(width 0.127)
		(layer "B.Cu")
		(net "LAN1_P4_P")
	)
	(segment
		(start 7.767574 -135.153146)
		(end 7.498334 -135.422386)
		(width 0.127)
		(layer "B.Cu")
		(net "LAN1_P4_P")
	)
	(segment
		(start 3.317494 -184.955942)
		(end 3.21818 -185.15457)
		(width 0.127)
		(layer "B.Cu")
		(net "LAN1_P4_P")
	)
	(segment
		(start 8.265922 -134.654798)
		(end 8.265922 -134.883906)
		(width 0.127)
		(layer "B.Cu")
		(net "LAN1_P4_P")
	)
	(segment
		(start 7.229094 -135.920734)
		(end 6.999986 -135.920734)
		(width 0.127)
		(layer "B.Cu")
		(net "LAN1_P4_P")
	)
	(segment
		(start 3.102864 -183.195468)
		(end 3.102864 -184.07888)
		(width 0.127)
		(layer "B.Cu")
		(net "LAN1_P4_P")
	)
	(segment
		(start 6.999986 -135.920734)
		(end 5.207508 -137.713212)
		(width 0.127)
		(layer "B.Cu")
		(net "LAN1_P4_P")
	)
	(segment
		(start 8.76427 -134.385558)
		(end 8.535162 -134.385558)
		(width 0.127)
		(layer "B.Cu")
		(net "LAN1_P4_P")
	)
	(segment
		(start 3.21818 -185.15457)
		(end 3.274822 -185.325004)
		(width 0.127)
		(layer "B.Cu")
		(net "LAN1_P4_P")
	)
	(segment
		(start 1.347724 -36.342066)
		(end 1.347724 -176.977802)
		(width 0.1524)
		(layer "F.Cu")
		(net "CM_PWR_CTL_IN")
	)
	(segment
		(start 2.661158 -181.958234)
		(end 1.948942 -182.67045)
		(width 0.1524)
		(layer "F.Cu")
		(net "CM_PWR_CTL_IN")
	)
	(segment
		(start 1.347724 -176.977802)
		(end 2.661158 -178.291236)
		(width 0.1524)
		(layer "F.Cu")
		(net "CM_PWR_CTL_IN")
	)
	(segment
		(start 2.661158 -178.291236)
		(end 2.661158 -181.958234)
		(width 0.1524)
		(layer "F.Cu")
		(net "CM_PWR_CTL_IN")
	)
	(segment
		(start 5.780024 -31.909766)
		(end 1.347724 -36.342066)
		(width 0.1524)
		(layer "F.Cu")
		(net "CM_PWR_CTL_IN")
	)
	(segment
		(start 13.045694 -140.147548)
		(end 13.045694 -142.788386)
		(width 0.127)
		(layer "B.Cu")
		(net "LAN1_P3_N")
	)
	(segment
		(start 3.24485 -188.022992)
		(end 3.948938 -187.67044)
		(width 0.127)
		(layer "B.Cu")
		(net "LAN1_P3_N")
	)
	(segment
		(start 10.40384 -148.662898)
		(end 10.40384 -156.894022)
		(width 0.127)
		(layer "B.Cu")
		(net "LAN1_P3_N")
	)
	(segment
		(start 3.017266 -187.85205)
		(end 3.074416 -187.965842)
		(width 0.127)
		(layer "B.Cu")
		(net "LAN1_P3_N")
	)
	(segment
		(start 15.265908 -136.020302)
		(end 15.813786 -135.472678)
		(width 0.127)
		(layer "B.Cu")
		(net "LAN1_P3_N")
	)
	(segment
		(start 13.547344 -143.290036)
		(end 13.547344 -145.519394)
		(width 0.127)
		(layer "B.Cu")
		(net "LAN1_P3_N")
	)
	(segment
		(start 18.245074 -136.117838)
		(end 18.245074 -137.569194)
		(width 0.127)
		(layer "B.Cu")
		(net "LAN1_P3_N")
	)
	(segment
		(start 2.987548 -187.793122)
		(end 3.017012 -187.85205)
		(width 0.127)
		(layer "B.Cu")
		(net "LAN1_P3_N")
	)
	(segment
		(start 13.547344 -145.519394)
		(end 10.40384 -148.662898)
		(width 0.127)
		(layer "B.Cu")
		(net "LAN1_P3_N")
	)
	(segment
		(start 18.245074 -137.569194)
		(end 17.152366 -138.661902)
		(width 0.127)
		(layer "B.Cu")
		(net "LAN1_P3_N")
	)
	(segment
		(start 15.008606 -136.25068)
		(end 15.17904 -136.19353)
		(width 0.127)
		(layer "B.Cu")
		(net "LAN1_P3_N")
	)
	(segment
		(start 13.479272 -139.71397)
		(end 13.045694 -140.147548)
		(width 0.127)
		(layer "B.Cu")
		(net "LAN1_P3_N")
	)
	(segment
		(start 17.599914 -135.472678)
		(end 18.245074 -136.117838)
		(width 0.127)
		(layer "B.Cu")
		(net "LAN1_P3_N")
	)
	(segment
		(start 10.40384 -156.894022)
		(end 11.04265 -157.532832)
		(width 0.127)
		(layer "B.Cu")
		(net "LAN1_P3_N")
	)
	(segment
		(start 9.607042 -187.85586)
		(end 7.912862 -187.85586)
		(width 0.127)
		(layer "B.Cu")
		(net "LAN1_P3_N")
	)
	(segment
		(start 3.074416 -187.965842)
		(end 3.24485 -188.022992)
		(width 0.127)
		(layer "B.Cu")
		(net "LAN1_P3_N")
	)
	(segment
		(start 15.813786 -135.472678)
		(end 17.599914 -135.472678)
		(width 0.127)
		(layer "B.Cu")
		(net "LAN1_P3_N")
	)
	(segment
		(start 11.04265 -186.420252)
		(end 9.607042 -187.85586)
		(width 0.127)
		(layer "B.Cu")
		(net "LAN1_P3_N")
	)
	(segment
		(start 13.045694 -142.788386)
		(end 13.547344 -143.290036)
		(width 0.127)
		(layer "B.Cu")
		(net "LAN1_P3_N")
	)
	(segment
		(start 14.402308 -139.71397)
		(end 13.479272 -139.71397)
		(width 0.127)
		(layer "B.Cu")
		(net "LAN1_P3_N")
	)
	(segment
		(start 2.940812 -187.746386)
		(end 2.987548 -187.793122)
		(width 0.127)
		(layer "B.Cu")
		(net "LAN1_P3_N")
	)
	(segment
		(start 15.23619 -136.079484)
		(end 15.265908 -136.020302)
		(width 0.127)
		(layer "B.Cu")
		(net "LAN1_P3_N")
	)
	(segment
		(start 6.855714 -186.798712)
		(end 3.636518 -186.798712)
		(width 0.127)
		(layer "B.Cu")
		(net "LAN1_P3_N")
	)
	(segment
		(start 11.04265 -157.532832)
		(end 11.04265 -186.420252)
		(width 0.127)
		(layer "B.Cu")
		(net "LAN1_P3_N")
	)
	(segment
		(start 15.17904 -136.19353)
		(end 15.23619 -136.079484)
		(width 0.127)
		(layer "B.Cu")
		(net "LAN1_P3_N")
	)
	(segment
		(start 17.152366 -138.661902)
		(end 15.454376 -138.661902)
		(width 0.127)
		(layer "B.Cu")
		(net "LAN1_P3_N")
	)
	(segment
		(start 3.017012 -187.85205)
		(end 3.017266 -187.85205)
		(width 0.127)
		(layer "B.Cu")
		(net "LAN1_P3_N")
	)
	(segment
		(start 15.454376 -138.661902)
		(end 14.402308 -139.71397)
		(width 0.127)
		(layer "B.Cu")
		(net "LAN1_P3_N")
	)
	(segment
		(start 14.034516 -135.763)
		(end 15.008606 -136.25068)
		(width 0.127)
		(layer "B.Cu")
		(net "LAN1_P3_N")
	)
	(segment
		(start 7.912862 -187.85586)
		(end 6.855714 -186.798712)
		(width 0.127)
		(layer "B.Cu")
		(net "LAN1_P3_N")
	)
	(segment
		(start 3.636518 -186.798712)
		(end 2.940812 -187.494418)
		(width 0.127)
		(layer "B.Cu")
		(net "LAN1_P3_N")
	)
	(segment
		(start 2.940812 -187.494418)
		(end 2.940812 -187.746386)
		(width 0.127)
		(layer "B.Cu")
		(net "LAN1_P3_N")
	)
	(segment
		(start 4.263644 -182.48122)
		(end 3.24231 -182.48122)
		(width 0.127)
		(layer "B.Cu")
		(net "LAN1_P4_N")
	)
	(segment
		(start 6.54177 -152.929336)
		(end 6.54177 -175.103028)
		(width 0.127)
		(layer "B.Cu")
		(net "LAN1_P4_N")
	)
	(segment
		(start 4.801108 -151.188674)
		(end 6.54177 -152.929336)
		(width 0.127)
		(layer "B.Cu")
		(net "LAN1_P4_N")
	)
	(segment
		(start 2.911094 -184.85993)
		(end 2.854452 -184.97296)
		(width 0.127)
		(layer "B.Cu")
		(net "LAN1_P4_N")
	)
	(segment
		(start 4.801108 -137.54481)
		(end 4.801108 -151.188674)
		(width 0.127)
		(layer "B.Cu")
		(net "LAN1_P4_N")
	)
	(segment
		(start 4.80695 -181.937914)
		(end 4.263644 -182.48122)
		(width 0.127)
		(layer "B.Cu")
		(net "LAN1_P4_N")
	)
	(segment
		(start 11.259312 -131.086606)
		(end 4.801108 -137.54481)
		(width 0.127)
		(layer "B.Cu")
		(net "LAN1_P4_N")
	)
	(segment
		(start 14.402308 -131.086606)
		(end 11.259312 -131.086606)
		(width 0.127)
		(layer "B.Cu")
		(net "LAN1_P4_N")
	)
	(segment
		(start 2.68351 -185.030364)
		(end 1.948942 -184.670446)
		(width 0.127)
		(layer "B.Cu")
		(net "LAN1_P4_N")
	)
	(segment
		(start 15.268702 -131.953)
		(end 14.402308 -131.086606)
		(width 0.127)
		(layer "B.Cu")
		(net "LAN1_P4_N")
	)
	(segment
		(start 2.853944 -184.973214)
		(end 2.68351 -185.030364)
		(width 0.127)
		(layer "B.Cu")
		(net "LAN1_P4_N")
	)
	(segment
		(start 4.80695 -179.73929)
		(end 4.80695 -181.937914)
		(width 0.127)
		(layer "B.Cu")
		(net "LAN1_P4_N")
	)
	(segment
		(start 2.854452 -184.97296)
		(end 2.853944 -184.973214)
		(width 0.127)
		(layer "B.Cu")
		(net "LAN1_P4_N")
	)
	(segment
		(start 2.696464 -184.247282)
		(end 2.911094 -184.461912)
		(width 0.127)
		(layer "B.Cu")
		(net "LAN1_P4_N")
	)
	(segment
		(start 6.54177 -175.103028)
		(end 7.000494 -175.561752)
		(width 0.127)
		(layer "B.Cu")
		(net "LAN1_P4_N")
	)
	(segment
		(start 2.696464 -183.027066)
		(end 2.696464 -184.247282)
		(width 0.127)
		(layer "B.Cu")
		(net "LAN1_P4_N")
	)
	(segment
		(start 16.574516 -131.953)
		(end 15.268702 -131.953)
		(width 0.127)
		(layer "B.Cu")
		(net "LAN1_P4_N")
	)
	(segment
		(start 7.000494 -175.561752)
		(end 7.000494 -177.545746)
		(width 0.127)
		(layer "B.Cu")
		(net "LAN1_P4_N")
	)
	(segment
		(start 7.000494 -177.545746)
		(end 4.80695 -179.73929)
		(width 0.127)
		(layer "B.Cu")
		(net "LAN1_P4_N")
	)
	(segment
		(start 3.24231 -182.48122)
		(end 2.696464 -183.027066)
		(width 0.127)
		(layer "B.Cu")
		(net "LAN1_P4_N")
	)
	(segment
		(start 2.911094 -184.461912)
		(end 2.911094 -184.85993)
		(width 0.127)
		(layer "B.Cu")
		(net "LAN1_P4_N")
	)
	(segment
		(start 10.738612 -178.432968)
		(end 20.287234 -168.884346)
		(width 0.127)
		(layer "In2.Cu")
		(net "UART_RX_P1_L")
	)
	(segment
		(start 12.985496 -111.682022)
		(end 12.985496 -106.9594)
		(width 0.127)
		(layer "In2.Cu")
		(net "UART_RX_P1_L")
	)
	(segment
		(start 12.215368 -17.116298)
		(end 13.964666 -15.367)
		(width 0.127)
		(layer "In2.Cu")
		(net "UART_RX_P1_L")
	)
	(segment
		(start 11.804904 -61.495686)
		(end 19.048476 -54.252114)
		(width 0.127)
		(layer "In2.Cu")
		(net "UART_RX_P1_L")
	)
	(segment
		(start 14.884908 -88.335358)
		(end 14.884908 -75.707494)
		(width 0.127)
		(layer "In2.Cu")
		(net "UART_RX_P1_L")
	)
	(segment
		(start 4.454906 -198.670418)
		(end 4.99364 -198.131684)
		(width 0.127)
		(layer "In2.Cu")
		(net "UART_RX_P1_L")
	)
	(segment
		(start 19.048476 -54.252114)
		(end 19.048476 -41.618662)
		(width 0.127)
		(layer "In2.Cu")
		(net "UART_RX_P1_L")
	)
	(segment
		(start 9.586214 -115.081304)
		(end 12.985496 -111.682022)
		(width 0.127)
		(layer "In2.Cu")
		(net "UART_RX_P1_L")
	)
	(segment
		(start 20.287234 -131.671314)
		(end 9.586214 -120.970294)
		(width 0.127)
		(layer "In2.Cu")
		(net "UART_RX_P1_L")
	)
	(segment
		(start 11.761216 -105.73512)
		(end 11.761216 -91.45905)
		(width 0.127)
		(layer "In2.Cu")
		(net "UART_RX_P1_L")
	)
	(segment
		(start 14.884908 -75.707494)
		(end 11.804904 -72.62749)
		(width 0.127)
		(layer "In2.Cu")
		(net "UART_RX_P1_L")
	)
	(segment
		(start 4.99364 -198.131684)
		(end 4.99364 -193.905124)
		(width 0.127)
		(layer "In2.Cu")
		(net "UART_RX_P1_L")
	)
	(segment
		(start 10.149586 -21.833078)
		(end 12.215368 -19.767296)
		(width 0.127)
		(layer "In2.Cu")
		(net "UART_RX_P1_L")
	)
	(segment
		(start 19.048476 -41.618662)
		(end 10.149586 -32.719772)
		(width 0.127)
		(layer "In2.Cu")
		(net "UART_RX_P1_L")
	)
	(segment
		(start 7.9121 -191.947546)
		(end 8.879078 -191.947546)
		(width 0.127)
		(layer "In2.Cu")
		(net "UART_RX_P1_L")
	)
	(segment
		(start 20.287234 -168.884346)
		(end 20.287234 -131.671314)
		(width 0.127)
		(layer "In2.Cu")
		(net "UART_RX_P1_L")
	)
	(segment
		(start 6.126226 -192.772538)
		(end 7.087108 -192.772538)
		(width 0.127)
		(layer "In2.Cu")
		(net "UART_RX_P1_L")
	)
	(segment
		(start 10.738612 -190.088012)
		(end 10.738612 -178.432968)
		(width 0.127)
		(layer "In2.Cu")
		(net "UART_RX_P1_L")
	)
	(segment
		(start 10.149586 -32.719772)
		(end 10.149586 -21.833078)
		(width 0.127)
		(layer "In2.Cu")
		(net "UART_RX_P1_L")
	)
	(segment
		(start 8.879078 -191.947546)
		(end 10.738612 -190.088012)
		(width 0.127)
		(layer "In2.Cu")
		(net "UART_RX_P1_L")
	)
	(segment
		(start 9.586214 -120.970294)
		(end 9.586214 -115.081304)
		(width 0.127)
		(layer "In2.Cu")
		(net "UART_RX_P1_L")
	)
	(segment
		(start 12.215368 -19.767296)
		(end 12.215368 -17.116298)
		(width 0.127)
		(layer "In2.Cu")
		(net "UART_RX_P1_L")
	)
	(segment
		(start 1.948942 -198.670418)
		(end 4.454906 -198.670418)
		(width 0.127)
		(layer "In2.Cu")
		(net "UART_RX_P1_L")
	)
	(segment
		(start 12.985496 -106.9594)
		(end 11.761216 -105.73512)
		(width 0.127)
		(layer "In2.Cu")
		(net "UART_RX_P1_L")
	)
	(segment
		(start 4.99364 -193.905124)
		(end 6.126226 -192.772538)
		(width 0.127)
		(layer "In2.Cu")
		(net "UART_RX_P1_L")
	)
	(segment
		(start 11.761216 -91.45905)
		(end 14.884908 -88.335358)
		(width 0.127)
		(layer "In2.Cu")
		(net "UART_RX_P1_L")
	)
	(segment
		(start 7.087108 -192.772538)
		(end 7.9121 -191.947546)
		(width 0.127)
		(layer "In2.Cu")
		(net "UART_RX_P1_L")
	)
	(segment
		(start 11.804904 -72.62749)
		(end 11.804904 -61.495686)
		(width 0.127)
		(layer "In2.Cu")
		(net "UART_RX_P1_L")
	)
	(segment
		(start 13.964666 -11.211052)
		(end 11.224768 -13.95095)
		(width 0.127)
		(layer "In2.Cu")
		(net "UART_DTR_P1_L_N")
	)
	(segment
		(start 11.994896 -107.370118)
		(end 11.994896 -111.271304)
		(width 0.127)
		(layer "In2.Cu")
		(net "UART_DTR_P1_L_N")
	)
	(segment
		(start 19.296634 -132.082032)
		(end 19.296634 -168.473628)
		(width 0.127)
		(layer "In2.Cu")
		(net "UART_DTR_P1_L_N")
	)
	(segment
		(start 10.770616 -106.145838)
		(end 11.994896 -107.370118)
		(width 0.127)
		(layer "In2.Cu")
		(net "UART_DTR_P1_L_N")
	)
	(segment
		(start 10.770616 -91.048332)
		(end 10.770616 -106.145838)
		(width 0.127)
		(layer "In2.Cu")
		(net "UART_DTR_P1_L_N")
	)
	(segment
		(start 4.344924 -192.500758)
		(end 3.374644 -192.500758)
		(width 0.127)
		(layer "In2.Cu")
		(net "UART_DTR_P1_L_N")
	)
	(segment
		(start 2.726944 -193.148712)
		(end 2.726944 -193.148966)
		(width 0.127)
		(layer "In2.Cu")
		(net "UART_DTR_P1_L_N")
	)
	(segment
		(start 2.726944 -193.148966)
		(end 2.710688 -193.165222)
		(width 0.127)
		(layer "In2.Cu")
		(net "UART_DTR_P1_L_N")
	)
	(segment
		(start 9.158986 -21.42236)
		(end 9.158986 -33.130744)
		(width 0.127)
		(layer "In2.Cu")
		(net "UART_DTR_P1_L_N")
	)
	(segment
		(start 3.374644 -192.500758)
		(end 2.726944 -193.148712)
		(width 0.127)
		(layer "In2.Cu")
		(net "UART_DTR_P1_L_N")
	)
	(segment
		(start 8.595614 -114.670586)
		(end 8.595614 -121.381012)
		(width 0.127)
		(layer "In2.Cu")
		(net "UART_DTR_P1_L_N")
	)
	(segment
		(start 8.965184 -189.530736)
		(end 7.82955 -189.530736)
		(width 0.127)
		(layer "In2.Cu")
		(net "UART_DTR_P1_L_N")
	)
	(segment
		(start 2.710688 -193.165222)
		(end 2.710688 -195.908676)
		(width 0.127)
		(layer "In2.Cu")
		(net "UART_DTR_P1_L_N")
	)
	(segment
		(start 13.894308 -76.118212)
		(end 13.894308 -87.92464)
		(width 0.127)
		(layer "In2.Cu")
		(net "UART_DTR_P1_L_N")
	)
	(segment
		(start 11.224768 -13.95095)
		(end 11.224768 -19.356578)
		(width 0.127)
		(layer "In2.Cu")
		(net "UART_DTR_P1_L_N")
	)
	(segment
		(start 5.907786 -190.443104)
		(end 4.946904 -191.403986)
		(width 0.127)
		(layer "In2.Cu")
		(net "UART_DTR_P1_L_N")
	)
	(segment
		(start 9.723374 -178.046888)
		(end 9.723374 -188.772546)
		(width 0.127)
		(layer "In2.Cu")
		(net "UART_DTR_P1_L_N")
	)
	(segment
		(start 11.994896 -111.271304)
		(end 8.595614 -114.670586)
		(width 0.127)
		(layer "In2.Cu")
		(net "UART_DTR_P1_L_N")
	)
	(segment
		(start 9.723374 -188.772546)
		(end 8.965184 -189.530736)
		(width 0.127)
		(layer "In2.Cu")
		(net "UART_DTR_P1_L_N")
	)
	(segment
		(start 19.296634 -168.473628)
		(end 9.723374 -178.046888)
		(width 0.127)
		(layer "In2.Cu")
		(net "UART_DTR_P1_L_N")
	)
	(segment
		(start 10.814304 -61.084714)
		(end 10.814304 -73.038208)
		(width 0.127)
		(layer "In2.Cu")
		(net "UART_DTR_P1_L_N")
	)
	(segment
		(start 4.946904 -191.403986)
		(end 4.946904 -191.898778)
		(width 0.127)
		(layer "In2.Cu")
		(net "UART_DTR_P1_L_N")
	)
	(segment
		(start 18.057876 -53.841142)
		(end 10.814304 -61.084714)
		(width 0.127)
		(layer "In2.Cu")
		(net "UART_DTR_P1_L_N")
	)
	(segment
		(start 8.595614 -121.381012)
		(end 19.296634 -132.082032)
		(width 0.127)
		(layer "In2.Cu")
		(net "UART_DTR_P1_L_N")
	)
	(segment
		(start 9.158986 -33.130744)
		(end 18.057876 -42.029634)
		(width 0.127)
		(layer "In2.Cu")
		(net "UART_DTR_P1_L_N")
	)
	(segment
		(start 10.814304 -73.038208)
		(end 13.894308 -76.118212)
		(width 0.127)
		(layer "In2.Cu")
		(net "UART_DTR_P1_L_N")
	)
	(segment
		(start 7.82955 -189.530736)
		(end 6.917182 -190.443104)
		(width 0.127)
		(layer "In2.Cu")
		(net "UART_DTR_P1_L_N")
	)
	(segment
		(start 13.964666 -10.287)
		(end 13.964666 -11.211052)
		(width 0.127)
		(layer "In2.Cu")
		(net "UART_DTR_P1_L_N")
	)
	(segment
		(start 18.057876 -42.029634)
		(end 18.057876 -53.841142)
		(width 0.127)
		(layer "In2.Cu")
		(net "UART_DTR_P1_L_N")
	)
	(segment
		(start 4.946904 -191.898778)
		(end 4.344924 -192.500758)
		(width 0.127)
		(layer "In2.Cu")
		(net "UART_DTR_P1_L_N")
	)
	(segment
		(start 2.710688 -195.908676)
		(end 1.948942 -196.670422)
		(width 0.127)
		(layer "In2.Cu")
		(net "UART_DTR_P1_L_N")
	)
	(segment
		(start 13.894308 -87.92464)
		(end 10.770616 -91.048332)
		(width 0.127)
		(layer "In2.Cu")
		(net "UART_DTR_P1_L_N")
	)
	(segment
		(start 11.224768 -19.356578)
		(end 9.158986 -21.42236)
		(width 0.127)
		(layer "In2.Cu")
		(net "UART_DTR_P1_L_N")
	)
	(segment
		(start 6.917182 -190.443104)
		(end 5.907786 -190.443104)
		(width 0.127)
		(layer "In2.Cu")
		(net "UART_DTR_P1_L_N")
	)
	(segment
		(start 4.8006 -94.153482)
		(end 4.8006 -111.709454)
		(width 0.127)
		(layer "In5.Cu")
		(net "UART_RX_P5_L")
	)
	(segment
		(start 8.506714 -92.59824)
		(end 6.355842 -92.59824)
		(width 0.127)
		(layer "In5.Cu")
		(net "UART_RX_P5_L")
	)
	(segment
		(start 11.758168 -70.659498)
		(end 11.758168 -73.643744)
		(width 0.127)
		(layer "In5.Cu")
		(net "UART_RX_P5_L")
	)
	(segment
		(start 20.719288 -159.927036)
		(end 11.254232 -169.392092)
		(width 0.127)
		(layer "In5.Cu")
		(net "UART_RX_P5_L")
	)
	(segment
		(start 4.093718 -206.670656)
		(end 1.948942 -206.670656)
		(width 0.127)
		(layer "In5.Cu")
		(net "UART_RX_P5_L")
	)
	(segment
		(start 8.259826 -115.16868)
		(end 8.259826 -121.36247)
		(width 0.127)
		(layer "In5.Cu")
		(net "UART_RX_P5_L")
	)
	(segment
		(start 13.964666 -68.453)
		(end 11.758168 -70.659498)
		(width 0.127)
		(layer "In5.Cu")
		(net "UART_RX_P5_L")
	)
	(segment
		(start 8.259826 -121.36247)
		(end 16.356584 -129.459228)
		(width 0.127)
		(layer "In5.Cu")
		(net "UART_RX_P5_L")
	)
	(segment
		(start 11.254232 -190.394844)
		(end 9.712706 -191.93637)
		(width 0.127)
		(layer "In5.Cu")
		(net "UART_RX_P5_L")
	)
	(segment
		(start 11.254232 -169.392092)
		(end 11.254232 -190.394844)
		(width 0.127)
		(layer "In5.Cu")
		(net "UART_RX_P5_L")
	)
	(segment
		(start 10.536428 -74.865484)
		(end 10.536428 -90.568526)
		(width 0.127)
		(layer "In5.Cu")
		(net "UART_RX_P5_L")
	)
	(segment
		(start 17.370044 -129.459228)
		(end 20.719288 -132.808472)
		(width 0.127)
		(layer "In5.Cu")
		(net "UART_RX_P5_L")
	)
	(segment
		(start 9.712706 -191.93637)
		(end 8.05815 -191.93637)
		(width 0.127)
		(layer "In5.Cu")
		(net "UART_RX_P5_L")
	)
	(segment
		(start 20.719288 -132.808472)
		(end 20.719288 -159.927036)
		(width 0.127)
		(layer "In5.Cu")
		(net "UART_RX_P5_L")
	)
	(segment
		(start 5.046218 -193.77025)
		(end 5.046218 -205.718156)
		(width 0.127)
		(layer "In5.Cu")
		(net "UART_RX_P5_L")
	)
	(segment
		(start 4.8006 -111.709454)
		(end 8.259826 -115.16868)
		(width 0.127)
		(layer "In5.Cu")
		(net "UART_RX_P5_L")
	)
	(segment
		(start 6.355842 -92.59824)
		(end 4.8006 -94.153482)
		(width 0.127)
		(layer "In5.Cu")
		(net "UART_RX_P5_L")
	)
	(segment
		(start 10.536428 -90.568526)
		(end 8.506714 -92.59824)
		(width 0.127)
		(layer "In5.Cu")
		(net "UART_RX_P5_L")
	)
	(segment
		(start 5.989828 -192.82664)
		(end 5.046218 -193.77025)
		(width 0.127)
		(layer "In5.Cu")
		(net "UART_RX_P5_L")
	)
	(segment
		(start 7.16788 -192.82664)
		(end 5.989828 -192.82664)
		(width 0.127)
		(layer "In5.Cu")
		(net "UART_RX_P5_L")
	)
	(segment
		(start 16.356584 -129.459228)
		(end 17.370044 -129.459228)
		(width 0.127)
		(layer "In5.Cu")
		(net "UART_RX_P5_L")
	)
	(segment
		(start 8.05815 -191.93637)
		(end 7.16788 -192.82664)
		(width 0.127)
		(layer "In5.Cu")
		(net "UART_RX_P5_L")
	)
	(segment
		(start 11.758168 -73.643744)
		(end 10.536428 -74.865484)
		(width 0.127)
		(layer "In5.Cu")
		(net "UART_RX_P5_L")
	)
	(segment
		(start 5.046218 -205.718156)
		(end 4.093718 -206.670656)
		(width 0.127)
		(layer "In5.Cu")
		(net "UART_RX_P5_L")
	)
	(segment
		(start 12.875768 -20.041108)
		(end 12.875768 -18.995898)
		(width 0.127)
		(layer "In2.Cu")
		(net "UART_RTS_P1_L_N")
	)
	(segment
		(start 7.14502 -194.859148)
		(end 8.159496 -193.844672)
		(width 0.127)
		(layer "In2.Cu")
		(net "UART_RTS_P1_L_N")
	)
	(segment
		(start 12.426442 -105.459276)
		(end 12.426442 -91.734894)
		(width 0.127)
		(layer "In2.Cu")
		(net "UART_RTS_P1_L_N")
	)
	(segment
		(start 15.550134 -75.43165)
		(end 12.465304 -72.34682)
		(width 0.127)
		(layer "In2.Cu")
		(net "UART_RTS_P1_L_N")
	)
	(segment
		(start 20.947634 -131.397502)
		(end 10.246614 -120.696482)
		(width 0.127)
		(layer "In2.Cu")
		(net "UART_RTS_P1_L_N")
	)
	(segment
		(start 9.057386 -193.844672)
		(end 11.399012 -191.503046)
		(width 0.127)
		(layer "In2.Cu")
		(net "UART_RTS_P1_L_N")
	)
	(segment
		(start 13.645896 -106.67873)
		(end 12.426442 -105.459276)
		(width 0.127)
		(layer "In2.Cu")
		(net "UART_RTS_P1_L_N")
	)
	(segment
		(start 5.971286 -194.859148)
		(end 7.14502 -194.859148)
		(width 0.127)
		(layer "In2.Cu")
		(net "UART_RTS_P1_L_N")
	)
	(segment
		(start 12.875768 -18.995898)
		(end 13.964666 -17.907)
		(width 0.127)
		(layer "In2.Cu")
		(net "UART_RTS_P1_L_N")
	)
	(segment
		(start 19.708876 -41.34485)
		(end 10.809986 -32.44596)
		(width 0.127)
		(layer "In2.Cu")
		(net "UART_RTS_P1_L_N")
	)
	(segment
		(start 5.65404 -195.176394)
		(end 5.971286 -194.859148)
		(width 0.127)
		(layer "In2.Cu")
		(net "UART_RTS_P1_L_N")
	)
	(segment
		(start 13.645896 -111.956088)
		(end 13.645896 -106.67873)
		(width 0.127)
		(layer "In2.Cu")
		(net "UART_RTS_P1_L_N")
	)
	(segment
		(start 11.399012 -191.503046)
		(end 11.399012 -178.70678)
		(width 0.127)
		(layer "In2.Cu")
		(net "UART_RTS_P1_L_N")
	)
	(segment
		(start 19.708876 -54.525926)
		(end 19.708876 -41.34485)
		(width 0.127)
		(layer "In2.Cu")
		(net "UART_RTS_P1_L_N")
	)
	(segment
		(start 10.246614 -115.35537)
		(end 13.645896 -111.956088)
		(width 0.127)
		(layer "In2.Cu")
		(net "UART_RTS_P1_L_N")
	)
	(segment
		(start 10.246614 -120.696482)
		(end 10.246614 -115.35537)
		(width 0.127)
		(layer "In2.Cu")
		(net "UART_RTS_P1_L_N")
	)
	(segment
		(start 1.948942 -200.670414)
		(end 4.343146 -200.670414)
		(width 0.127)
		(layer "In2.Cu")
		(net "UART_RTS_P1_L_N")
	)
	(segment
		(start 12.465304 -72.34682)
		(end 12.465304 -61.769498)
		(width 0.127)
		(layer "In2.Cu")
		(net "UART_RTS_P1_L_N")
	)
	(segment
		(start 10.809986 -22.10689)
		(end 12.875768 -20.041108)
		(width 0.127)
		(layer "In2.Cu")
		(net "UART_RTS_P1_L_N")
	)
	(segment
		(start 4.343146 -200.670414)
		(end 5.65404 -199.35952)
		(width 0.127)
		(layer "In2.Cu")
		(net "UART_RTS_P1_L_N")
	)
	(segment
		(start 12.426442 -91.734894)
		(end 15.550134 -88.611202)
		(width 0.127)
		(layer "In2.Cu")
		(net "UART_RTS_P1_L_N")
	)
	(segment
		(start 12.465304 -61.769498)
		(end 19.708876 -54.525926)
		(width 0.127)
		(layer "In2.Cu")
		(net "UART_RTS_P1_L_N")
	)
	(segment
		(start 8.159496 -193.844672)
		(end 9.057386 -193.844672)
		(width 0.127)
		(layer "In2.Cu")
		(net "UART_RTS_P1_L_N")
	)
	(segment
		(start 5.65404 -199.35952)
		(end 5.65404 -195.176394)
		(width 0.127)
		(layer "In2.Cu")
		(net "UART_RTS_P1_L_N")
	)
	(segment
		(start 10.809986 -32.44596)
		(end 10.809986 -22.10689)
		(width 0.127)
		(layer "In2.Cu")
		(net "UART_RTS_P1_L_N")
	)
	(segment
		(start 15.550134 -88.611202)
		(end 15.550134 -75.43165)
		(width 0.127)
		(layer "In2.Cu")
		(net "UART_RTS_P1_L_N")
	)
	(segment
		(start 20.947634 -169.158158)
		(end 20.947634 -131.397502)
		(width 0.127)
		(layer "In2.Cu")
		(net "UART_RTS_P1_L_N")
	)
	(segment
		(start 11.399012 -178.70678)
		(end 20.947634 -169.158158)
		(width 0.127)
		(layer "In2.Cu")
		(net "UART_RTS_P1_L_N")
	)
	(segment
		(start 12.325096 -107.233212)
		(end 11.100816 -106.008932)
		(width 0.127)
		(layer "In2.Cu")
		(net "UART_CTS_P1_L_N")
	)
	(segment
		(start 13.091922 -13.922756)
		(end 14.280896 -13.922756)
		(width 0.127)
		(layer "In2.Cu")
		(net "UART_CTS_P1_L_N")
	)
	(segment
		(start 14.224508 -75.981306)
		(end 11.144504 -72.901302)
		(width 0.127)
		(layer "In2.Cu")
		(net "UART_CTS_P1_L_N")
	)
	(segment
		(start 11.144504 -72.901302)
		(end 11.144504 -61.22162)
		(width 0.127)
		(layer "In2.Cu")
		(net "UART_CTS_P1_L_N")
	)
	(segment
		(start 14.280896 -13.922756)
		(end 15.339822 -12.86383)
		(width 0.127)
		(layer "In2.Cu")
		(net "UART_CTS_P1_L_N")
	)
	(segment
		(start 15.339822 -12.86383)
		(end 15.339822 -10.181844)
		(width 0.127)
		(layer "In2.Cu")
		(net "UART_CTS_P1_L_N")
	)
	(segment
		(start 11.554968 -19.493484)
		(end 11.554968 -15.45971)
		(width 0.127)
		(layer "In2.Cu")
		(net "UART_CTS_P1_L_N")
	)
	(segment
		(start 5.344922 -192.063878)
		(end 5.344922 -191.569086)
		(width 0.127)
		(layer "In2.Cu")
		(net "UART_CTS_P1_L_N")
	)
	(segment
		(start 19.626834 -168.610534)
		(end 19.626834 -131.945126)
		(width 0.127)
		(layer "In2.Cu")
		(net "UART_CTS_P1_L_N")
	)
	(segment
		(start 10.078212 -178.159156)
		(end 19.626834 -168.610534)
		(width 0.127)
		(layer "In2.Cu")
		(net "UART_CTS_P1_L_N")
	)
	(segment
		(start 9.489186 -21.559266)
		(end 11.554968 -19.493484)
		(width 0.127)
		(layer "In2.Cu")
		(net "UART_CTS_P1_L_N")
	)
	(segment
		(start 5.344922 -191.569086)
		(end 6.072886 -190.841122)
		(width 0.127)
		(layer "In2.Cu")
		(net "UART_CTS_P1_L_N")
	)
	(segment
		(start 12.325096 -111.40821)
		(end 12.325096 -107.233212)
		(width 0.127)
		(layer "In2.Cu")
		(net "UART_CTS_P1_L_N")
	)
	(segment
		(start 3.539744 -192.898776)
		(end 4.510024 -192.898776)
		(width 0.127)
		(layer "In2.Cu")
		(net "UART_CTS_P1_L_N")
	)
	(segment
		(start 7.082282 -190.841122)
		(end 7.99465 -189.928754)
		(width 0.127)
		(layer "In2.Cu")
		(net "UART_CTS_P1_L_N")
	)
	(segment
		(start 18.388076 -41.892474)
		(end 9.489186 -32.993584)
		(width 0.127)
		(layer "In2.Cu")
		(net "UART_CTS_P1_L_N")
	)
	(segment
		(start 19.626834 -131.945126)
		(end 8.925814 -121.244106)
		(width 0.127)
		(layer "In2.Cu")
		(net "UART_CTS_P1_L_N")
	)
	(segment
		(start 3.948938 -195.670678)
		(end 3.040888 -194.762628)
		(width 0.127)
		(layer "In2.Cu")
		(net "UART_CTS_P1_L_N")
	)
	(segment
		(start 8.925814 -114.807492)
		(end 12.325096 -111.40821)
		(width 0.127)
		(layer "In2.Cu")
		(net "UART_CTS_P1_L_N")
	)
	(segment
		(start 8.925814 -121.244106)
		(end 8.925814 -114.807492)
		(width 0.127)
		(layer "In2.Cu")
		(net "UART_CTS_P1_L_N")
	)
	(segment
		(start 3.040888 -193.397632)
		(end 3.539744 -192.898776)
		(width 0.127)
		(layer "In2.Cu")
		(net "UART_CTS_P1_L_N")
	)
	(segment
		(start 9.489186 -32.993584)
		(end 9.489186 -21.559266)
		(width 0.127)
		(layer "In2.Cu")
		(net "UART_CTS_P1_L_N")
	)
	(segment
		(start 15.339822 -10.181844)
		(end 16.504666 -9.017)
		(width 0.127)
		(layer "In2.Cu")
		(net "UART_CTS_P1_L_N")
	)
	(segment
		(start 11.554968 -15.45971)
		(end 13.091922 -13.922756)
		(width 0.127)
		(layer "In2.Cu")
		(net "UART_CTS_P1_L_N")
	)
	(segment
		(start 11.100816 -91.185238)
		(end 14.224508 -88.061546)
		(width 0.127)
		(layer "In2.Cu")
		(net "UART_CTS_P1_L_N")
	)
	(segment
		(start 6.072886 -190.841122)
		(end 7.082282 -190.841122)
		(width 0.127)
		(layer "In2.Cu")
		(net "UART_CTS_P1_L_N")
	)
	(segment
		(start 3.040888 -194.762628)
		(end 3.040888 -193.397632)
		(width 0.127)
		(layer "In2.Cu")
		(net "UART_CTS_P1_L_N")
	)
	(segment
		(start 11.100816 -106.008932)
		(end 11.100816 -91.185238)
		(width 0.127)
		(layer "In2.Cu")
		(net "UART_CTS_P1_L_N")
	)
	(segment
		(start 11.144504 -61.22162)
		(end 18.388076 -53.978048)
		(width 0.127)
		(layer "In2.Cu")
		(net "UART_CTS_P1_L_N")
	)
	(segment
		(start 7.99465 -189.928754)
		(end 9.047226 -189.928754)
		(width 0.127)
		(layer "In2.Cu")
		(net "UART_CTS_P1_L_N")
	)
	(segment
		(start 18.388076 -53.978048)
		(end 18.388076 -41.892474)
		(width 0.127)
		(layer "In2.Cu")
		(net "UART_CTS_P1_L_N")
	)
	(segment
		(start 10.078212 -188.897768)
		(end 10.078212 -178.159156)
		(width 0.127)
		(layer "In2.Cu")
		(net "UART_CTS_P1_L_N")
	)
	(segment
		(start 4.510024 -192.898776)
		(end 5.344922 -192.063878)
		(width 0.127)
		(layer "In2.Cu")
		(net "UART_CTS_P1_L_N")
	)
	(segment
		(start 9.047226 -189.928754)
		(end 10.078212 -188.897768)
		(width 0.127)
		(layer "In2.Cu")
		(net "UART_CTS_P1_L_N")
	)
	(segment
		(start 14.224508 -88.061546)
		(end 14.224508 -75.981306)
		(width 0.127)
		(layer "In2.Cu")
		(net "UART_CTS_P1_L_N")
	)
	(segment
		(start 11.068812 -191.36614)
		(end 8.92048 -193.514472)
		(width 0.127)
		(layer "In2.Cu")
		(net "UART_DSR_P1_L_N")
	)
	(segment
		(start 9.916414 -120.833388)
		(end 20.617434 -131.534408)
		(width 0.127)
		(layer "In2.Cu")
		(net "UART_DSR_P1_L_N")
	)
	(segment
		(start 5.83438 -194.528948)
		(end 5.32384 -195.039488)
		(width 0.127)
		(layer "In2.Cu")
		(net "UART_DSR_P1_L_N")
	)
	(segment
		(start 13.315696 -111.819182)
		(end 9.916414 -115.218464)
		(width 0.127)
		(layer "In2.Cu")
		(net "UART_DSR_P1_L_N")
	)
	(segment
		(start 8.92048 -193.514472)
		(end 8.02259 -193.514472)
		(width 0.127)
		(layer "In2.Cu")
		(net "UART_DSR_P1_L_N")
	)
	(segment
		(start 13.572998 -16.637)
		(end 12.545568 -17.66443)
		(width 0.127)
		(layer "In2.Cu")
		(net "UART_DSR_P1_L_N")
	)
	(segment
		(start 8.02259 -193.514472)
		(end 7.008114 -194.528948)
		(width 0.127)
		(layer "In2.Cu")
		(net "UART_DSR_P1_L_N")
	)
	(segment
		(start 12.545568 -19.904202)
		(end 10.479786 -21.969984)
		(width 0.127)
		(layer "In2.Cu")
		(net "UART_DSR_P1_L_N")
	)
	(segment
		(start 12.091416 -105.598214)
		(end 13.315696 -106.822494)
		(width 0.127)
		(layer "In2.Cu")
		(net "UART_DSR_P1_L_N")
	)
	(segment
		(start 16.504666 -16.637)
		(end 13.572998 -16.637)
		(width 0.127)
		(layer "In2.Cu")
		(net "UART_DSR_P1_L_N")
	)
	(segment
		(start 19.378676 -41.481756)
		(end 19.378676 -54.38902)
		(width 0.127)
		(layer "In2.Cu")
		(net "UART_DSR_P1_L_N")
	)
	(segment
		(start 9.916414 -115.218464)
		(end 9.916414 -120.833388)
		(width 0.127)
		(layer "In2.Cu")
		(net "UART_DSR_P1_L_N")
	)
	(segment
		(start 12.091416 -91.595956)
		(end 12.091416 -105.598214)
		(width 0.127)
		(layer "In2.Cu")
		(net "UART_DSR_P1_L_N")
	)
	(segment
		(start 5.32384 -195.039488)
		(end 5.32384 -198.888096)
		(width 0.127)
		(layer "In2.Cu")
		(net "UART_DSR_P1_L_N")
	)
	(segment
		(start 12.135104 -72.490584)
		(end 15.215108 -75.570588)
		(width 0.127)
		(layer "In2.Cu")
		(net "UART_DSR_P1_L_N")
	)
	(segment
		(start 4.541266 -199.67067)
		(end 3.948938 -199.67067)
		(width 0.127)
		(layer "In2.Cu")
		(net "UART_DSR_P1_L_N")
	)
	(segment
		(start 11.068812 -178.569874)
		(end 11.068812 -191.36614)
		(width 0.127)
		(layer "In2.Cu")
		(net "UART_DSR_P1_L_N")
	)
	(segment
		(start 7.008114 -194.528948)
		(end 5.83438 -194.528948)
		(width 0.127)
		(layer "In2.Cu")
		(net "UART_DSR_P1_L_N")
	)
	(segment
		(start 15.215108 -88.472264)
		(end 12.091416 -91.595956)
		(width 0.127)
		(layer "In2.Cu")
		(net "UART_DSR_P1_L_N")
	)
	(segment
		(start 20.617434 -169.021252)
		(end 11.068812 -178.569874)
		(width 0.127)
		(layer "In2.Cu")
		(net "UART_DSR_P1_L_N")
	)
	(segment
		(start 15.215108 -75.570588)
		(end 15.215108 -88.472264)
		(width 0.127)
		(layer "In2.Cu")
		(net "UART_DSR_P1_L_N")
	)
	(segment
		(start 5.32384 -198.888096)
		(end 4.541266 -199.67067)
		(width 0.127)
		(layer "In2.Cu")
		(net "UART_DSR_P1_L_N")
	)
	(segment
		(start 20.617434 -131.534408)
		(end 20.617434 -169.021252)
		(width 0.127)
		(layer "In2.Cu")
		(net "UART_DSR_P1_L_N")
	)
	(segment
		(start 10.479786 -32.582866)
		(end 19.378676 -41.481756)
		(width 0.127)
		(layer "In2.Cu")
		(net "UART_DSR_P1_L_N")
	)
	(segment
		(start 12.135104 -61.632592)
		(end 12.135104 -72.490584)
		(width 0.127)
		(layer "In2.Cu")
		(net "UART_DSR_P1_L_N")
	)
	(segment
		(start 10.479786 -21.969984)
		(end 10.479786 -32.582866)
		(width 0.127)
		(layer "In2.Cu")
		(net "UART_DSR_P1_L_N")
	)
	(segment
		(start 13.315696 -106.822494)
		(end 13.315696 -111.819182)
		(width 0.127)
		(layer "In2.Cu")
		(net "UART_DSR_P1_L_N")
	)
	(segment
		(start 12.545568 -17.66443)
		(end 12.545568 -19.904202)
		(width 0.127)
		(layer "In2.Cu")
		(net "UART_DSR_P1_L_N")
	)
	(segment
		(start 19.378676 -54.38902)
		(end 12.135104 -61.632592)
		(width 0.127)
		(layer "In2.Cu")
		(net "UART_DSR_P1_L_N")
	)
	(segment
		(start 1.948942 -204.348842)
		(end 1.250442 -203.650342)
		(width 0.127)
		(layer "In5.Cu")
		(net "UART_DTR_P5_L_N")
	)
	(segment
		(start 1.250442 -203.650342)
		(end 1.250442 -202.38085)
		(width 0.127)
		(layer "In5.Cu")
		(net "UART_DTR_P5_L_N")
	)
	(segment
		(start 19.218656 -159.558736)
		(end 19.218656 -133.304534)
		(width 0.127)
		(layer "In5.Cu")
		(net "UART_DTR_P5_L_N")
	)
	(segment
		(start 10.258044 -73.02119)
		(end 10.258044 -67.079622)
		(width 0.127)
		(layer "In5.Cu")
		(net "UART_DTR_P5_L_N")
	)
	(segment
		(start 10.258044 -67.079622)
		(end 13.964666 -63.373)
		(width 0.127)
		(layer "In5.Cu")
		(net "UART_DTR_P5_L_N")
	)
	(segment
		(start 2.464054 -198.108062)
		(end 2.464054 -197.233286)
		(width 0.127)
		(layer "In5.Cu")
		(net "UART_DTR_P5_L_N")
	)
	(segment
		(start 7.958582 -187.738512)
		(end 9.294876 -187.738512)
		(width 0.127)
		(layer "In5.Cu")
		(net "UART_DTR_P5_L_N")
	)
	(segment
		(start 9.035796 -89.94648)
		(end 9.035796 -74.243438)
		(width 0.127)
		(layer "In5.Cu")
		(net "UART_DTR_P5_L_N")
	)
	(segment
		(start 3.4544 -93.561408)
		(end 5.917692 -91.098116)
		(width 0.127)
		(layer "In5.Cu")
		(net "UART_DTR_P5_L_N")
	)
	(segment
		(start 9.754108 -169.023538)
		(end 10.978134 -167.799258)
		(width 0.127)
		(layer "In5.Cu")
		(net "UART_DTR_P5_L_N")
	)
	(segment
		(start 3.74904 -190.456312)
		(end 4.555744 -190.456312)
		(width 0.127)
		(layer "In5.Cu")
		(net "UART_DTR_P5_L_N")
	)
	(segment
		(start 1.250442 -202.38085)
		(end 2.647442 -200.98385)
		(width 0.127)
		(layer "In5.Cu")
		(net "UART_DTR_P5_L_N")
	)
	(segment
		(start 19.218656 -133.304534)
		(end 16.69415 -130.780028)
		(width 0.127)
		(layer "In5.Cu")
		(net "UART_DTR_P5_L_N")
	)
	(segment
		(start 2.647442 -199.049894)
		(end 2.647442 -198.29145)
		(width 0.127)
		(layer "In5.Cu")
		(net "UART_DTR_P5_L_N")
	)
	(segment
		(start 6.254242 -188.757814)
		(end 6.93928 -188.757814)
		(width 0.127)
		(layer "In5.Cu")
		(net "UART_DTR_P5_L_N")
	)
	(segment
		(start 2.464054 -197.233286)
		(end 2.70256 -196.99478)
		(width 0.127)
		(layer "In5.Cu")
		(net "UART_DTR_P5_L_N")
	)
	(segment
		(start 1.948942 -204.67066)
		(end 1.948942 -204.348842)
		(width 0.127)
		(layer "In5.Cu")
		(net "UART_DTR_P5_L_N")
	)
	(segment
		(start 2.752598 -194.944746)
		(end 2.752598 -194.396614)
		(width 0.127)
		(layer "In5.Cu")
		(net "UART_DTR_P5_L_N")
	)
	(segment
		(start 2.647442 -198.29145)
		(end 2.464054 -198.108062)
		(width 0.127)
		(layer "In5.Cu")
		(net "UART_DTR_P5_L_N")
	)
	(segment
		(start 3.02514 -191.180212)
		(end 3.74904 -190.456312)
		(width 0.127)
		(layer "In5.Cu")
		(net "UART_DTR_P5_L_N")
	)
	(segment
		(start 7.88416 -91.098116)
		(end 9.035796 -89.94648)
		(width 0.127)
		(layer "In5.Cu")
		(net "UART_DTR_P5_L_N")
	)
	(segment
		(start 3.02514 -192.672208)
		(end 3.02514 -191.180212)
		(width 0.127)
		(layer "In5.Cu")
		(net "UART_DTR_P5_L_N")
	)
	(segment
		(start 5.917692 -91.098116)
		(end 7.88416 -91.098116)
		(width 0.127)
		(layer "In5.Cu")
		(net "UART_DTR_P5_L_N")
	)
	(segment
		(start 9.035796 -74.243438)
		(end 10.258044 -73.02119)
		(width 0.127)
		(layer "In5.Cu")
		(net "UART_DTR_P5_L_N")
	)
	(segment
		(start 2.499106 -200.14311)
		(end 2.499106 -199.19823)
		(width 0.127)
		(layer "In5.Cu")
		(net "UART_DTR_P5_L_N")
	)
	(segment
		(start 2.647442 -200.291446)
		(end 2.499106 -200.14311)
		(width 0.127)
		(layer "In5.Cu")
		(net "UART_DTR_P5_L_N")
	)
	(segment
		(start 4.555744 -190.456312)
		(end 6.254242 -188.757814)
		(width 0.127)
		(layer "In5.Cu")
		(net "UART_DTR_P5_L_N")
	)
	(segment
		(start 2.499106 -199.19823)
		(end 2.647442 -199.049894)
		(width 0.127)
		(layer "In5.Cu")
		(net "UART_DTR_P5_L_N")
	)
	(segment
		(start 2.647442 -200.98385)
		(end 2.647442 -200.291446)
		(width 0.127)
		(layer "In5.Cu")
		(net "UART_DTR_P5_L_N")
	)
	(segment
		(start 2.590038 -194.234054)
		(end 2.590038 -193.10731)
		(width 0.127)
		(layer "In5.Cu")
		(net "UART_DTR_P5_L_N")
	)
	(segment
		(start 6.939026 -121.910094)
		(end 6.939026 -115.969542)
		(width 0.127)
		(layer "In5.Cu")
		(net "UART_DTR_P5_L_N")
	)
	(segment
		(start 2.484882 -196.128894)
		(end 2.484882 -195.212462)
		(width 0.127)
		(layer "In5.Cu")
		(net "UART_DTR_P5_L_N")
	)
	(segment
		(start 2.752598 -194.396614)
		(end 2.590038 -194.234054)
		(width 0.127)
		(layer "In5.Cu")
		(net "UART_DTR_P5_L_N")
	)
	(segment
		(start 2.484882 -195.212462)
		(end 2.752598 -194.944746)
		(width 0.127)
		(layer "In5.Cu")
		(net "UART_DTR_P5_L_N")
	)
	(segment
		(start 10.978134 -167.799258)
		(end 19.218656 -159.558736)
		(width 0.127)
		(layer "In5.Cu")
		(net "UART_DTR_P5_L_N")
	)
	(segment
		(start 16.69415 -130.780028)
		(end 15.80896 -130.780028)
		(width 0.127)
		(layer "In5.Cu")
		(net "UART_DTR_P5_L_N")
	)
	(segment
		(start 6.939026 -115.969542)
		(end 3.4544 -112.484916)
		(width 0.127)
		(layer "In5.Cu")
		(net "UART_DTR_P5_L_N")
	)
	(segment
		(start 3.4544 -112.484916)
		(end 3.4544 -93.561408)
		(width 0.127)
		(layer "In5.Cu")
		(net "UART_DTR_P5_L_N")
	)
	(segment
		(start 2.70256 -196.99478)
		(end 2.70256 -196.346572)
		(width 0.127)
		(layer "In5.Cu")
		(net "UART_DTR_P5_L_N")
	)
	(segment
		(start 9.294876 -187.738512)
		(end 9.754108 -187.27928)
		(width 0.127)
		(layer "In5.Cu")
		(net "UART_DTR_P5_L_N")
	)
	(segment
		(start 9.754108 -187.27928)
		(end 9.754108 -169.023538)
		(width 0.127)
		(layer "In5.Cu")
		(net "UART_DTR_P5_L_N")
	)
	(segment
		(start 6.93928 -188.757814)
		(end 7.958582 -187.738512)
		(width 0.127)
		(layer "In5.Cu")
		(net "UART_DTR_P5_L_N")
	)
	(segment
		(start 2.70256 -196.346572)
		(end 2.484882 -196.128894)
		(width 0.127)
		(layer "In5.Cu")
		(net "UART_DTR_P5_L_N")
	)
	(segment
		(start 2.590038 -193.10731)
		(end 3.02514 -192.672208)
		(width 0.127)
		(layer "In5.Cu")
		(net "UART_DTR_P5_L_N")
	)
	(segment
		(start 15.80896 -130.780028)
		(end 6.939026 -121.910094)
		(width 0.127)
		(layer "In5.Cu")
		(net "UART_DTR_P5_L_N")
	)
	(segment
		(start 15.711424 -15.353284)
		(end 14.736064 -14.377924)
		(width 0.127)
		(layer "In2.Cu")
		(net "UART_TX_P1_L")
	)
	(segment
		(start 5.98932 -192.442338)
		(end 4.66344 -193.768218)
		(width 0.127)
		(layer "In2.Cu")
		(net "UART_TX_P1_L")
	)
	(segment
		(start 14.554708 -75.8444)
		(end 14.554708 -88.198452)
		(width 0.127)
		(layer "In2.Cu")
		(net "UART_TX_P1_L")
	)
	(segment
		(start 6.950202 -192.442338)
		(end 5.98932 -192.442338)
		(width 0.127)
		(layer "In2.Cu")
		(net "UART_TX_P1_L")
	)
	(segment
		(start 9.256014 -114.944398)
		(end 9.256014 -121.1072)
		(width 0.127)
		(layer "In2.Cu")
		(net "UART_TX_P1_L")
	)
	(segment
		(start 11.474704 -72.764396)
		(end 14.554708 -75.8444)
		(width 0.127)
		(layer "In2.Cu")
		(net "UART_TX_P1_L")
	)
	(segment
		(start 12.655296 -107.096306)
		(end 12.655296 -111.545116)
		(width 0.127)
		(layer "In2.Cu")
		(net "UART_TX_P1_L")
	)
	(segment
		(start 18.718276 -41.755568)
		(end 18.718276 -54.114954)
		(width 0.127)
		(layer "In2.Cu")
		(net "UART_TX_P1_L")
	)
	(segment
		(start 16.504666 -11.557)
		(end 17.736312 -12.788646)
		(width 0.127)
		(layer "In2.Cu")
		(net "UART_TX_P1_L")
	)
	(segment
		(start 9.256014 -121.1072)
		(end 19.957034 -131.80822)
		(width 0.127)
		(layer "In2.Cu")
		(net "UART_TX_P1_L")
	)
	(segment
		(start 17.736312 -12.788646)
		(end 17.736312 -14.851634)
		(width 0.127)
		(layer "In2.Cu")
		(net "UART_TX_P1_L")
	)
	(segment
		(start 19.957034 -168.74744)
		(end 10.408412 -178.296062)
		(width 0.127)
		(layer "In2.Cu")
		(net "UART_TX_P1_L")
	)
	(segment
		(start 13.156692 -14.377924)
		(end 11.885168 -15.649448)
		(width 0.127)
		(layer "In2.Cu")
		(net "UART_TX_P1_L")
	)
	(segment
		(start 9.819386 -32.856678)
		(end 18.718276 -41.755568)
		(width 0.127)
		(layer "In2.Cu")
		(net "UART_TX_P1_L")
	)
	(segment
		(start 14.554708 -88.198452)
		(end 11.431016 -91.322144)
		(width 0.127)
		(layer "In2.Cu")
		(net "UART_TX_P1_L")
	)
	(segment
		(start 19.957034 -131.80822)
		(end 19.957034 -168.74744)
		(width 0.127)
		(layer "In2.Cu")
		(net "UART_TX_P1_L")
	)
	(segment
		(start 11.474704 -61.358526)
		(end 11.474704 -72.764396)
		(width 0.127)
		(layer "In2.Cu")
		(net "UART_TX_P1_L")
	)
	(segment
		(start 4.66344 -193.768218)
		(end 4.66344 -196.956172)
		(width 0.127)
		(layer "In2.Cu")
		(net "UART_TX_P1_L")
	)
	(segment
		(start 8.741918 -191.617346)
		(end 7.775194 -191.617346)
		(width 0.127)
		(layer "In2.Cu")
		(net "UART_TX_P1_L")
	)
	(segment
		(start 9.819386 -21.696172)
		(end 9.819386 -32.856678)
		(width 0.127)
		(layer "In2.Cu")
		(net "UART_TX_P1_L")
	)
	(segment
		(start 7.775194 -191.617346)
		(end 6.950202 -192.442338)
		(width 0.127)
		(layer "In2.Cu")
		(net "UART_TX_P1_L")
	)
	(segment
		(start 11.885168 -15.649448)
		(end 11.885168 -19.63039)
		(width 0.127)
		(layer "In2.Cu")
		(net "UART_TX_P1_L")
	)
	(segment
		(start 17.736312 -14.851634)
		(end 17.234662 -15.353284)
		(width 0.127)
		(layer "In2.Cu")
		(net "UART_TX_P1_L")
	)
	(segment
		(start 10.408412 -189.950852)
		(end 8.741918 -191.617346)
		(width 0.127)
		(layer "In2.Cu")
		(net "UART_TX_P1_L")
	)
	(segment
		(start 18.718276 -54.114954)
		(end 11.474704 -61.358526)
		(width 0.127)
		(layer "In2.Cu")
		(net "UART_TX_P1_L")
	)
	(segment
		(start 14.736064 -14.377924)
		(end 13.156692 -14.377924)
		(width 0.127)
		(layer "In2.Cu")
		(net "UART_TX_P1_L")
	)
	(segment
		(start 10.408412 -178.296062)
		(end 10.408412 -189.950852)
		(width 0.127)
		(layer "In2.Cu")
		(net "UART_TX_P1_L")
	)
	(segment
		(start 17.234662 -15.353284)
		(end 15.711424 -15.353284)
		(width 0.127)
		(layer "In2.Cu")
		(net "UART_TX_P1_L")
	)
	(segment
		(start 4.66344 -196.956172)
		(end 3.948938 -197.670674)
		(width 0.127)
		(layer "In2.Cu")
		(net "UART_TX_P1_L")
	)
	(segment
		(start 11.431016 -105.872026)
		(end 12.655296 -107.096306)
		(width 0.127)
		(layer "In2.Cu")
		(net "UART_TX_P1_L")
	)
	(segment
		(start 12.655296 -111.545116)
		(end 9.256014 -114.944398)
		(width 0.127)
		(layer "In2.Cu")
		(net "UART_TX_P1_L")
	)
	(segment
		(start 11.431016 -91.322144)
		(end 11.431016 -105.872026)
		(width 0.127)
		(layer "In2.Cu")
		(net "UART_TX_P1_L")
	)
	(segment
		(start 11.885168 -19.63039)
		(end 9.819386 -21.696172)
		(width 0.127)
		(layer "In2.Cu")
		(net "UART_TX_P1_L")
	)
	(segment
		(start 11.965432 -169.615358)
		(end 11.965432 -191.3128)
		(width 0.127)
		(layer "In5.Cu")
		(net "UART_RTS_P5_L_N")
	)
	(segment
		(start 21.430488 -160.150302)
		(end 11.965432 -169.615358)
		(width 0.127)
		(layer "In5.Cu")
		(net "UART_RTS_P5_L_N")
	)
	(segment
		(start 8.920226 -121.088658)
		(end 16.630396 -128.798828)
		(width 0.127)
		(layer "In5.Cu")
		(net "UART_RTS_P5_L_N")
	)
	(segment
		(start 10.084562 -113.100612)
		(end 8.920226 -114.264948)
		(width 0.127)
		(layer "In5.Cu")
		(net "UART_RTS_P5_L_N")
	)
	(segment
		(start 5.739384 -207.133952)
		(end 4.202684 -208.670652)
		(width 0.127)
		(layer "In5.Cu")
		(net "UART_RTS_P5_L_N")
	)
	(segment
		(start 9.381998 -193.896234)
		(end 8.1788 -193.896234)
		(width 0.127)
		(layer "In5.Cu")
		(net "UART_RTS_P5_L_N")
	)
	(segment
		(start 16.630396 -128.798828)
		(end 17.771364 -128.798828)
		(width 0.127)
		(layer "In5.Cu")
		(net "UART_RTS_P5_L_N")
	)
	(segment
		(start 5.739384 -195.307712)
		(end 5.739384 -207.133952)
		(width 0.127)
		(layer "In5.Cu")
		(net "UART_RTS_P5_L_N")
	)
	(segment
		(start 17.771364 -128.798828)
		(end 21.430488 -132.457952)
		(width 0.127)
		(layer "In5.Cu")
		(net "UART_RTS_P5_L_N")
	)
	(segment
		(start 6.2738 -194.773296)
		(end 5.739384 -195.307712)
		(width 0.127)
		(layer "In5.Cu")
		(net "UART_RTS_P5_L_N")
	)
	(segment
		(start 12.469368 -72.488298)
		(end 12.469368 -73.938384)
		(width 0.127)
		(layer "In5.Cu")
		(net "UART_RTS_P5_L_N")
	)
	(segment
		(start 21.430488 -132.457952)
		(end 21.430488 -160.150302)
		(width 0.127)
		(layer "In5.Cu")
		(net "UART_RTS_P5_L_N")
	)
	(segment
		(start 12.469368 -73.938384)
		(end 11.247628 -75.160124)
		(width 0.127)
		(layer "In5.Cu")
		(net "UART_RTS_P5_L_N")
	)
	(segment
		(start 10.084562 -92.026232)
		(end 10.084562 -113.100612)
		(width 0.127)
		(layer "In5.Cu")
		(net "UART_RTS_P5_L_N")
	)
	(segment
		(start 13.964666 -70.993)
		(end 12.469368 -72.488298)
		(width 0.127)
		(layer "In5.Cu")
		(net "UART_RTS_P5_L_N")
	)
	(segment
		(start 11.965432 -191.3128)
		(end 9.381998 -193.896234)
		(width 0.127)
		(layer "In5.Cu")
		(net "UART_RTS_P5_L_N")
	)
	(segment
		(start 4.202684 -208.670652)
		(end 1.948942 -208.670652)
		(width 0.127)
		(layer "In5.Cu")
		(net "UART_RTS_P5_L_N")
	)
	(segment
		(start 7.301738 -194.773296)
		(end 6.2738 -194.773296)
		(width 0.127)
		(layer "In5.Cu")
		(net "UART_RTS_P5_L_N")
	)
	(segment
		(start 11.247628 -75.160124)
		(end 11.247628 -90.863166)
		(width 0.127)
		(layer "In5.Cu")
		(net "UART_RTS_P5_L_N")
	)
	(segment
		(start 11.247628 -90.863166)
		(end 10.084562 -92.026232)
		(width 0.127)
		(layer "In5.Cu")
		(net "UART_RTS_P5_L_N")
	)
	(segment
		(start 8.920226 -114.264948)
		(end 8.920226 -121.088658)
		(width 0.127)
		(layer "In5.Cu")
		(net "UART_RTS_P5_L_N")
	)
	(segment
		(start 8.1788 -193.896234)
		(end 7.301738 -194.773296)
		(width 0.127)
		(layer "In5.Cu")
		(net "UART_RTS_P5_L_N")
	)
	(segment
		(start 3.250438 -193.381122)
		(end 3.250438 -193.960242)
		(width 0.127)
		(layer "In5.Cu")
		(net "UART_TX_P5_L")
	)
	(segment
		(start 16.110712 -68.198238)
		(end 14.958822 -67.046348)
		(width 0.127)
		(layer "In5.Cu")
		(net "UART_TX_P5_L")
	)
	(segment
		(start 16.779494 -68.198238)
		(end 16.110712 -68.198238)
		(width 0.127)
		(layer "In5.Cu")
		(net "UART_TX_P5_L")
	)
	(segment
		(start 3.375914 -199.255634)
		(end 3.250438 -199.38111)
		(width 0.127)
		(layer "In5.Cu")
		(net "UART_TX_P5_L")
	)
	(segment
		(start 10.517378 -169.19448)
		(end 10.517378 -188.933582)
		(width 0.127)
		(layer "In5.Cu")
		(net "UART_TX_P5_L")
	)
	(segment
		(start 3.193542 -195.903342)
		(end 3.403854 -196.113654)
		(width 0.127)
		(layer "In5.Cu")
		(net "UART_TX_P5_L")
	)
	(segment
		(start 7.599426 -121.636282)
		(end 16.082772 -130.119628)
		(width 0.127)
		(layer "In5.Cu")
		(net "UART_TX_P5_L")
	)
	(segment
		(start 17.004284 -130.119628)
		(end 19.904964 -133.020308)
		(width 0.127)
		(layer "In5.Cu")
		(net "UART_TX_P5_L")
	)
	(segment
		(start 3.403854 -196.113654)
		(end 3.403854 -197.227698)
		(width 0.127)
		(layer "In5.Cu")
		(net "UART_TX_P5_L")
	)
	(segment
		(start 3.250438 -197.960234)
		(end 3.375914 -198.08571)
		(width 0.127)
		(layer "In5.Cu")
		(net "UART_TX_P5_L")
	)
	(segment
		(start 3.403854 -197.227698)
		(end 3.250438 -197.381114)
		(width 0.127)
		(layer "In5.Cu")
		(net "UART_TX_P5_L")
	)
	(segment
		(start 7.268464 -190.805054)
		(end 6.326124 -190.805054)
		(width 0.127)
		(layer "In5.Cu")
		(net "UART_TX_P5_L")
	)
	(segment
		(start 9.598406 -189.852554)
		(end 8.220964 -189.852554)
		(width 0.127)
		(layer "In5.Cu")
		(net "UART_TX_P5_L")
	)
	(segment
		(start 4.317238 -192.81394)
		(end 3.81762 -192.81394)
		(width 0.127)
		(layer "In5.Cu")
		(net "UART_TX_P5_L")
	)
	(segment
		(start 9.799574 -74.560176)
		(end 9.799574 -90.263218)
		(width 0.127)
		(layer "In5.Cu")
		(net "UART_TX_P5_L")
	)
	(segment
		(start 16.082772 -130.119628)
		(end 17.004284 -130.119628)
		(width 0.127)
		(layer "In5.Cu")
		(net "UART_TX_P5_L")
	)
	(segment
		(start 3.81762 -192.81394)
		(end 3.250438 -193.381122)
		(width 0.127)
		(layer "In5.Cu")
		(net "UART_TX_P5_L")
	)
	(segment
		(start 8.201406 -91.861386)
		(end 6.088888 -91.861386)
		(width 0.127)
		(layer "In5.Cu")
		(net "UART_TX_P5_L")
	)
	(segment
		(start 3.250438 -199.96023)
		(end 3.382772 -200.092564)
		(width 0.127)
		(layer "In5.Cu")
		(net "UART_TX_P5_L")
	)
	(segment
		(start 3.382772 -200.092564)
		(end 3.382772 -201.248772)
		(width 0.127)
		(layer "In5.Cu")
		(net "UART_TX_P5_L")
	)
	(segment
		(start 17.411192 -67.56654)
		(end 16.779494 -68.198238)
		(width 0.127)
		(layer "In5.Cu")
		(net "UART_TX_P5_L")
	)
	(segment
		(start 3.250438 -201.381106)
		(end 3.250438 -204.972158)
		(width 0.127)
		(layer "In5.Cu")
		(net "UART_TX_P5_L")
	)
	(segment
		(start 8.220964 -189.852554)
		(end 7.268464 -190.805054)
		(width 0.127)
		(layer "In5.Cu")
		(net "UART_TX_P5_L")
	)
	(segment
		(start 3.193542 -195.438014)
		(end 3.193542 -195.903342)
		(width 0.127)
		(layer "In5.Cu")
		(net "UART_TX_P5_L")
	)
	(segment
		(start 12.580874 -67.046348)
		(end 11.021314 -68.605908)
		(width 0.127)
		(layer "In5.Cu")
		(net "UART_TX_P5_L")
	)
	(segment
		(start 19.904964 -133.020308)
		(end 19.904964 -159.80664)
		(width 0.127)
		(layer "In5.Cu")
		(net "UART_TX_P5_L")
	)
	(segment
		(start 11.517884 -168.19372)
		(end 10.517378 -169.19448)
		(width 0.127)
		(layer "In5.Cu")
		(net "UART_TX_P5_L")
	)
	(segment
		(start 10.517378 -188.933582)
		(end 9.598406 -189.852554)
		(width 0.127)
		(layer "In5.Cu")
		(net "UART_TX_P5_L")
	)
	(segment
		(start 11.021314 -68.605908)
		(end 11.021314 -73.338436)
		(width 0.127)
		(layer "In5.Cu")
		(net "UART_TX_P5_L")
	)
	(segment
		(start 3.250438 -193.960242)
		(end 3.414014 -194.123818)
		(width 0.127)
		(layer "In5.Cu")
		(net "UART_TX_P5_L")
	)
	(segment
		(start 17.411192 -65.549526)
		(end 17.411192 -67.56654)
		(width 0.127)
		(layer "In5.Cu")
		(net "UART_TX_P5_L")
	)
	(segment
		(start 4.1148 -112.065816)
		(end 7.599426 -115.550442)
		(width 0.127)
		(layer "In5.Cu")
		(net "UART_TX_P5_L")
	)
	(segment
		(start 3.250438 -197.381114)
		(end 3.250438 -197.960234)
		(width 0.127)
		(layer "In5.Cu")
		(net "UART_TX_P5_L")
	)
	(segment
		(start 14.958822 -67.046348)
		(end 12.580874 -67.046348)
		(width 0.127)
		(layer "In5.Cu")
		(net "UART_TX_P5_L")
	)
	(segment
		(start 9.799574 -90.263218)
		(end 8.201406 -91.861386)
		(width 0.127)
		(layer "In5.Cu")
		(net "UART_TX_P5_L")
	)
	(segment
		(start 6.088888 -91.861386)
		(end 4.1148 -93.835474)
		(width 0.127)
		(layer "In5.Cu")
		(net "UART_TX_P5_L")
	)
	(segment
		(start 19.904964 -159.80664)
		(end 11.517884 -168.19372)
		(width 0.127)
		(layer "In5.Cu")
		(net "UART_TX_P5_L")
	)
	(segment
		(start 16.504666 -64.643)
		(end 17.411192 -65.549526)
		(width 0.127)
		(layer "In5.Cu")
		(net "UART_TX_P5_L")
	)
	(segment
		(start 3.250438 -204.972158)
		(end 3.948938 -205.670658)
		(width 0.127)
		(layer "In5.Cu")
		(net "UART_TX_P5_L")
	)
	(segment
		(start 3.414014 -194.123818)
		(end 3.414014 -195.217542)
		(width 0.127)
		(layer "In5.Cu")
		(net "UART_TX_P5_L")
	)
	(segment
		(start 11.021314 -73.338436)
		(end 9.799574 -74.560176)
		(width 0.127)
		(layer "In5.Cu")
		(net "UART_TX_P5_L")
	)
	(segment
		(start 4.1148 -93.835474)
		(end 4.1148 -112.065816)
		(width 0.127)
		(layer "In5.Cu")
		(net "UART_TX_P5_L")
	)
	(segment
		(start 3.414014 -195.217542)
		(end 3.193542 -195.438014)
		(width 0.127)
		(layer "In5.Cu")
		(net "UART_TX_P5_L")
	)
	(segment
		(start 7.599426 -115.550442)
		(end 7.599426 -121.636282)
		(width 0.127)
		(layer "In5.Cu")
		(net "UART_TX_P5_L")
	)
	(segment
		(start 3.250438 -199.38111)
		(end 3.250438 -199.96023)
		(width 0.127)
		(layer "In5.Cu")
		(net "UART_TX_P5_L")
	)
	(segment
		(start 6.326124 -190.805054)
		(end 4.317238 -192.81394)
		(width 0.127)
		(layer "In5.Cu")
		(net "UART_TX_P5_L")
	)
	(segment
		(start 3.382772 -201.248772)
		(end 3.250438 -201.381106)
		(width 0.127)
		(layer "In5.Cu")
		(net "UART_TX_P5_L")
	)
	(segment
		(start 3.375914 -198.08571)
		(end 3.375914 -199.255634)
		(width 0.127)
		(layer "In5.Cu")
		(net "UART_TX_P5_L")
	)
	(segment
		(start 15.009114 -404.984204)
		(end 14.034516 -404.496016)
		(width 0.127)
		(layer "B.Cu")
		(net "LAN2_P3_N")
	)
	(segment
		(start 11.171936 -406.234138)
		(end 11.441176 -406.503378)
		(width 0.127)
		(layer "B.Cu")
		(net "LAN2_P3_N")
	)
	(segment
		(start 10.648696 -405.426418)
		(end 10.648696 -405.999442)
		(width 0.127)
		(layer "B.Cu")
		(net "LAN2_P3_N")
	)
	(segment
		(start 12.2682 -407.618946)
		(end 12.621006 -407.971752)
		(width 0.127)
		(layer "B.Cu")
		(net "LAN2_P3_N")
	)
	(segment
		(start 10.863326 -405.212042)
		(end 10.648696 -405.426418)
		(width 0.127)
		(layer "B.Cu")
		(net "LAN2_P3_N")
	)
	(segment
		(start 11.99896 -407.061162)
		(end 12.2682 -407.330402)
		(width 0.127)
		(layer "B.Cu")
		(net "LAN2_P3_N")
	)
	(segment
		(start 12.621006 -407.971752)
		(end 14.4653 -407.971752)
		(width 0.127)
		(layer "B.Cu")
		(net "LAN2_P3_N")
	)
	(segment
		(start 15.065756 -405.154638)
		(end 15.009114 -404.984204)
		(width 0.127)
		(layer "B.Cu")
		(net "LAN2_P3_N")
	)
	(segment
		(start 10.648696 -403.425914)
		(end 10.863326 -403.64029)
		(width 0.127)
		(layer "B.Cu")
		(net "LAN2_P3_N")
	)
	(segment
		(start 8.449818 -349.669862)
		(end 8.08609 -349.669862)
		(width 0.127)
		(layer "B.Cu")
		(net "LAN2_P3_N")
	)
	(segment
		(start 8.08609 -349.669862)
		(end 7.689088 -350.066864)
		(width 0.127)
		(layer "B.Cu")
		(net "LAN2_P3_N")
	)
	(segment
		(start 14.786356 -406.310338)
		(end 14.786356 -405.490426)
		(width 0.127)
		(layer "B.Cu")
		(net "LAN2_P3_N")
	)
	(segment
		(start 11.710416 -407.061162)
		(end 11.99896 -407.061162)
		(width 0.127)
		(layer "B.Cu")
		(net "LAN2_P3_N")
	)
	(segment
		(start 15.009114 -405.267668)
		(end 15.065756 -405.154638)
		(width 0.127)
		(layer "B.Cu")
		(net "LAN2_P3_N")
	)
	(segment
		(start 10.883392 -406.234138)
		(end 11.171936 -406.234138)
		(width 0.127)
		(layer "B.Cu")
		(net "LAN2_P3_N")
	)
	(segment
		(start 10.648696 -404.616666)
		(end 10.863326 -404.831042)
		(width 0.127)
		(layer "B.Cu")
		(net "LAN2_P3_N")
	)
	(segment
		(start 10.648696 -404.235666)
		(end 10.648696 -404.616666)
		(width 0.127)
		(layer "B.Cu")
		(net "LAN2_P3_N")
	)
	(segment
		(start 11.441176 -406.503378)
		(end 11.441176 -406.791922)
		(width 0.127)
		(layer "B.Cu")
		(net "LAN2_P3_N")
	)
	(segment
		(start 15.23746 -406.761442)
		(end 14.786356 -406.310338)
		(width 0.127)
		(layer "B.Cu")
		(net "LAN2_P3_N")
	)
	(segment
		(start 6.78053 -394.651992)
		(end 10.648696 -398.520158)
		(width 0.127)
		(layer "B.Cu")
		(net "LAN2_P3_N")
	)
	(segment
		(start 14.786356 -405.490426)
		(end 15.009114 -405.267668)
		(width 0.127)
		(layer "B.Cu")
		(net "LAN2_P3_N")
	)
	(segment
		(start 6.78053 -354.831904)
		(end 6.78053 -394.651992)
		(width 0.127)
		(layer "B.Cu")
		(net "LAN2_P3_N")
	)
	(segment
		(start 7.689088 -350.066864)
		(end 7.689088 -353.923346)
		(width 0.127)
		(layer "B.Cu")
		(net "LAN2_P3_N")
	)
	(segment
		(start 12.2682 -407.330402)
		(end 12.2682 -407.618946)
		(width 0.127)
		(layer "B.Cu")
		(net "LAN2_P3_N")
	)
	(segment
		(start 10.863326 -404.02129)
		(end 10.648696 -404.235666)
		(width 0.127)
		(layer "B.Cu")
		(net "LAN2_P3_N")
	)
	(segment
		(start 10.648696 -398.520158)
		(end 10.648696 -403.425914)
		(width 0.127)
		(layer "B.Cu")
		(net "LAN2_P3_N")
	)
	(segment
		(start 10.863326 -403.64029)
		(end 10.863326 -404.02129)
		(width 0.127)
		(layer "B.Cu")
		(net "LAN2_P3_N")
	)
	(segment
		(start 14.4653 -407.971752)
		(end 15.23746 -407.199592)
		(width 0.127)
		(layer "B.Cu")
		(net "LAN2_P3_N")
	)
	(segment
		(start 7.689088 -353.923346)
		(end 6.78053 -354.831904)
		(width 0.127)
		(layer "B.Cu")
		(net "LAN2_P3_N")
	)
	(segment
		(start 11.441176 -406.791922)
		(end 11.710416 -407.061162)
		(width 0.127)
		(layer "B.Cu")
		(net "LAN2_P3_N")
	)
	(segment
		(start 10.648696 -405.999442)
		(end 10.883392 -406.234138)
		(width 0.127)
		(layer "B.Cu")
		(net "LAN2_P3_N")
	)
	(segment
		(start 10.863326 -404.831042)
		(end 10.863326 -405.212042)
		(width 0.127)
		(layer "B.Cu")
		(net "LAN2_P3_N")
	)
	(segment
		(start 15.23746 -407.199592)
		(end 15.23746 -406.761442)
		(width 0.127)
		(layer "B.Cu")
		(net "LAN2_P3_N")
	)
	(segment
		(start 10.242296 -398.68856)
		(end 10.242296 -406.167844)
		(width 0.127)
		(layer "B.Cu")
		(net "LAN2_P3_P")
	)
	(segment
		(start 15.343124 -405.508714)
		(end 15.429992 -405.335486)
		(width 0.127)
		(layer "B.Cu")
		(net "LAN2_P3_P")
	)
	(segment
		(start 7.282688 -353.754944)
		(end 6.37413 -354.663502)
		(width 0.127)
		(layer "B.Cu")
		(net "LAN2_P3_P")
	)
	(segment
		(start 7.099046 -350.205548)
		(end 7.282688 -350.38919)
		(width 0.127)
		(layer "B.Cu")
		(net "LAN2_P3_P")
	)
	(segment
		(start 6.37413 -354.663502)
		(end 6.37413 -394.820394)
		(width 0.127)
		(layer "B.Cu")
		(net "LAN2_P3_P")
	)
	(segment
		(start 15.192756 -405.658828)
		(end 15.343124 -405.508714)
		(width 0.127)
		(layer "B.Cu")
		(net "LAN2_P3_P")
	)
	(segment
		(start 14.633702 -408.378152)
		(end 15.64386 -407.367994)
		(width 0.127)
		(layer "B.Cu")
		(net "LAN2_P3_P")
	)
	(segment
		(start 15.429992 -405.335486)
		(end 15.600426 -405.278336)
		(width 0.127)
		(layer "B.Cu")
		(net "LAN2_P3_P")
	)
	(segment
		(start 15.64386 -407.367994)
		(end 15.64386 -406.59304)
		(width 0.127)
		(layer "B.Cu")
		(net "LAN2_P3_P")
	)
	(segment
		(start 6.914134 -350.205548)
		(end 7.099046 -350.205548)
		(width 0.127)
		(layer "B.Cu")
		(net "LAN2_P3_P")
	)
	(segment
		(start 12.452604 -408.378152)
		(end 14.633702 -408.378152)
		(width 0.127)
		(layer "B.Cu")
		(net "LAN2_P3_P")
	)
	(segment
		(start 7.282688 -350.38919)
		(end 7.282688 -353.754944)
		(width 0.127)
		(layer "B.Cu")
		(net "LAN2_P3_P")
	)
	(segment
		(start 15.192756 -406.141936)
		(end 15.192756 -405.658828)
		(width 0.127)
		(layer "B.Cu")
		(net "LAN2_P3_P")
	)
	(segment
		(start 15.64386 -406.59304)
		(end 15.192756 -406.141936)
		(width 0.127)
		(layer "B.Cu")
		(net "LAN2_P3_P")
	)
	(segment
		(start 15.600426 -405.278336)
		(end 16.574516 -405.766016)
		(width 0.127)
		(layer "B.Cu")
		(net "LAN2_P3_P")
	)
	(segment
		(start 6.37413 -394.820394)
		(end 10.242296 -398.68856)
		(width 0.127)
		(layer "B.Cu")
		(net "LAN2_P3_P")
	)
	(segment
		(start 6.449822 -350.66986)
		(end 6.914134 -350.205548)
		(width 0.127)
		(layer "B.Cu")
		(net "LAN2_P3_P")
	)
	(segment
		(start 10.242296 -406.167844)
		(end 12.452604 -408.378152)
		(width 0.127)
		(layer "B.Cu")
		(net "LAN2_P3_P")
	)
	(segment
		(start 10.613898 -365.04499)
		(end 10.367264 -365.29137)
		(width 0.127)
		(layer "B.Cu")
		(net "LAN2_P4_P")
	)
	(segment
		(start 10.613898 -348.782894)
		(end 10.613898 -360.02595)
		(width 0.127)
		(layer "B.Cu")
		(net "LAN2_P4_P")
	)
	(segment
		(start 10.367264 -365.29137)
		(end 10.367264 -365.67237)
		(width 0.127)
		(layer "B.Cu")
		(net "LAN2_P4_P")
	)
	(segment
		(start 14.49451 -394.460476)
		(end 14.49451 -400.669506)
		(width 0.127)
		(layer "B.Cu")
		(net "LAN2_P4_P")
	)
	(segment
		(start 10.367264 -362.78185)
		(end 10.367264 -363.16285)
		(width 0.127)
		(layer "B.Cu")
		(net "LAN2_P4_P")
	)
	(segment
		(start 7.837932 -346.953586)
		(end 8.78459 -346.953586)
		(width 0.127)
		(layer "B.Cu")
		(net "LAN2_P4_P")
	)
	(segment
		(start 10.367264 -364.03661)
		(end 10.367264 -364.41761)
		(width 0.127)
		(layer "B.Cu")
		(net "LAN2_P4_P")
	)
	(segment
		(start 15.009368 -401.184872)
		(end 15.009622 -401.185634)
		(width 0.127)
		(layer "B.Cu")
		(net "LAN2_P4_P")
	)
	(segment
		(start 10.367264 -364.41761)
		(end 10.613898 -364.66399)
		(width 0.127)
		(layer "B.Cu")
		(net "LAN2_P4_P")
	)
	(segment
		(start 8.449818 -347.669866)
		(end 7.736078 -347.309948)
		(width 0.127)
		(layer "B.Cu")
		(net "LAN2_P4_P")
	)
	(segment
		(start 10.367264 -361.90809)
		(end 10.613898 -362.15447)
		(width 0.127)
		(layer "B.Cu")
		(net "LAN2_P4_P")
	)
	(segment
		(start 10.367264 -365.67237)
		(end 10.613898 -365.91875)
		(width 0.127)
		(layer "B.Cu")
		(net "LAN2_P4_P")
	)
	(segment
		(start 10.367264 -363.16285)
		(end 10.613898 -363.40923)
		(width 0.127)
		(layer "B.Cu")
		(net "LAN2_P4_P")
	)
	(segment
		(start 7.736078 -347.309948)
		(end 7.679436 -347.139514)
		(width 0.127)
		(layer "B.Cu")
		(net "LAN2_P4_P")
	)
	(segment
		(start 10.613898 -364.66399)
		(end 10.613898 -365.04499)
		(width 0.127)
		(layer "B.Cu")
		(net "LAN2_P4_P")
	)
	(segment
		(start 10.367264 -366.92713)
		(end 10.613898 -367.17351)
		(width 0.127)
		(layer "B.Cu")
		(net "LAN2_P4_P")
	)
	(segment
		(start 10.613898 -360.02595)
		(end 10.367264 -360.27233)
		(width 0.127)
		(layer "B.Cu")
		(net "LAN2_P4_P")
	)
	(segment
		(start 10.613898 -367.17351)
		(end 10.613898 -369.43284)
		(width 0.127)
		(layer "B.Cu")
		(net "LAN2_P4_P")
	)
	(segment
		(start 10.613898 -369.43284)
		(end 9.625584 -370.421154)
		(width 0.127)
		(layer "B.Cu")
		(net "LAN2_P4_P")
	)
	(segment
		(start 10.613898 -363.79023)
		(end 10.367264 -364.03661)
		(width 0.127)
		(layer "B.Cu")
		(net "LAN2_P4_P")
	)
	(segment
		(start 15.009114 -401.467828)
		(end 14.034516 -401.956016)
		(width 0.127)
		(layer "B.Cu")
		(net "LAN2_P4_P")
	)
	(segment
		(start 10.613898 -362.15447)
		(end 10.613898 -362.53547)
		(width 0.127)
		(layer "B.Cu")
		(net "LAN2_P4_P")
	)
	(segment
		(start 8.78459 -346.953586)
		(end 10.613898 -348.782894)
		(width 0.127)
		(layer "B.Cu")
		(net "LAN2_P4_P")
	)
	(segment
		(start 10.367264 -361.52709)
		(end 10.367264 -361.90809)
		(width 0.127)
		(layer "B.Cu")
		(net "LAN2_P4_P")
	)
	(segment
		(start 9.625584 -389.59155)
		(end 14.49451 -394.460476)
		(width 0.127)
		(layer "B.Cu")
		(net "LAN2_P4_P")
	)
	(segment
		(start 10.613898 -361.28071)
		(end 10.367264 -361.52709)
		(width 0.127)
		(layer "B.Cu")
		(net "LAN2_P4_P")
	)
	(segment
		(start 15.009368 -401.184364)
		(end 15.009368 -401.184872)
		(width 0.127)
		(layer "B.Cu")
		(net "LAN2_P4_P")
	)
	(segment
		(start 10.613898 -363.40923)
		(end 10.613898 -363.79023)
		(width 0.127)
		(layer "B.Cu")
		(net "LAN2_P4_P")
	)
	(segment
		(start 10.367264 -366.54613)
		(end 10.367264 -366.92713)
		(width 0.127)
		(layer "B.Cu")
		(net "LAN2_P4_P")
	)
	(segment
		(start 10.367264 -360.27233)
		(end 10.367264 -360.65333)
		(width 0.127)
		(layer "B.Cu")
		(net "LAN2_P4_P")
	)
	(segment
		(start 10.613898 -360.89971)
		(end 10.613898 -361.28071)
		(width 0.127)
		(layer "B.Cu")
		(net "LAN2_P4_P")
	)
	(segment
		(start 7.679182 -347.139006)
		(end 7.706106 -347.085412)
		(width 0.127)
		(layer "B.Cu")
		(net "LAN2_P4_P")
	)
	(segment
		(start 7.679436 -347.139514)
		(end 7.679182 -347.139006)
		(width 0.127)
		(layer "B.Cu")
		(net "LAN2_P4_P")
	)
	(segment
		(start 10.613898 -366.29975)
		(end 10.367264 -366.54613)
		(width 0.127)
		(layer "B.Cu")
		(net "LAN2_P4_P")
	)
	(segment
		(start 10.613898 -365.91875)
		(end 10.613898 -366.29975)
		(width 0.127)
		(layer "B.Cu")
		(net "LAN2_P4_P")
	)
	(segment
		(start 10.613898 -362.53547)
		(end 10.367264 -362.78185)
		(width 0.127)
		(layer "B.Cu")
		(net "LAN2_P4_P")
	)
	(segment
		(start 7.706106 -347.085412)
		(end 7.837932 -346.953586)
		(width 0.127)
		(layer "B.Cu")
		(net "LAN2_P4_P")
	)
	(segment
		(start 15.009622 -401.185634)
		(end 15.065756 -401.297394)
		(width 0.127)
		(layer "B.Cu")
		(net "LAN2_P4_P")
	)
	(segment
		(start 9.625584 -370.421154)
		(end 9.625584 -389.59155)
		(width 0.127)
		(layer "B.Cu")
		(net "LAN2_P4_P")
	)
	(segment
		(start 15.065756 -401.297394)
		(end 15.009114 -401.467828)
		(width 0.127)
		(layer "B.Cu")
		(net "LAN2_P4_P")
	)
	(segment
		(start 14.49451 -400.669506)
		(end 15.009368 -401.184364)
		(width 0.127)
		(layer "B.Cu")
		(net "LAN2_P4_P")
	)
	(segment
		(start 10.367264 -360.65333)
		(end 10.613898 -360.89971)
		(width 0.127)
		(layer "B.Cu")
		(net "LAN2_P4_P")
	)
	(segment
		(start 16.574516 -400.686016)
		(end 15.600426 -401.173696)
		(width 0.127)
		(layer "B.Cu")
		(net "LAN2_P4_N")
	)
	(segment
		(start 14.90091 -400.501104)
		(end 14.90091 -394.292074)
		(width 0.127)
		(layer "B.Cu")
		(net "LAN2_P4_N")
	)
	(segment
		(start 11.020298 -348.614492)
		(end 8.952992 -346.547186)
		(width 0.127)
		(layer "B.Cu")
		(net "LAN2_P4_N")
	)
	(segment
		(start 7.66953 -346.547186)
		(end 7.37235 -346.844366)
		(width 0.127)
		(layer "B.Cu")
		(net "LAN2_P4_N")
	)
	(segment
		(start 14.90091 -394.292074)
		(end 10.031984 -389.423148)
		(width 0.127)
		(layer "B.Cu")
		(net "LAN2_P4_N")
	)
	(segment
		(start 10.031984 -389.423148)
		(end 10.031984 -370.589556)
		(width 0.127)
		(layer "B.Cu")
		(net "LAN2_P4_N")
	)
	(segment
		(start 7.37235 -346.844366)
		(end 7.3152 -346.958158)
		(width 0.127)
		(layer "B.Cu")
		(net "LAN2_P4_N")
	)
	(segment
		(start 15.600426 -401.173696)
		(end 15.429992 -401.116546)
		(width 0.127)
		(layer "B.Cu")
		(net "LAN2_P4_N")
	)
	(segment
		(start 11.020298 -369.601242)
		(end 11.020298 -348.614492)
		(width 0.127)
		(layer "B.Cu")
		(net "LAN2_P4_N")
	)
	(segment
		(start 15.429992 -401.116546)
		(end 15.372842 -401.0025)
		(width 0.127)
		(layer "B.Cu")
		(net "LAN2_P4_N")
	)
	(segment
		(start 15.343124 -400.943318)
		(end 14.90091 -400.501104)
		(width 0.127)
		(layer "B.Cu")
		(net "LAN2_P4_N")
	)
	(segment
		(start 7.144766 -347.015308)
		(end 6.449822 -346.669868)
		(width 0.127)
		(layer "B.Cu")
		(net "LAN2_P4_N")
	)
	(segment
		(start 7.3152 -346.958158)
		(end 7.144766 -347.015308)
		(width 0.127)
		(layer "B.Cu")
		(net "LAN2_P4_N")
	)
	(segment
		(start 8.952992 -346.547186)
		(end 7.66953 -346.547186)
		(width 0.127)
		(layer "B.Cu")
		(net "LAN2_P4_N")
	)
	(segment
		(start 15.372842 -401.0025)
		(end 15.343124 -400.943318)
		(width 0.127)
		(layer "B.Cu")
		(net "LAN2_P4_N")
	)
	(segment
		(start 10.031984 -370.589556)
		(end 11.020298 -369.601242)
		(width 0.127)
		(layer "B.Cu")
		(net "LAN2_P4_N")
	)
	(segment
		(start 12.73683 -162.141916)
		(end 12.86383 -162.014916)
		(width 0.127)
		(layer "B.Cu")
		(net "LAN1_P1_P")
	)
	(segment
		(start 11.947652 -157.839918)
		(end 11.947652 -156.339286)
		(width 0.127)
		(layer "B.Cu")
		(net "LAN1_P1_P")
	)
	(segment
		(start 7.830566 -189.410594)
		(end 9.784588 -189.410594)
		(width 0.127)
		(layer "B.Cu")
		(net "LAN1_P1_P")
	)
	(segment
		(start 10.166604 -189.028578)
		(end 10.166604 -188.7093)
		(width 0.127)
		(layer "B.Cu")
		(net "LAN1_P1_P")
	)
	(segment
		(start 15.179548 -140.411962)
		(end 15.009368 -140.354812)
		(width 0.127)
		(layer "B.Cu")
		(net "LAN1_P1_P")
	)
	(segment
		(start 14.441424 -146.205448)
		(end 14.441424 -142.56258)
		(width 0.127)
		(layer "B.Cu")
		(net "LAN1_P1_P")
	)
	(segment
		(start 7.57428 -188.375036)
		(end 7.51713 -188.488828)
		(width 0.127)
		(layer "B.Cu")
		(net "LAN1_P1_P")
	)
	(segment
		(start 11.947652 -163.631118)
		(end 11.947652 -162.506914)
		(width 0.127)
		(layer "B.Cu")
		(net "LAN1_P1_P")
	)
	(segment
		(start 12.31265 -167.933116)
		(end 12.73683 -167.933116)
		(width 0.127)
		(layer "B.Cu")
		(net "LAN1_P1_P")
	)
	(segment
		(start 12.73683 -158.204916)
		(end 12.31265 -158.204916)
		(width 0.127)
		(layer "B.Cu")
		(net "LAN1_P1_P")
	)
	(segment
		(start 12.73683 -166.891716)
		(end 12.31265 -166.891716)
		(width 0.127)
		(layer "B.Cu")
		(net "LAN1_P1_P")
	)
	(segment
		(start 11.947652 -148.69922)
		(end 14.441424 -146.205448)
		(width 0.127)
		(layer "B.Cu")
		(net "LAN1_P1_P")
	)
	(segment
		(start 11.947652 -153.199846)
		(end 11.947652 -152.818846)
		(width 0.127)
		(layer "B.Cu")
		(net "LAN1_P1_P")
	)
	(segment
		(start 11.947652 -151.645366)
		(end 11.741658 -151.439626)
		(width 0.127)
		(layer "B.Cu")
		(net "LAN1_P1_P")
	)
	(segment
		(start 11.947652 -187.24753)
		(end 11.947652 -168.298114)
		(width 0.127)
		(layer "B.Cu")
		(net "LAN1_P1_P")
	)
	(segment
		(start 7.487412 -188.547756)
		(end 7.440676 -188.594492)
		(width 0.127)
		(layer "B.Cu")
		(net "LAN1_P1_P")
	)
	(segment
		(start 11.947652 -154.373326)
		(end 11.947652 -153.992326)
		(width 0.127)
		(layer "B.Cu")
		(net "LAN1_P1_P")
	)
	(segment
		(start 10.755376 -188.439806)
		(end 11.025124 -188.170058)
		(width 0.127)
		(layer "B.Cu")
		(net "LAN1_P1_P")
	)
	(segment
		(start 11.947652 -155.546806)
		(end 11.947652 -155.165806)
		(width 0.127)
		(layer "B.Cu")
		(net "LAN1_P1_P")
	)
	(segment
		(start 11.947652 -152.818846)
		(end 11.741658 -152.613106)
		(width 0.127)
		(layer "B.Cu")
		(net "LAN1_P1_P")
	)
	(segment
		(start 12.86383 -158.331916)
		(end 12.73683 -158.204916)
		(width 0.127)
		(layer "B.Cu")
		(net "LAN1_P1_P")
	)
	(segment
		(start 12.73683 -159.246316)
		(end 12.86383 -159.119316)
		(width 0.127)
		(layer "B.Cu")
		(net "LAN1_P1_P")
	)
	(segment
		(start 8.448802 -188.670438)
		(end 7.744714 -188.317886)
		(width 0.127)
		(layer "B.Cu")
		(net "LAN1_P1_P")
	)
	(segment
		(start 12.31265 -163.996116)
		(end 11.947652 -163.631118)
		(width 0.127)
		(layer "B.Cu")
		(net "LAN1_P1_P")
	)
	(segment
		(start 11.947652 -150.471886)
		(end 11.741658 -150.266146)
		(width 0.127)
		(layer "B.Cu")
		(net "LAN1_P1_P")
	)
	(segment
		(start 7.440676 -189.020704)
		(end 7.830566 -189.410594)
		(width 0.127)
		(layer "B.Cu")
		(net "LAN1_P1_P")
	)
	(segment
		(start 11.741658 -152.613106)
		(end 11.741658 -152.232106)
		(width 0.127)
		(layer "B.Cu")
		(net "LAN1_P1_P")
	)
	(segment
		(start 11.947652 -155.165806)
		(end 11.741658 -154.960066)
		(width 0.127)
		(layer "B.Cu")
		(net "LAN1_P1_P")
	)
	(segment
		(start 11.947652 -150.852886)
		(end 11.947652 -150.471886)
		(width 0.127)
		(layer "B.Cu")
		(net "LAN1_P1_P")
	)
	(segment
		(start 11.947652 -165.402514)
		(end 12.31265 -165.037516)
		(width 0.127)
		(layer "B.Cu")
		(net "LAN1_P1_P")
	)
	(segment
		(start 11.741658 -154.579066)
		(end 11.947652 -154.373326)
		(width 0.127)
		(layer "B.Cu")
		(net "LAN1_P1_P")
	)
	(segment
		(start 10.436352 -188.439552)
		(end 10.595864 -188.439552)
		(width 0.127)
		(layer "B.Cu")
		(net "LAN1_P1_P")
	)
	(segment
		(start 7.744714 -188.317886)
		(end 7.57428 -188.375036)
		(width 0.127)
		(layer "B.Cu")
		(net "LAN1_P1_P")
	)
	(segment
		(start 15.236698 -140.526008)
		(end 15.179548 -140.411962)
		(width 0.127)
		(layer "B.Cu")
		(net "LAN1_P1_P")
	)
	(segment
		(start 12.73683 -165.037516)
		(end 12.86383 -164.910516)
		(width 0.127)
		(layer "B.Cu")
		(net "LAN1_P1_P")
	)
	(segment
		(start 12.86383 -167.018716)
		(end 12.73683 -166.891716)
		(width 0.127)
		(layer "B.Cu")
		(net "LAN1_P1_P")
	)
	(segment
		(start 11.741658 -151.058626)
		(end 11.947652 -150.852886)
		(width 0.127)
		(layer "B.Cu")
		(net "LAN1_P1_P")
	)
	(segment
		(start 11.741658 -153.786586)
		(end 11.741658 -153.405586)
		(width 0.127)
		(layer "B.Cu")
		(net "LAN1_P1_P")
	)
	(segment
		(start 12.86383 -159.119316)
		(end 12.86383 -158.331916)
		(width 0.127)
		(layer "B.Cu")
		(net "LAN1_P1_P")
	)
	(segment
		(start 11.947652 -168.298114)
		(end 12.31265 -167.933116)
		(width 0.127)
		(layer "B.Cu")
		(net "LAN1_P1_P")
	)
	(segment
		(start 11.741658 -154.960066)
		(end 11.741658 -154.579066)
		(width 0.127)
		(layer "B.Cu")
		(net "LAN1_P1_P")
	)
	(segment
		(start 11.947652 -162.506914)
		(end 12.31265 -162.141916)
		(width 0.127)
		(layer "B.Cu")
		(net "LAN1_P1_P")
	)
	(segment
		(start 7.51713 -188.488828)
		(end 7.516876 -188.488828)
		(width 0.127)
		(layer "B.Cu")
		(net "LAN1_P1_P")
	)
	(segment
		(start 11.947652 -156.339286)
		(end 11.741658 -156.133546)
		(width 0.127)
		(layer "B.Cu")
		(net "LAN1_P1_P")
	)
	(segment
		(start 7.516876 -188.488828)
		(end 7.487412 -188.547756)
		(width 0.127)
		(layer "B.Cu")
		(net "LAN1_P1_P")
	)
	(segment
		(start 12.86383 -164.123116)
		(end 12.73683 -163.996116)
		(width 0.127)
		(layer "B.Cu")
		(net "LAN1_P1_P")
	)
	(segment
		(start 11.294872 -187.581032)
		(end 11.454384 -187.581032)
		(width 0.127)
		(layer "B.Cu")
		(net "LAN1_P1_P")
	)
	(segment
		(start 12.31265 -159.246316)
		(end 12.73683 -159.246316)
		(width 0.127)
		(layer "B.Cu")
		(net "LAN1_P1_P")
	)
	(segment
		(start 11.947652 -166.526718)
		(end 11.947652 -165.402514)
		(width 0.127)
		(layer "B.Cu")
		(net "LAN1_P1_P")
	)
	(segment
		(start 15.236698 -141.767306)
		(end 15.236698 -140.526008)
		(width 0.127)
		(layer "B.Cu")
		(net "LAN1_P1_P")
	)
	(segment
		(start 11.025124 -187.85078)
		(end 11.294872 -187.581032)
		(width 0.127)
		(layer "B.Cu")
		(net "LAN1_P1_P")
	)
	(segment
		(start 15.009368 -140.354812)
		(end 14.034516 -140.843)
		(width 0.127)
		(layer "B.Cu")
		(net "LAN1_P1_P")
	)
	(segment
		(start 7.440676 -188.594492)
		(end 7.440676 -189.020704)
		(width 0.127)
		(layer "B.Cu")
		(net "LAN1_P1_P")
	)
	(segment
		(start 11.741658 -156.133546)
		(end 11.741658 -155.752546)
		(width 0.127)
		(layer "B.Cu")
		(net "LAN1_P1_P")
	)
	(segment
		(start 11.741658 -151.439626)
		(end 11.741658 -151.058626)
		(width 0.127)
		(layer "B.Cu")
		(net "LAN1_P1_P")
	)
	(segment
		(start 12.31265 -166.891716)
		(end 11.947652 -166.526718)
		(width 0.127)
		(layer "B.Cu")
		(net "LAN1_P1_P")
	)
	(segment
		(start 11.741658 -150.266146)
		(end 11.741658 -149.885146)
		(width 0.127)
		(layer "B.Cu")
		(net "LAN1_P1_P")
	)
	(segment
		(start 12.86383 -162.014916)
		(end 12.86383 -161.227516)
		(width 0.127)
		(layer "B.Cu")
		(net "LAN1_P1_P")
	)
	(segment
		(start 9.784588 -189.410594)
		(end 10.166604 -189.028578)
		(width 0.127)
		(layer "B.Cu")
		(net "LAN1_P1_P")
	)
	(segment
		(start 11.025124 -188.170058)
		(end 11.025124 -187.85078)
		(width 0.127)
		(layer "B.Cu")
		(net "LAN1_P1_P")
	)
	(segment
		(start 10.166604 -188.7093)
		(end 10.436352 -188.439552)
		(width 0.127)
		(layer "B.Cu")
		(net "LAN1_P1_P")
	)
	(segment
		(start 11.613896 -187.581286)
		(end 11.947652 -187.24753)
		(width 0.127)
		(layer "B.Cu")
		(net "LAN1_P1_P")
	)
	(segment
		(start 12.86383 -164.910516)
		(end 12.86383 -164.123116)
		(width 0.127)
		(layer "B.Cu")
		(net "LAN1_P1_P")
	)
	(segment
		(start 12.73683 -163.996116)
		(end 12.31265 -163.996116)
		(width 0.127)
		(layer "B.Cu")
		(net "LAN1_P1_P")
	)
	(segment
		(start 11.741658 -153.405586)
		(end 11.947652 -153.199846)
		(width 0.127)
		(layer "B.Cu")
		(net "LAN1_P1_P")
	)
	(segment
		(start 11.947652 -159.611314)
		(end 12.31265 -159.246316)
		(width 0.127)
		(layer "B.Cu")
		(net "LAN1_P1_P")
	)
	(segment
		(start 12.73683 -161.100516)
		(end 12.31265 -161.100516)
		(width 0.127)
		(layer "B.Cu")
		(net "LAN1_P1_P")
	)
	(segment
		(start 12.31265 -161.100516)
		(end 11.947652 -160.735518)
		(width 0.127)
		(layer "B.Cu")
		(net "LAN1_P1_P")
	)
	(segment
		(start 11.741658 -152.232106)
		(end 11.947652 -152.026366)
		(width 0.127)
		(layer "B.Cu")
		(net "LAN1_P1_P")
	)
	(segment
		(start 11.741658 -149.885146)
		(end 11.947652 -149.679406)
		(width 0.127)
		(layer "B.Cu")
		(net "LAN1_P1_P")
	)
	(segment
		(start 12.31265 -162.141916)
		(end 12.73683 -162.141916)
		(width 0.127)
		(layer "B.Cu")
		(net "LAN1_P1_P")
	)
	(segment
		(start 11.947652 -153.992326)
		(end 11.741658 -153.786586)
		(width 0.127)
		(layer "B.Cu")
		(net "LAN1_P1_P")
	)
	(segment
		(start 11.947652 -152.026366)
		(end 11.947652 -151.645366)
		(width 0.127)
		(layer "B.Cu")
		(net "LAN1_P1_P")
	)
	(segment
		(start 12.31265 -158.204916)
		(end 11.947652 -157.839918)
		(width 0.127)
		(layer "B.Cu")
		(net "LAN1_P1_P")
	)
	(segment
		(start 14.441424 -142.56258)
		(end 15.236698 -141.767306)
		(width 0.127)
		(layer "B.Cu")
		(net "LAN1_P1_P")
	)
	(segment
		(start 12.73683 -167.933116)
		(end 12.86383 -167.806116)
		(width 0.127)
		(layer "B.Cu")
		(net "LAN1_P1_P")
	)
	(segment
		(start 12.31265 -165.037516)
		(end 12.73683 -165.037516)
		(width 0.127)
		(layer "B.Cu")
		(net "LAN1_P1_P")
	)
	(segment
		(start 11.741658 -155.752546)
		(end 11.947652 -155.546806)
		(width 0.127)
		(layer "B.Cu")
		(net "LAN1_P1_P")
	)
	(segment
		(start 10.595864 -188.439552)
		(end 10.755376 -188.439806)
		(width 0.127)
		(layer "B.Cu")
		(net "LAN1_P1_P")
	)
	(segment
		(start 11.947652 -149.679406)
		(end 11.947652 -148.69922)
		(width 0.127)
		(layer "B.Cu")
		(net "LAN1_P1_P")
	)
	(segment
		(start 12.86383 -167.806116)
		(end 12.86383 -167.018716)
		(width 0.127)
		(layer "B.Cu")
		(net "LAN1_P1_P")
	)
	(segment
		(start 11.947652 -160.735518)
		(end 11.947652 -159.611314)
		(width 0.127)
		(layer "B.Cu")
		(net "LAN1_P1_P")
	)
	(segment
		(start 12.86383 -161.227516)
		(end 12.73683 -161.100516)
		(width 0.127)
		(layer "B.Cu")
		(net "LAN1_P1_P")
	)
	(segment
		(start 11.454384 -187.581032)
		(end 11.613896 -187.581286)
		(width 0.127)
		(layer "B.Cu")
		(net "LAN1_P1_P")
	)
	(segment
		(start 12.481052 -157.798516)
		(end 12.354052 -157.671516)
		(width 0.127)
		(layer "B.Cu")
		(net "LAN1_P1_N")
	)
	(segment
		(start 12.354052 -165.570916)
		(end 12.481052 -165.443916)
		(width 0.127)
		(layer "B.Cu")
		(net "LAN1_P1_N")
	)
	(segment
		(start 12.905232 -162.548316)
		(end 13.27023 -162.183318)
		(width 0.127)
		(layer "B.Cu")
		(net "LAN1_P1_N")
	)
	(segment
		(start 6.448806 -187.67044)
		(end 7.153402 -188.023246)
		(width 0.127)
		(layer "B.Cu")
		(net "LAN1_P1_N")
	)
	(segment
		(start 7.034276 -189.189106)
		(end 7.662164 -189.816994)
		(width 0.127)
		(layer "B.Cu")
		(net "LAN1_P1_N")
	)
	(segment
		(start 12.354052 -187.415932)
		(end 12.354052 -168.466516)
		(width 0.127)
		(layer "B.Cu")
		(net "LAN1_P1_N")
	)
	(segment
		(start 13.27023 -162.183318)
		(end 13.27023 -161.059114)
		(width 0.127)
		(layer "B.Cu")
		(net "LAN1_P1_N")
	)
	(segment
		(start 12.354052 -166.358316)
		(end 12.354052 -165.570916)
		(width 0.127)
		(layer "B.Cu")
		(net "LAN1_P1_N")
	)
	(segment
		(start 12.481052 -166.485316)
		(end 12.354052 -166.358316)
		(width 0.127)
		(layer "B.Cu")
		(net "LAN1_P1_N")
	)
	(segment
		(start 9.95299 -189.816994)
		(end 12.354052 -187.415932)
		(width 0.127)
		(layer "B.Cu")
		(net "LAN1_P1_N")
	)
	(segment
		(start 12.354052 -168.466516)
		(end 12.481052 -168.339516)
		(width 0.127)
		(layer "B.Cu")
		(net "LAN1_P1_N")
	)
	(segment
		(start 15.643098 -141.935708)
		(end 15.643098 -140.429742)
		(width 0.127)
		(layer "B.Cu")
		(net "LAN1_P1_N")
	)
	(segment
		(start 13.27023 -161.059114)
		(end 12.905232 -160.694116)
		(width 0.127)
		(layer "B.Cu")
		(net "LAN1_P1_N")
	)
	(segment
		(start 12.905232 -166.485316)
		(end 12.481052 -166.485316)
		(width 0.127)
		(layer "B.Cu")
		(net "LAN1_P1_N")
	)
	(segment
		(start 13.27023 -166.850314)
		(end 12.905232 -166.485316)
		(width 0.127)
		(layer "B.Cu")
		(net "LAN1_P1_N")
	)
	(segment
		(start 13.27023 -165.078918)
		(end 13.27023 -163.954714)
		(width 0.127)
		(layer "B.Cu")
		(net "LAN1_P1_N")
	)
	(segment
		(start 13.27023 -158.163514)
		(end 12.905232 -157.798516)
		(width 0.127)
		(layer "B.Cu")
		(net "LAN1_P1_N")
	)
	(segment
		(start 7.662164 -189.816994)
		(end 9.95299 -189.816994)
		(width 0.127)
		(layer "B.Cu")
		(net "LAN1_P1_N")
	)
	(segment
		(start 15.643098 -140.429742)
		(end 15.600426 -140.344144)
		(width 0.127)
		(layer "B.Cu")
		(net "LAN1_P1_N")
	)
	(segment
		(start 12.481052 -162.548316)
		(end 12.905232 -162.548316)
		(width 0.127)
		(layer "B.Cu")
		(net "LAN1_P1_N")
	)
	(segment
		(start 12.354052 -159.779716)
		(end 12.481052 -159.652716)
		(width 0.127)
		(layer "B.Cu")
		(net "LAN1_P1_N")
	)
	(segment
		(start 12.481052 -163.589716)
		(end 12.354052 -163.462716)
		(width 0.127)
		(layer "B.Cu")
		(net "LAN1_P1_N")
	)
	(segment
		(start 13.27023 -167.974518)
		(end 13.27023 -166.850314)
		(width 0.127)
		(layer "B.Cu")
		(net "LAN1_P1_N")
	)
	(segment
		(start 12.354052 -162.675316)
		(end 12.481052 -162.548316)
		(width 0.127)
		(layer "B.Cu")
		(net "LAN1_P1_N")
	)
	(segment
		(start 7.153402 -188.306964)
		(end 7.034276 -188.42609)
		(width 0.127)
		(layer "B.Cu")
		(net "LAN1_P1_N")
	)
	(segment
		(start 13.27023 -159.287718)
		(end 13.27023 -158.163514)
		(width 0.127)
		(layer "B.Cu")
		(net "LAN1_P1_N")
	)
	(segment
		(start 15.600426 -140.06068)
		(end 16.574516 -139.573)
		(width 0.127)
		(layer "B.Cu")
		(net "LAN1_P1_N")
	)
	(segment
		(start 12.354052 -163.462716)
		(end 12.354052 -162.675316)
		(width 0.127)
		(layer "B.Cu")
		(net "LAN1_P1_N")
	)
	(segment
		(start 12.905232 -165.443916)
		(end 13.27023 -165.078918)
		(width 0.127)
		(layer "B.Cu")
		(net "LAN1_P1_N")
	)
	(segment
		(start 12.354052 -157.671516)
		(end 12.354052 -148.867622)
		(width 0.127)
		(layer "B.Cu")
		(net "LAN1_P1_N")
	)
	(segment
		(start 13.27023 -163.954714)
		(end 12.905232 -163.589716)
		(width 0.127)
		(layer "B.Cu")
		(net "LAN1_P1_N")
	)
	(segment
		(start 12.481052 -168.339516)
		(end 12.905232 -168.339516)
		(width 0.127)
		(layer "B.Cu")
		(net "LAN1_P1_N")
	)
	(segment
		(start 7.153402 -188.023246)
		(end 7.210044 -188.19368)
		(width 0.127)
		(layer "B.Cu")
		(net "LAN1_P1_N")
	)
	(segment
		(start 12.481052 -159.652716)
		(end 12.905232 -159.652716)
		(width 0.127)
		(layer "B.Cu")
		(net "LAN1_P1_N")
	)
	(segment
		(start 12.905232 -157.798516)
		(end 12.481052 -157.798516)
		(width 0.127)
		(layer "B.Cu")
		(net "LAN1_P1_N")
	)
	(segment
		(start 15.543784 -140.231114)
		(end 15.600426 -140.06068)
		(width 0.127)
		(layer "B.Cu")
		(net "LAN1_P1_N")
	)
	(segment
		(start 12.481052 -160.694116)
		(end 12.354052 -160.567116)
		(width 0.127)
		(layer "B.Cu")
		(net "LAN1_P1_N")
	)
	(segment
		(start 7.210044 -188.19368)
		(end 7.153402 -188.306964)
		(width 0.127)
		(layer "B.Cu")
		(net "LAN1_P1_N")
	)
	(segment
		(start 12.354052 -148.867622)
		(end 14.847824 -146.37385)
		(width 0.127)
		(layer "B.Cu")
		(net "LAN1_P1_N")
	)
	(segment
		(start 12.905232 -159.652716)
		(end 13.27023 -159.287718)
		(width 0.127)
		(layer "B.Cu")
		(net "LAN1_P1_N")
	)
	(segment
		(start 15.600426 -140.344144)
		(end 15.543784 -140.231114)
		(width 0.127)
		(layer "B.Cu")
		(net "LAN1_P1_N")
	)
	(segment
		(start 12.905232 -160.694116)
		(end 12.481052 -160.694116)
		(width 0.127)
		(layer "B.Cu")
		(net "LAN1_P1_N")
	)
	(segment
		(start 14.847824 -142.730982)
		(end 15.643098 -141.935708)
		(width 0.127)
		(layer "B.Cu")
		(net "LAN1_P1_N")
	)
	(segment
		(start 12.481052 -165.443916)
		(end 12.905232 -165.443916)
		(width 0.127)
		(layer "B.Cu")
		(net "LAN1_P1_N")
	)
	(segment
		(start 12.905232 -163.589716)
		(end 12.481052 -163.589716)
		(width 0.127)
		(layer "B.Cu")
		(net "LAN1_P1_N")
	)
	(segment
		(start 12.905232 -168.339516)
		(end 13.27023 -167.974518)
		(width 0.127)
		(layer "B.Cu")
		(net "LAN1_P1_N")
	)
	(segment
		(start 7.034276 -188.42609)
		(end 7.034276 -189.189106)
		(width 0.127)
		(layer "B.Cu")
		(net "LAN1_P1_N")
	)
	(segment
		(start 14.847824 -146.37385)
		(end 14.847824 -142.730982)
		(width 0.127)
		(layer "B.Cu")
		(net "LAN1_P1_N")
	)
	(segment
		(start 12.354052 -160.567116)
		(end 12.354052 -159.779716)
		(width 0.127)
		(layer "B.Cu")
		(net "LAN1_P1_N")
	)
	(segment
		(start 8.720836 -164.252148)
		(end 9.085834 -164.617146)
		(width 0.127)
		(layer "B.Cu")
		(net "LAN1_P2_P")
	)
	(segment
		(start 11.001248 -137.947654)
		(end 11.001248 -138.328654)
		(width 0.127)
		(layer "B.Cu")
		(net "LAN1_P2_P")
	)
	(segment
		(start 9.712198 -185.362342)
		(end 9.185656 -185.888884)
		(width 0.127)
		(layer "B.Cu")
		(net "LAN1_P2_P")
	)
	(segment
		(start 9.085834 -164.617146)
		(end 9.085834 -165.74135)
		(width 0.127)
		(layer "B.Cu")
		(net "LAN1_P2_P")
	)
	(segment
		(start 8.390128 -169.001948)
		(end 8.263128 -169.128948)
		(width 0.127)
		(layer "B.Cu")
		(net "LAN1_P2_P")
	)
	(segment
		(start 10.82294 -142.89786)
		(end 8.263128 -145.457672)
		(width 0.127)
		(layer "B.Cu")
		(net "LAN1_P2_P")
	)
	(segment
		(start 8.263128 -169.128948)
		(end 8.263128 -169.916348)
		(width 0.127)
		(layer "B.Cu")
		(net "LAN1_P2_P")
	)
	(segment
		(start 11.001248 -139.06627)
		(end 11.001248 -139.44727)
		(width 0.127)
		(layer "B.Cu")
		(net "LAN1_P2_P")
	)
	(segment
		(start 11.651234 -135.93318)
		(end 10.82294 -136.761474)
		(width 0.127)
		(layer "B.Cu")
		(net "LAN1_P2_P")
	)
	(segment
		(start 11.001248 -140.565886)
		(end 10.82294 -140.744194)
		(width 0.127)
		(layer "B.Cu")
		(net "LAN1_P2_P")
	)
	(segment
		(start 8.390128 -166.106348)
		(end 8.263128 -166.233348)
		(width 0.127)
		(layer "B.Cu")
		(net "LAN1_P2_P")
	)
	(segment
		(start 12.89685 -135.93318)
		(end 11.651234 -135.93318)
		(width 0.127)
		(layer "B.Cu")
		(net "LAN1_P2_P")
	)
	(segment
		(start 7.410196 -185.547762)
		(end 7.380732 -185.488834)
		(width 0.127)
		(layer "B.Cu")
		(net "LAN1_P2_P")
	)
	(segment
		(start 10.82294 -139.625578)
		(end 10.82294 -140.006578)
		(width 0.127)
		(layer "B.Cu")
		(net "LAN1_P2_P")
	)
	(segment
		(start 10.82294 -138.887962)
		(end 11.001248 -139.06627)
		(width 0.127)
		(layer "B.Cu")
		(net "LAN1_P2_P")
	)
	(segment
		(start 8.720836 -170.043348)
		(end 9.085834 -170.408346)
		(width 0.127)
		(layer "B.Cu")
		(net "LAN1_P2_P")
	)
	(segment
		(start 14.034516 -138.303)
		(end 14.034516 -137.070846)
		(width 0.127)
		(layer "B.Cu")
		(net "LAN1_P2_P")
	)
	(segment
		(start 9.185656 -185.888884)
		(end 7.751318 -185.888884)
		(width 0.127)
		(layer "B.Cu")
		(net "LAN1_P2_P")
	)
	(segment
		(start 9.085834 -167.512746)
		(end 9.085834 -168.63695)
		(width 0.127)
		(layer "B.Cu")
		(net "LAN1_P2_P")
	)
	(segment
		(start 10.82294 -140.006578)
		(end 11.001248 -140.184886)
		(width 0.127)
		(layer "B.Cu")
		(net "LAN1_P2_P")
	)
	(segment
		(start 8.390128 -167.147748)
		(end 8.720836 -167.147748)
		(width 0.127)
		(layer "B.Cu")
		(net "LAN1_P2_P")
	)
	(segment
		(start 8.263128 -169.916348)
		(end 8.390128 -170.043348)
		(width 0.127)
		(layer "B.Cu")
		(net "LAN1_P2_P")
	)
	(segment
		(start 9.085834 -168.63695)
		(end 8.720836 -169.001948)
		(width 0.127)
		(layer "B.Cu")
		(net "LAN1_P2_P")
	)
	(segment
		(start 11.001248 -140.184886)
		(end 11.001248 -140.565886)
		(width 0.127)
		(layer "B.Cu")
		(net "LAN1_P2_P")
	)
	(segment
		(start 8.720836 -167.147748)
		(end 9.085834 -167.512746)
		(width 0.127)
		(layer "B.Cu")
		(net "LAN1_P2_P")
	)
	(segment
		(start 8.263128 -166.233348)
		(end 8.263128 -167.020748)
		(width 0.127)
		(layer "B.Cu")
		(net "LAN1_P2_P")
	)
	(segment
		(start 7.323328 -185.375042)
		(end 7.152894 -185.317892)
		(width 0.127)
		(layer "B.Cu")
		(net "LAN1_P2_P")
	)
	(segment
		(start 8.263128 -172.024548)
		(end 8.263128 -173.755304)
		(width 0.127)
		(layer "B.Cu")
		(net "LAN1_P2_P")
	)
	(segment
		(start 9.712198 -175.204374)
		(end 9.712198 -185.362342)
		(width 0.127)
		(layer "B.Cu")
		(net "LAN1_P2_P")
	)
	(segment
		(start 10.82294 -140.744194)
		(end 10.82294 -142.89786)
		(width 0.127)
		(layer "B.Cu")
		(net "LAN1_P2_P")
	)
	(segment
		(start 10.82294 -138.506962)
		(end 10.82294 -138.887962)
		(width 0.127)
		(layer "B.Cu")
		(net "LAN1_P2_P")
	)
	(segment
		(start 8.720836 -169.001948)
		(end 8.390128 -169.001948)
		(width 0.127)
		(layer "B.Cu")
		(net "LAN1_P2_P")
	)
	(segment
		(start 9.085834 -170.408346)
		(end 9.085834 -171.53255)
		(width 0.127)
		(layer "B.Cu")
		(net "LAN1_P2_P")
	)
	(segment
		(start 8.263128 -145.457672)
		(end 8.263128 -164.125148)
		(width 0.127)
		(layer "B.Cu")
		(net "LAN1_P2_P")
	)
	(segment
		(start 8.390128 -164.252148)
		(end 8.720836 -164.252148)
		(width 0.127)
		(layer "B.Cu")
		(net "LAN1_P2_P")
	)
	(segment
		(start 7.152894 -185.317892)
		(end 6.448806 -185.670444)
		(width 0.127)
		(layer "B.Cu")
		(net "LAN1_P2_P")
	)
	(segment
		(start 7.751318 -185.888884)
		(end 7.410196 -185.547762)
		(width 0.127)
		(layer "B.Cu")
		(net "LAN1_P2_P")
	)
	(segment
		(start 8.390128 -170.043348)
		(end 8.720836 -170.043348)
		(width 0.127)
		(layer "B.Cu")
		(net "LAN1_P2_P")
	)
	(segment
		(start 14.034516 -137.070846)
		(end 12.89685 -135.93318)
		(width 0.127)
		(layer "B.Cu")
		(net "LAN1_P2_P")
	)
	(segment
		(start 7.380732 -185.488834)
		(end 7.380478 -185.488834)
		(width 0.127)
		(layer "B.Cu")
		(net "LAN1_P2_P")
	)
	(segment
		(start 8.720836 -171.897548)
		(end 8.390128 -171.897548)
		(width 0.127)
		(layer "B.Cu")
		(net "LAN1_P2_P")
	)
	(segment
		(start 9.085834 -165.74135)
		(end 8.720836 -166.106348)
		(width 0.127)
		(layer "B.Cu")
		(net "LAN1_P2_P")
	)
	(segment
		(start 8.720836 -166.106348)
		(end 8.390128 -166.106348)
		(width 0.127)
		(layer "B.Cu")
		(net "LAN1_P2_P")
	)
	(segment
		(start 11.001248 -139.44727)
		(end 10.82294 -139.625578)
		(width 0.127)
		(layer "B.Cu")
		(net "LAN1_P2_P")
	)
	(segment
		(start 10.82294 -136.761474)
		(end 10.82294 -137.769346)
		(width 0.127)
		(layer "B.Cu")
		(net "LAN1_P2_P")
	)
	(segment
		(start 8.263128 -167.020748)
		(end 8.390128 -167.147748)
		(width 0.127)
		(layer "B.Cu")
		(net "LAN1_P2_P")
	)
	(segment
		(start 8.390128 -171.897548)
		(end 8.263128 -172.024548)
		(width 0.127)
		(layer "B.Cu")
		(net "LAN1_P2_P")
	)
	(segment
		(start 9.085834 -171.53255)
		(end 8.720836 -171.897548)
		(width 0.127)
		(layer "B.Cu")
		(net "LAN1_P2_P")
	)
	(segment
		(start 11.001248 -138.328654)
		(end 10.82294 -138.506962)
		(width 0.127)
		(layer "B.Cu")
		(net "LAN1_P2_P")
	)
	(segment
		(start 10.82294 -137.769346)
		(end 11.001248 -137.947654)
		(width 0.127)
		(layer "B.Cu")
		(net "LAN1_P2_P")
	)
	(segment
		(start 8.263128 -173.755304)
		(end 9.712198 -175.204374)
		(width 0.127)
		(layer "B.Cu")
		(net "LAN1_P2_P")
	)
	(segment
		(start 7.380478 -185.488834)
		(end 7.323328 -185.375042)
		(width 0.127)
		(layer "B.Cu")
		(net "LAN1_P2_P")
	)
	(segment
		(start 8.263128 -164.125148)
		(end 8.390128 -164.252148)
		(width 0.127)
		(layer "B.Cu")
		(net "LAN1_P2_P")
	)
	(segment
		(start 10.41654 -142.729458)
		(end 7.856728 -145.28927)
		(width 0.127)
		(layer "B.Cu")
		(net "LAN1_P2_N")
	)
	(segment
		(start 8.221726 -168.595548)
		(end 7.856728 -168.960546)
		(width 0.127)
		(layer "B.Cu")
		(net "LAN1_P2_N")
	)
	(segment
		(start 8.552434 -165.699948)
		(end 8.221726 -165.699948)
		(width 0.127)
		(layer "B.Cu")
		(net "LAN1_P2_N")
	)
	(segment
		(start 7.687564 -185.193686)
		(end 7.744206 -185.023252)
		(width 0.127)
		(layer "B.Cu")
		(net "LAN1_P2_N")
	)
	(segment
		(start 11.482832 -135.52678)
		(end 10.41654 -136.593072)
		(width 0.127)
		(layer "B.Cu")
		(net "LAN1_P2_N")
	)
	(segment
		(start 10.41654 -136.593072)
		(end 10.41654 -142.729458)
		(width 0.127)
		(layer "B.Cu")
		(net "LAN1_P2_N")
	)
	(segment
		(start 8.679434 -165.572948)
		(end 8.552434 -165.699948)
		(width 0.127)
		(layer "B.Cu")
		(net "LAN1_P2_N")
	)
	(segment
		(start 8.552434 -171.491148)
		(end 8.221726 -171.491148)
		(width 0.127)
		(layer "B.Cu")
		(net "LAN1_P2_N")
	)
	(segment
		(start 8.221726 -164.658548)
		(end 8.552434 -164.658548)
		(width 0.127)
		(layer "B.Cu")
		(net "LAN1_P2_N")
	)
	(segment
		(start 8.552434 -170.449748)
		(end 8.679434 -170.576748)
		(width 0.127)
		(layer "B.Cu")
		(net "LAN1_P2_N")
	)
	(segment
		(start 16.574516 -134.493)
		(end 13.893546 -134.493)
		(width 0.127)
		(layer "B.Cu")
		(net "LAN1_P2_N")
	)
	(segment
		(start 8.221726 -167.554148)
		(end 8.552434 -167.554148)
		(width 0.127)
		(layer "B.Cu")
		(net "LAN1_P2_N")
	)
	(segment
		(start 7.856728 -164.29355)
		(end 8.221726 -164.658548)
		(width 0.127)
		(layer "B.Cu")
		(net "LAN1_P2_N")
	)
	(segment
		(start 7.856728 -173.923706)
		(end 9.305798 -175.372776)
		(width 0.127)
		(layer "B.Cu")
		(net "LAN1_P2_N")
	)
	(segment
		(start 8.552434 -167.554148)
		(end 8.679434 -167.681148)
		(width 0.127)
		(layer "B.Cu")
		(net "LAN1_P2_N")
	)
	(segment
		(start 7.856728 -171.856146)
		(end 7.856728 -173.923706)
		(width 0.127)
		(layer "B.Cu")
		(net "LAN1_P2_N")
	)
	(segment
		(start 7.744206 -185.023252)
		(end 8.448802 -184.670446)
		(width 0.127)
		(layer "B.Cu")
		(net "LAN1_P2_N")
	)
	(segment
		(start 7.856728 -170.08475)
		(end 8.221726 -170.449748)
		(width 0.127)
		(layer "B.Cu")
		(net "LAN1_P2_N")
	)
	(segment
		(start 7.744206 -185.30697)
		(end 7.687564 -185.193686)
		(width 0.127)
		(layer "B.Cu")
		(net "LAN1_P2_N")
	)
	(segment
		(start 9.305798 -185.19394)
		(end 9.017254 -185.482484)
		(width 0.127)
		(layer "B.Cu")
		(net "LAN1_P2_N")
	)
	(segment
		(start 8.221726 -165.699948)
		(end 7.856728 -166.064946)
		(width 0.127)
		(layer "B.Cu")
		(net "LAN1_P2_N")
	)
	(segment
		(start 12.859766 -135.52678)
		(end 11.482832 -135.52678)
		(width 0.127)
		(layer "B.Cu")
		(net "LAN1_P2_N")
	)
	(segment
		(start 9.305798 -175.372776)
		(end 9.305798 -185.19394)
		(width 0.127)
		(layer "B.Cu")
		(net "LAN1_P2_N")
	)
	(segment
		(start 8.679434 -168.468548)
		(end 8.552434 -168.595548)
		(width 0.127)
		(layer "B.Cu")
		(net "LAN1_P2_N")
	)
	(segment
		(start 8.221726 -171.491148)
		(end 7.856728 -171.856146)
		(width 0.127)
		(layer "B.Cu")
		(net "LAN1_P2_N")
	)
	(segment
		(start 8.679434 -171.364148)
		(end 8.552434 -171.491148)
		(width 0.127)
		(layer "B.Cu")
		(net "LAN1_P2_N")
	)
	(segment
		(start 9.017254 -185.482484)
		(end 7.91972 -185.482484)
		(width 0.127)
		(layer "B.Cu")
		(net "LAN1_P2_N")
	)
	(segment
		(start 7.856728 -166.064946)
		(end 7.856728 -167.18915)
		(width 0.127)
		(layer "B.Cu")
		(net "LAN1_P2_N")
	)
	(segment
		(start 8.679434 -167.681148)
		(end 8.679434 -168.468548)
		(width 0.127)
		(layer "B.Cu")
		(net "LAN1_P2_N")
	)
	(segment
		(start 8.679434 -164.785548)
		(end 8.679434 -165.572948)
		(width 0.127)
		(layer "B.Cu")
		(net "LAN1_P2_N")
	)
	(segment
		(start 8.221726 -170.449748)
		(end 8.552434 -170.449748)
		(width 0.127)
		(layer "B.Cu")
		(net "LAN1_P2_N")
	)
	(segment
		(start 7.91972 -185.482484)
		(end 7.744206 -185.30697)
		(width 0.127)
		(layer "B.Cu")
		(net "LAN1_P2_N")
	)
	(segment
		(start 13.893546 -134.493)
		(end 12.859766 -135.52678)
		(width 0.127)
		(layer "B.Cu")
		(net "LAN1_P2_N")
	)
	(segment
		(start 8.679434 -170.576748)
		(end 8.679434 -171.364148)
		(width 0.127)
		(layer "B.Cu")
		(net "LAN1_P2_N")
	)
	(segment
		(start 8.552434 -164.658548)
		(end 8.679434 -164.785548)
		(width 0.127)
		(layer "B.Cu")
		(net "LAN1_P2_N")
	)
	(segment
		(start 8.552434 -168.595548)
		(end 8.221726 -168.595548)
		(width 0.127)
		(layer "B.Cu")
		(net "LAN1_P2_N")
	)
	(segment
		(start 7.856728 -167.18915)
		(end 8.221726 -167.554148)
		(width 0.127)
		(layer "B.Cu")
		(net "LAN1_P2_N")
	)
	(segment
		(start 7.856728 -168.960546)
		(end 7.856728 -170.08475)
		(width 0.127)
		(layer "B.Cu")
		(net "LAN1_P2_N")
	)
	(segment
		(start 7.856728 -145.28927)
		(end 7.856728 -164.29355)
		(width 0.127)
		(layer "B.Cu")
		(net "LAN1_P2_N")
	)
	(segment
		(start 23.70455 -132.084826)
		(end 18.767552 -127.147828)
		(width 0.127)
		(layer "In5.Cu")
		(net "UART_DSR_P2_L_N")
	)
	(segment
		(start 13.692632 -173.44644)
		(end 23.70455 -163.434522)
		(width 0.127)
		(layer "In5.Cu")
		(net "UART_DSR_P2_L_N")
	)
	(segment
		(start 13.029184 -53.896768)
		(end 13.029184 -51.77536)
		(width 0.127)
		(layer "In5.Cu")
		(net "UART_DSR_P2_L_N")
	)
	(segment
		(start 18.751042 -59.543188)
		(end 18.675604 -59.543188)
		(width 0.127)
		(layer "In5.Cu")
		(net "UART_DSR_P2_L_N")
	)
	(segment
		(start 8.486394 -199.67067)
		(end 13.692632 -194.464432)
		(width 0.127)
		(layer "In5.Cu")
		(net "UART_DSR_P2_L_N")
	)
	(segment
		(start 13.029184 -51.77536)
		(end 13.623544 -51.181)
		(width 0.127)
		(layer "In5.Cu")
		(net "UART_DSR_P2_L_N")
	)
	(segment
		(start 17.314926 -127.147828)
		(end 10.571226 -120.404128)
		(width 0.127)
		(layer "In5.Cu")
		(net "UART_DSR_P2_L_N")
	)
	(segment
		(start 18.675604 -59.543188)
		(end 13.029184 -53.896768)
		(width 0.127)
		(layer "In5.Cu")
		(net "UART_DSR_P2_L_N")
	)
	(segment
		(start 11.93419 -94.996)
		(end 19.711162 -87.219028)
		(width 0.127)
		(layer "In5.Cu")
		(net "UART_DSR_P2_L_N")
	)
	(segment
		(start 18.767552 -127.147828)
		(end 17.314926 -127.147828)
		(width 0.127)
		(layer "In5.Cu")
		(net "UART_DSR_P2_L_N")
	)
	(segment
		(start 11.93419 -114.169952)
		(end 11.93419 -94.996)
		(width 0.127)
		(layer "In5.Cu")
		(net "UART_DSR_P2_L_N")
	)
	(segment
		(start 23.70455 -163.434522)
		(end 23.70455 -132.084826)
		(width 0.127)
		(layer "In5.Cu")
		(net "UART_DSR_P2_L_N")
	)
	(segment
		(start 6.448806 -199.67067)
		(end 8.486394 -199.67067)
		(width 0.127)
		(layer "In5.Cu")
		(net "UART_DSR_P2_L_N")
	)
	(segment
		(start 13.692632 -194.464432)
		(end 13.692632 -173.44644)
		(width 0.127)
		(layer "In5.Cu")
		(net "UART_DSR_P2_L_N")
	)
	(segment
		(start 10.571226 -115.532916)
		(end 11.93419 -114.169952)
		(width 0.127)
		(layer "In5.Cu")
		(net "UART_DSR_P2_L_N")
	)
	(segment
		(start 13.623544 -51.181)
		(end 16.504666 -51.181)
		(width 0.127)
		(layer "In5.Cu")
		(net "UART_DSR_P2_L_N")
	)
	(segment
		(start 19.711162 -60.503308)
		(end 18.751042 -59.543188)
		(width 0.127)
		(layer "In5.Cu")
		(net "UART_DSR_P2_L_N")
	)
	(segment
		(start 19.711162 -87.219028)
		(end 19.711162 -60.503308)
		(width 0.127)
		(layer "In5.Cu")
		(net "UART_DSR_P2_L_N")
	)
	(segment
		(start 10.571226 -120.404128)
		(end 10.571226 -115.532916)
		(width 0.127)
		(layer "In5.Cu")
		(net "UART_DSR_P2_L_N")
	)
	(segment
		(start 13.964666 -44.831)
		(end 12.74064 -46.055026)
		(width 0.127)
		(layer "In5.Cu")
		(net "UART_DTR_P2_L_N")
	)
	(segment
		(start 9.580626 -115.014756)
		(end 9.580626 -120.814846)
		(width 0.127)
		(layer "In5.Cu")
		(net "UART_DTR_P2_L_N")
	)
	(segment
		(start 18.644362 -60.945268)
		(end 18.644362 -86.777068)
		(width 0.127)
		(layer "In5.Cu")
		(net "UART_DTR_P2_L_N")
	)
	(segment
		(start 18.233644 -60.609988)
		(end 18.309082 -60.609988)
		(width 0.127)
		(layer "In5.Cu")
		(net "UART_DTR_P2_L_N")
	)
	(segment
		(start 10.86739 -94.55404)
		(end 10.86739 -113.727992)
		(width 0.127)
		(layer "In5.Cu")
		(net "UART_DTR_P2_L_N")
	)
	(segment
		(start 11.97356 -54.349904)
		(end 18.233644 -60.609988)
		(width 0.127)
		(layer "In5.Cu")
		(net "UART_DTR_P2_L_N")
	)
	(segment
		(start 18.309082 -60.609988)
		(end 18.644362 -60.945268)
		(width 0.127)
		(layer "In5.Cu")
		(net "UART_DTR_P2_L_N")
	)
	(segment
		(start 18.114518 -128.138428)
		(end 22.63775 -132.66166)
		(width 0.127)
		(layer "In5.Cu")
		(net "UART_DTR_P2_L_N")
	)
	(segment
		(start 12.625832 -169.88917)
		(end 12.625832 -192.493392)
		(width 0.127)
		(layer "In5.Cu")
		(net "UART_DTR_P2_L_N")
	)
	(segment
		(start 12.74064 -48.42129)
		(end 11.97356 -49.18837)
		(width 0.127)
		(layer "In5.Cu")
		(net "UART_DTR_P2_L_N")
	)
	(segment
		(start 12.625832 -192.493392)
		(end 8.448802 -196.670422)
		(width 0.127)
		(layer "In5.Cu")
		(net "UART_DTR_P2_L_N")
	)
	(segment
		(start 22.63775 -159.877252)
		(end 12.625832 -169.88917)
		(width 0.127)
		(layer "In5.Cu")
		(net "UART_DTR_P2_L_N")
	)
	(segment
		(start 9.580626 -120.814846)
		(end 16.904208 -128.138428)
		(width 0.127)
		(layer "In5.Cu")
		(net "UART_DTR_P2_L_N")
	)
	(segment
		(start 10.86739 -113.727992)
		(end 9.580626 -115.014756)
		(width 0.127)
		(layer "In5.Cu")
		(net "UART_DTR_P2_L_N")
	)
	(segment
		(start 16.904208 -128.138428)
		(end 18.114518 -128.138428)
		(width 0.127)
		(layer "In5.Cu")
		(net "UART_DTR_P2_L_N")
	)
	(segment
		(start 18.644362 -86.777068)
		(end 10.86739 -94.55404)
		(width 0.127)
		(layer "In5.Cu")
		(net "UART_DTR_P2_L_N")
	)
	(segment
		(start 22.63775 -132.66166)
		(end 22.63775 -159.877252)
		(width 0.127)
		(layer "In5.Cu")
		(net "UART_DTR_P2_L_N")
	)
	(segment
		(start 12.74064 -46.055026)
		(end 12.74064 -48.42129)
		(width 0.127)
		(layer "In5.Cu")
		(net "UART_DTR_P2_L_N")
	)
	(segment
		(start 11.97356 -49.18837)
		(end 11.97356 -54.349904)
		(width 0.127)
		(layer "In5.Cu")
		(net "UART_DTR_P2_L_N")
	)
	(segment
		(start 11.22299 -113.875312)
		(end 11.22299 -94.70136)
		(width 0.127)
		(layer "In5.Cu")
		(net "UART_TX_P2_L")
	)
	(segment
		(start 11.22299 -94.70136)
		(end 18.999962 -86.924388)
		(width 0.127)
		(layer "In5.Cu")
		(net "UART_TX_P2_L")
	)
	(segment
		(start 9.910826 -120.67794)
		(end 9.910826 -115.187476)
		(width 0.127)
		(layer "In5.Cu")
		(net "UART_TX_P2_L")
	)
	(segment
		(start 22.99335 -132.409692)
		(end 18.391886 -127.808228)
		(width 0.127)
		(layer "In5.Cu")
		(net "UART_TX_P2_L")
	)
	(segment
		(start 12.9921 -48.67275)
		(end 14.236192 -48.67275)
		(width 0.127)
		(layer "In5.Cu")
		(net "UART_TX_P2_L")
	)
	(segment
		(start 9.910826 -115.187476)
		(end 11.22299 -113.875312)
		(width 0.127)
		(layer "In5.Cu")
		(net "UART_TX_P2_L")
	)
	(segment
		(start 18.391886 -127.808228)
		(end 17.041114 -127.808228)
		(width 0.127)
		(layer "In5.Cu")
		(net "UART_TX_P2_L")
	)
	(segment
		(start 18.380964 -60.254388)
		(end 12.32916 -54.202584)
		(width 0.127)
		(layer "In5.Cu")
		(net "UART_TX_P2_L")
	)
	(segment
		(start 6.448806 -197.670674)
		(end 8.915654 -197.670674)
		(width 0.127)
		(layer "In5.Cu")
		(net "UART_TX_P2_L")
	)
	(segment
		(start 12.981432 -193.604896)
		(end 12.981432 -170.00093)
		(width 0.127)
		(layer "In5.Cu")
		(net "UART_TX_P2_L")
	)
	(segment
		(start 8.915654 -197.670674)
		(end 12.981432 -193.604896)
		(width 0.127)
		(layer "In5.Cu")
		(net "UART_TX_P2_L")
	)
	(segment
		(start 16.504666 -46.404276)
		(end 16.504666 -46.101)
		(width 0.127)
		(layer "In5.Cu")
		(net "UART_TX_P2_L")
	)
	(segment
		(start 18.456402 -60.254388)
		(end 18.380964 -60.254388)
		(width 0.127)
		(layer "In5.Cu")
		(net "UART_TX_P2_L")
	)
	(segment
		(start 18.999962 -86.924388)
		(end 18.999962 -60.797948)
		(width 0.127)
		(layer "In5.Cu")
		(net "UART_TX_P2_L")
	)
	(segment
		(start 14.236192 -48.67275)
		(end 16.504666 -46.404276)
		(width 0.127)
		(layer "In5.Cu")
		(net "UART_TX_P2_L")
	)
	(segment
		(start 12.981432 -170.00093)
		(end 22.99335 -159.989012)
		(width 0.127)
		(layer "In5.Cu")
		(net "UART_TX_P2_L")
	)
	(segment
		(start 22.99335 -159.989012)
		(end 22.99335 -132.409692)
		(width 0.127)
		(layer "In5.Cu")
		(net "UART_TX_P2_L")
	)
	(segment
		(start 17.041114 -127.808228)
		(end 9.910826 -120.67794)
		(width 0.127)
		(layer "In5.Cu")
		(net "UART_TX_P2_L")
	)
	(segment
		(start 18.999962 -60.797948)
		(end 18.456402 -60.254388)
		(width 0.127)
		(layer "In5.Cu")
		(net "UART_TX_P2_L")
	)
	(segment
		(start 12.32916 -49.33569)
		(end 12.9921 -48.67275)
		(width 0.127)
		(layer "In5.Cu")
		(net "UART_TX_P2_L")
	)
	(segment
		(start 12.32916 -54.202584)
		(end 12.32916 -49.33569)
		(width 0.127)
		(layer "In5.Cu")
		(net "UART_TX_P2_L")
	)
	(segment
		(start 10.901426 -115.705636)
		(end 10.901426 -120.267222)
		(width 0.127)
		(layer "In5.Cu")
		(net "UART_RTS_P2_L_N")
	)
	(segment
		(start 18.898362 -59.187588)
		(end 20.066762 -60.355988)
		(width 0.127)
		(layer "In5.Cu")
		(net "UART_RTS_P2_L_N")
	)
	(segment
		(start 13.87348 -54.238144)
		(end 18.822924 -59.187588)
		(width 0.127)
		(layer "In5.Cu")
		(net "UART_RTS_P2_L_N")
	)
	(segment
		(start 24.06015 -163.581842)
		(end 14.048232 -173.59376)
		(width 0.127)
		(layer "In5.Cu")
		(net "UART_RTS_P2_L_N")
	)
	(segment
		(start 12.28979 -114.317272)
		(end 10.901426 -115.705636)
		(width 0.127)
		(layer "In5.Cu")
		(net "UART_RTS_P2_L_N")
	)
	(segment
		(start 17.451832 -126.817628)
		(end 19.00936 -126.817628)
		(width 0.127)
		(layer "In5.Cu")
		(net "UART_RTS_P2_L_N")
	)
	(segment
		(start 20.066762 -87.366348)
		(end 12.28979 -95.14332)
		(width 0.127)
		(layer "In5.Cu")
		(net "UART_RTS_P2_L_N")
	)
	(segment
		(start 18.822924 -59.187588)
		(end 18.898362 -59.187588)
		(width 0.127)
		(layer "In5.Cu")
		(net "UART_RTS_P2_L_N")
	)
	(segment
		(start 14.048232 -195.070984)
		(end 8.448802 -200.670414)
		(width 0.127)
		(layer "In5.Cu")
		(net "UART_RTS_P2_L_N")
	)
	(segment
		(start 13.964666 -52.451)
		(end 13.87348 -52.542186)
		(width 0.127)
		(layer "In5.Cu")
		(net "UART_RTS_P2_L_N")
	)
	(segment
		(start 10.901426 -120.267222)
		(end 17.451832 -126.817628)
		(width 0.127)
		(layer "In5.Cu")
		(net "UART_RTS_P2_L_N")
	)
	(segment
		(start 14.048232 -173.59376)
		(end 14.048232 -195.070984)
		(width 0.127)
		(layer "In5.Cu")
		(net "UART_RTS_P2_L_N")
	)
	(segment
		(start 20.066762 -60.355988)
		(end 20.066762 -87.366348)
		(width 0.127)
		(layer "In5.Cu")
		(net "UART_RTS_P2_L_N")
	)
	(segment
		(start 24.06015 -131.868418)
		(end 24.06015 -163.581842)
		(width 0.127)
		(layer "In5.Cu")
		(net "UART_RTS_P2_L_N")
	)
	(segment
		(start 13.87348 -52.542186)
		(end 13.87348 -54.238144)
		(width 0.127)
		(layer "In5.Cu")
		(net "UART_RTS_P2_L_N")
	)
	(segment
		(start 12.28979 -95.14332)
		(end 12.28979 -114.317272)
		(width 0.127)
		(layer "In5.Cu")
		(net "UART_RTS_P2_L_N")
	)
	(segment
		(start 19.00936 -126.817628)
		(end 24.06015 -131.868418)
		(width 0.127)
		(layer "In5.Cu")
		(net "UART_RTS_P2_L_N")
	)
	(segment
		(start 6.448806 -195.670678)
		(end 8.860536 -195.670678)
		(width 0.127)
		(layer "In5.Cu")
		(net "UART_CTS_P2_L_N")
	)
	(segment
		(start 22.28215 -159.765746)
		(end 22.28215 -132.80898)
		(width 0.127)
		(layer "In5.Cu")
		(net "UART_CTS_P2_L_N")
	)
	(segment
		(start 18.161762 -60.965588)
		(end 18.086324 -60.965588)
		(width 0.127)
		(layer "In5.Cu")
		(net "UART_CTS_P2_L_N")
	)
	(segment
		(start 22.28215 -132.80898)
		(end 17.941798 -128.468628)
		(width 0.127)
		(layer "In5.Cu")
		(net "UART_CTS_P2_L_N")
	)
	(segment
		(start 18.288762 -61.092588)
		(end 18.161762 -60.965588)
		(width 0.127)
		(layer "In5.Cu")
		(net "UART_CTS_P2_L_N")
	)
	(segment
		(start 13.531088 -43.561)
		(end 16.504666 -43.561)
		(width 0.127)
		(layer "In5.Cu")
		(net "UART_CTS_P2_L_N")
	)
	(segment
		(start 17.941798 -128.468628)
		(end 16.767302 -128.468628)
		(width 0.127)
		(layer "In5.Cu")
		(net "UART_CTS_P2_L_N")
	)
	(segment
		(start 12.376404 -48.282606)
		(end 12.376404 -44.715684)
		(width 0.127)
		(layer "In5.Cu")
		(net "UART_CTS_P2_L_N")
	)
	(segment
		(start 11.61796 -54.497224)
		(end 11.61796 -49.04105)
		(width 0.127)
		(layer "In5.Cu")
		(net "UART_CTS_P2_L_N")
	)
	(segment
		(start 10.51179 -113.580672)
		(end 10.51179 -94.40672)
		(width 0.127)
		(layer "In5.Cu")
		(net "UART_CTS_P2_L_N")
	)
	(segment
		(start 9.250426 -120.951752)
		(end 9.250426 -114.842036)
		(width 0.127)
		(layer "In5.Cu")
		(net "UART_CTS_P2_L_N")
	)
	(segment
		(start 9.250426 -114.842036)
		(end 10.51179 -113.580672)
		(width 0.127)
		(layer "In5.Cu")
		(net "UART_CTS_P2_L_N")
	)
	(segment
		(start 18.086324 -60.965588)
		(end 11.61796 -54.497224)
		(width 0.127)
		(layer "In5.Cu")
		(net "UART_CTS_P2_L_N")
	)
	(segment
		(start 10.51179 -94.40672)
		(end 18.288762 -86.629748)
		(width 0.127)
		(layer "In5.Cu")
		(net "UART_CTS_P2_L_N")
	)
	(segment
		(start 18.288762 -86.629748)
		(end 18.288762 -61.092588)
		(width 0.127)
		(layer "In5.Cu")
		(net "UART_CTS_P2_L_N")
	)
	(segment
		(start 12.376404 -44.715684)
		(end 13.531088 -43.561)
		(width 0.127)
		(layer "In5.Cu")
		(net "UART_CTS_P2_L_N")
	)
	(segment
		(start 11.61796 -49.04105)
		(end 12.376404 -48.282606)
		(width 0.127)
		(layer "In5.Cu")
		(net "UART_CTS_P2_L_N")
	)
	(segment
		(start 12.295632 -192.235582)
		(end 12.295632 -169.752264)
		(width 0.127)
		(layer "In5.Cu")
		(net "UART_CTS_P2_L_N")
	)
	(segment
		(start 16.767302 -128.468628)
		(end 9.250426 -120.951752)
		(width 0.127)
		(layer "In5.Cu")
		(net "UART_CTS_P2_L_N")
	)
	(segment
		(start 12.295632 -169.752264)
		(end 22.28215 -159.765746)
		(width 0.127)
		(layer "In5.Cu")
		(net "UART_CTS_P2_L_N")
	)
	(segment
		(start 8.860536 -195.670678)
		(end 12.295632 -192.235582)
		(width 0.127)
		(layer "In5.Cu")
		(net "UART_CTS_P2_L_N")
	)
	(segment
		(start 11.57859 -114.022632)
		(end 11.57859 -94.84868)
		(width 0.127)
		(layer "In5.Cu")
		(net "UART_RX_P2_L")
	)
	(segment
		(start 18.603722 -59.898788)
		(end 18.528284 -59.898788)
		(width 0.127)
		(layer "In5.Cu")
		(net "UART_RX_P2_L")
	)
	(segment
		(start 18.528284 -59.898788)
		(end 12.676124 -54.046628)
		(width 0.127)
		(layer "In5.Cu")
		(net "UART_RX_P2_L")
	)
	(segment
		(start 17.17802 -127.478028)
		(end 10.241026 -120.541034)
		(width 0.127)
		(layer "In5.Cu")
		(net "UART_RX_P2_L")
	)
	(segment
		(start 12.676124 -51.199542)
		(end 13.964666 -49.911)
		(width 0.127)
		(layer "In5.Cu")
		(net "UART_RX_P2_L")
	)
	(segment
		(start 23.34895 -160.100518)
		(end 23.34895 -132.196332)
		(width 0.127)
		(layer "In5.Cu")
		(net "UART_RX_P2_L")
	)
	(segment
		(start 13.337032 -170.112436)
		(end 23.34895 -160.100518)
		(width 0.127)
		(layer "In5.Cu")
		(net "UART_RX_P2_L")
	)
	(segment
		(start 10.241026 -115.360196)
		(end 11.57859 -114.022632)
		(width 0.127)
		(layer "In5.Cu")
		(net "UART_RX_P2_L")
	)
	(segment
		(start 18.630646 -127.478028)
		(end 17.17802 -127.478028)
		(width 0.127)
		(layer "In5.Cu")
		(net "UART_RX_P2_L")
	)
	(segment
		(start 23.34895 -132.196332)
		(end 18.630646 -127.478028)
		(width 0.127)
		(layer "In5.Cu")
		(net "UART_RX_P2_L")
	)
	(segment
		(start 12.676124 -54.046628)
		(end 12.676124 -51.199542)
		(width 0.127)
		(layer "In5.Cu")
		(net "UART_RX_P2_L")
	)
	(segment
		(start 10.241026 -120.541034)
		(end 10.241026 -115.360196)
		(width 0.127)
		(layer "In5.Cu")
		(net "UART_RX_P2_L")
	)
	(segment
		(start 13.337032 -193.782188)
		(end 13.337032 -170.112436)
		(width 0.127)
		(layer "In5.Cu")
		(net "UART_RX_P2_L")
	)
	(segment
		(start 19.355562 -87.071708)
		(end 19.355562 -60.650628)
		(width 0.127)
		(layer "In5.Cu")
		(net "UART_RX_P2_L")
	)
	(segment
		(start 19.355562 -60.650628)
		(end 18.603722 -59.898788)
		(width 0.127)
		(layer "In5.Cu")
		(net "UART_RX_P2_L")
	)
	(segment
		(start 8.448802 -198.670418)
		(end 13.337032 -193.782188)
		(width 0.127)
		(layer "In5.Cu")
		(net "UART_RX_P2_L")
	)
	(segment
		(start 11.57859 -94.84868)
		(end 19.355562 -87.071708)
		(width 0.127)
		(layer "In5.Cu")
		(net "UART_RX_P2_L")
	)
	(segment
		(start 7.716012 -203.93787)
		(end 8.448802 -204.67066)
		(width 0.1524)
		(layer "B.Cu")
		(net "UART_DTR_P6_L_N")
	)
	(segment
		(start 7.073646 -114.434112)
		(end 7.073646 -120.384316)
		(width 0.1524)
		(layer "B.Cu")
		(net "UART_DTR_P6_L_N")
	)
	(segment
		(start 17.810988 -142.259304)
		(end 17.810988 -193.932556)
		(width 0.1524)
		(layer "B.Cu")
		(net "UART_DTR_P6_L_N")
	)
	(segment
		(start 11.392154 -110.115604)
		(end 7.073646 -114.434112)
		(width 0.1524)
		(layer "B.Cu")
		(net "UART_DTR_P6_L_N")
	)
	(segment
		(start 13.964666 -97.917)
		(end 11.392154 -100.489512)
		(width 0.1524)
		(layer "B.Cu")
		(net "UART_DTR_P6_L_N")
	)
	(segment
		(start 7.716012 -202.30338)
		(end 7.716012 -203.93787)
		(width 0.1524)
		(layer "B.Cu")
		(net "UART_DTR_P6_L_N")
	)
	(segment
		(start 8.117332 -201.90206)
		(end 7.716012 -202.30338)
		(width 0.1524)
		(layer "B.Cu")
		(net "UART_DTR_P6_L_N")
	)
	(segment
		(start 19.629628 -140.440664)
		(end 17.810988 -142.259304)
		(width 0.1524)
		(layer "B.Cu")
		(net "UART_DTR_P6_L_N")
	)
	(segment
		(start 9.841484 -201.90206)
		(end 8.117332 -201.90206)
		(width 0.1524)
		(layer "B.Cu")
		(net "UART_DTR_P6_L_N")
	)
	(segment
		(start 11.392154 -100.489512)
		(end 11.392154 -110.115604)
		(width 0.1524)
		(layer "B.Cu")
		(net "UART_DTR_P6_L_N")
	)
	(segment
		(start 19.629628 -132.940298)
		(end 19.629628 -140.440664)
		(width 0.1524)
		(layer "B.Cu")
		(net "UART_DTR_P6_L_N")
	)
	(segment
		(start 7.073646 -120.384316)
		(end 19.629628 -132.940298)
		(width 0.1524)
		(layer "B.Cu")
		(net "UART_DTR_P6_L_N")
	)
	(segment
		(start 17.810988 -193.932556)
		(end 9.841484 -201.90206)
		(width 0.1524)
		(layer "B.Cu")
		(net "UART_DTR_P6_L_N")
	)
	(segment
		(start 13.063982 -101.935534)
		(end 14.364462 -101.935534)
		(width 0.1524)
		(layer "B.Cu")
		(net "UART_TX_P6_L")
	)
	(segment
		(start 16.504666 -99.79533)
		(end 16.504666 -99.187)
		(width 0.1524)
		(layer "B.Cu")
		(net "UART_TX_P6_L")
	)
	(segment
		(start 13.01115 -109.796834)
		(end 13.01115 -108.16209)
		(width 0.1524)
		(layer "B.Cu")
		(net "UART_TX_P6_L")
	)
	(segment
		(start 6.448806 -205.670658)
		(end 8.659368 -205.670658)
		(width 0.1524)
		(layer "B.Cu")
		(net "UART_TX_P6_L")
	)
	(segment
		(start 12.153646 -102.84587)
		(end 13.063982 -101.935534)
		(width 0.1524)
		(layer "B.Cu")
		(net "UART_TX_P6_L")
	)
	(segment
		(start 12.153646 -107.304586)
		(end 12.153646 -102.84587)
		(width 0.1524)
		(layer "B.Cu")
		(net "UART_TX_P6_L")
	)
	(segment
		(start 18.522188 -194.227196)
		(end 18.522188 -142.553944)
		(width 0.1524)
		(layer "B.Cu")
		(net "UART_TX_P6_L")
	)
	(segment
		(start 18.522188 -142.553944)
		(end 20.340828 -140.735304)
		(width 0.1524)
		(layer "B.Cu")
		(net "UART_TX_P6_L")
	)
	(segment
		(start 8.659368 -205.670658)
		(end 9.204452 -205.125574)
		(width 0.1524)
		(layer "B.Cu")
		(net "UART_TX_P6_L")
	)
	(segment
		(start 20.340828 -140.735304)
		(end 20.340828 -132.645658)
		(width 0.1524)
		(layer "B.Cu")
		(net "UART_TX_P6_L")
	)
	(segment
		(start 7.784846 -120.089676)
		(end 7.784846 -115.023138)
		(width 0.1524)
		(layer "B.Cu")
		(net "UART_TX_P6_L")
	)
	(segment
		(start 13.01115 -108.16209)
		(end 12.153646 -107.304586)
		(width 0.1524)
		(layer "B.Cu")
		(net "UART_TX_P6_L")
	)
	(segment
		(start 20.340828 -132.645658)
		(end 7.784846 -120.089676)
		(width 0.1524)
		(layer "B.Cu")
		(net "UART_TX_P6_L")
	)
	(segment
		(start 14.364462 -101.935534)
		(end 16.504666 -99.79533)
		(width 0.1524)
		(layer "B.Cu")
		(net "UART_TX_P6_L")
	)
	(segment
		(start 7.784846 -115.023138)
		(end 13.01115 -109.796834)
		(width 0.1524)
		(layer "B.Cu")
		(net "UART_TX_P6_L")
	)
	(segment
		(start 9.204452 -203.544932)
		(end 18.522188 -194.227196)
		(width 0.1524)
		(layer "B.Cu")
		(net "UART_TX_P6_L")
	)
	(segment
		(start 9.204452 -205.125574)
		(end 9.204452 -203.544932)
		(width 0.1524)
		(layer "B.Cu")
		(net "UART_TX_P6_L")
	)
	(segment
		(start 21.052028 -141.029944)
		(end 19.233388 -142.848584)
		(width 0.1524)
		(layer "B.Cu")
		(net "UART_RTS_P6_L_N")
	)
	(segment
		(start 9.246108 -206.426816)
		(end 9.246108 -207.873346)
		(width 0.1524)
		(layer "B.Cu")
		(net "UART_RTS_P6_L_N")
	)
	(segment
		(start 19.233388 -194.521836)
		(end 9.915652 -203.839572)
		(width 0.1524)
		(layer "B.Cu")
		(net "UART_RTS_P6_L_N")
	)
	(segment
		(start 21.052028 -132.351018)
		(end 21.052028 -141.029944)
		(width 0.1524)
		(layer "B.Cu")
		(net "UART_RTS_P6_L_N")
	)
	(segment
		(start 14.837156 -106.40949)
		(end 14.837156 -109.152944)
		(width 0.1524)
		(layer "B.Cu")
		(net "UART_RTS_P6_L_N")
	)
	(segment
		(start 13.964666 -105.537)
		(end 14.837156 -106.40949)
		(width 0.1524)
		(layer "B.Cu")
		(net "UART_RTS_P6_L_N")
	)
	(segment
		(start 8.496046 -119.795036)
		(end 21.052028 -132.351018)
		(width 0.1524)
		(layer "B.Cu")
		(net "UART_RTS_P6_L_N")
	)
	(segment
		(start 9.246108 -207.873346)
		(end 8.448802 -208.670652)
		(width 0.1524)
		(layer "B.Cu")
		(net "UART_RTS_P6_L_N")
	)
	(segment
		(start 19.233388 -142.848584)
		(end 19.233388 -194.521836)
		(width 0.1524)
		(layer "B.Cu")
		(net "UART_RTS_P6_L_N")
	)
	(segment
		(start 9.915652 -205.757272)
		(end 9.246108 -206.426816)
		(width 0.1524)
		(layer "B.Cu")
		(net "UART_RTS_P6_L_N")
	)
	(segment
		(start 9.915652 -203.839572)
		(end 9.915652 -205.757272)
		(width 0.1524)
		(layer "B.Cu")
		(net "UART_RTS_P6_L_N")
	)
	(segment
		(start 8.496046 -115.494054)
		(end 8.496046 -119.795036)
		(width 0.1524)
		(layer "B.Cu")
		(net "UART_RTS_P6_L_N")
	)
	(segment
		(start 14.837156 -109.152944)
		(end 8.496046 -115.494054)
		(width 0.1524)
		(layer "B.Cu")
		(net "UART_RTS_P6_L_N")
	)
	(segment
		(start 13.389356 -108.005372)
		(end 13.389356 -109.953552)
		(width 0.1524)
		(layer "B.Cu")
		(net "UART_RX_P6_L")
	)
	(segment
		(start 9.129522 -205.989936)
		(end 8.448802 -206.670656)
		(width 0.1524)
		(layer "B.Cu")
		(net "UART_RX_P6_L")
	)
	(segment
		(start 18.877788 -142.701264)
		(end 18.877788 -194.374516)
		(width 0.1524)
		(layer "B.Cu")
		(net "UART_RX_P6_L")
	)
	(segment
		(start 9.560052 -205.54823)
		(end 9.129522 -205.97876)
		(width 0.1524)
		(layer "B.Cu")
		(net "UART_RX_P6_L")
	)
	(segment
		(start 9.560052 -203.692252)
		(end 9.560052 -205.54823)
		(width 0.1524)
		(layer "B.Cu")
		(net "UART_RX_P6_L")
	)
	(segment
		(start 18.877788 -194.374516)
		(end 9.560052 -203.692252)
		(width 0.1524)
		(layer "B.Cu")
		(net "UART_RX_P6_L")
	)
	(segment
		(start 13.964666 -102.997)
		(end 13.362178 -102.997)
		(width 0.1524)
		(layer "B.Cu")
		(net "UART_RX_P6_L")
	)
	(segment
		(start 8.140446 -119.942356)
		(end 20.696428 -132.498338)
		(width 0.1524)
		(layer "B.Cu")
		(net "UART_RX_P6_L")
	)
	(segment
		(start 20.696428 -140.882624)
		(end 18.877788 -142.701264)
		(width 0.1524)
		(layer "B.Cu")
		(net "UART_RX_P6_L")
	)
	(segment
		(start 20.696428 -132.498338)
		(end 20.696428 -140.882624)
		(width 0.1524)
		(layer "B.Cu")
		(net "UART_RX_P6_L")
	)
	(segment
		(start 12.531852 -103.827326)
		(end 12.531852 -107.147868)
		(width 0.1524)
		(layer "B.Cu")
		(net "UART_RX_P6_L")
	)
	(segment
		(start 12.531852 -107.147868)
		(end 13.389356 -108.005372)
		(width 0.1524)
		(layer "B.Cu")
		(net "UART_RX_P6_L")
	)
	(segment
		(start 9.129522 -205.97876)
		(end 9.129522 -205.989936)
		(width 0.1524)
		(layer "B.Cu")
		(net "UART_RX_P6_L")
	)
	(segment
		(start 13.389356 -109.953552)
		(end 8.140446 -115.202462)
		(width 0.1524)
		(layer "B.Cu")
		(net "UART_RX_P6_L")
	)
	(segment
		(start 8.140446 -115.202462)
		(end 8.140446 -119.942356)
		(width 0.1524)
		(layer "B.Cu")
		(net "UART_RX_P6_L")
	)
	(segment
		(start 13.362178 -102.997)
		(end 12.531852 -103.827326)
		(width 0.1524)
		(layer "B.Cu")
		(net "UART_RX_P6_L")
	)
	(segment
		(start 2.815082 -195.991988)
		(end 3.03911 -196.216016)
		(width 0.127)
		(layer "In5.Cu")
		(net "UART_RI_P5_L_N")
	)
	(segment
		(start 10.588244 -67.478402)
		(end 10.588244 -73.158858)
		(width 0.127)
		(layer "In5.Cu")
		(net "UART_RI_P5_L_N")
	)
	(segment
		(start 16.831564 -130.449828)
		(end 19.549364 -133.167628)
		(width 0.127)
		(layer "In5.Cu")
		(net "UART_RI_P5_L_N")
	)
	(segment
		(start 3.7846 -93.698314)
		(end 3.7846 -112.312196)
		(width 0.127)
		(layer "In5.Cu")
		(net "UART_RI_P5_L_N")
	)
	(segment
		(start 3.01117 -198.188072)
		(end 3.01117 -199.153272)
		(width 0.127)
		(layer "In5.Cu")
		(net "UART_RI_P5_L_N")
	)
	(segment
		(start 9.366504 -90.08364)
		(end 8.021828 -91.428316)
		(width 0.127)
		(layer "In5.Cu")
		(net "UART_RI_P5_L_N")
	)
	(segment
		(start 6.210046 -190.397384)
		(end 4.20116 -192.40627)
		(width 0.127)
		(layer "In5.Cu")
		(net "UART_RI_P5_L_N")
	)
	(segment
		(start 3.03911 -197.125336)
		(end 2.828798 -197.335648)
		(width 0.127)
		(layer "In5.Cu")
		(net "UART_RI_P5_L_N")
	)
	(segment
		(start 15.945866 -130.449828)
		(end 16.831564 -130.449828)
		(width 0.127)
		(layer "In5.Cu")
		(net "UART_RI_P5_L_N")
	)
	(segment
		(start 19.549364 -133.167628)
		(end 19.549364 -159.695134)
		(width 0.127)
		(layer "In5.Cu")
		(net "UART_RI_P5_L_N")
	)
	(segment
		(start 3.03911 -196.216016)
		(end 3.03911 -197.125336)
		(width 0.127)
		(layer "In5.Cu")
		(net "UART_RI_P5_L_N")
	)
	(segment
		(start 8.662416 -189.444884)
		(end 8.052054 -189.444884)
		(width 0.127)
		(layer "In5.Cu")
		(net "UART_RI_P5_L_N")
	)
	(segment
		(start 3.01117 -199.153272)
		(end 2.856738 -199.307704)
		(width 0.127)
		(layer "In5.Cu")
		(net "UART_RI_P5_L_N")
	)
	(segment
		(start 13.35278 -64.713866)
		(end 10.588244 -67.478402)
		(width 0.127)
		(layer "In5.Cu")
		(net "UART_RI_P5_L_N")
	)
	(segment
		(start 11.229594 -168.014904)
		(end 10.109708 -169.135044)
		(width 0.127)
		(layer "In5.Cu")
		(net "UART_RI_P5_L_N")
	)
	(segment
		(start 2.828798 -197.335648)
		(end 2.828798 -198.0057)
		(width 0.127)
		(layer "In5.Cu")
		(net "UART_RI_P5_L_N")
	)
	(segment
		(start 3.03911 -200.216008)
		(end 3.03911 -201.125328)
		(width 0.127)
		(layer "In5.Cu")
		(net "UART_RI_P5_L_N")
	)
	(segment
		(start 9.366504 -74.380598)
		(end 9.366504 -90.08364)
		(width 0.127)
		(layer "In5.Cu")
		(net "UART_RI_P5_L_N")
	)
	(segment
		(start 3.083814 -194.260724)
		(end 3.083814 -195.080636)
		(width 0.127)
		(layer "In5.Cu")
		(net "UART_RI_P5_L_N")
	)
	(segment
		(start 7.269226 -115.796822)
		(end 7.269226 -121.773188)
		(width 0.127)
		(layer "In5.Cu")
		(net "UART_RI_P5_L_N")
	)
	(segment
		(start 2.920238 -193.244216)
		(end 2.920238 -194.097148)
		(width 0.127)
		(layer "In5.Cu")
		(net "UART_RI_P5_L_N")
	)
	(segment
		(start 3.03911 -201.125328)
		(end 2.920238 -201.2442)
		(width 0.127)
		(layer "In5.Cu")
		(net "UART_RI_P5_L_N")
	)
	(segment
		(start 7.099554 -190.397384)
		(end 6.210046 -190.397384)
		(width 0.127)
		(layer "In5.Cu")
		(net "UART_RI_P5_L_N")
	)
	(segment
		(start 2.856738 -199.307704)
		(end 2.856738 -200.033636)
		(width 0.127)
		(layer "In5.Cu")
		(net "UART_RI_P5_L_N")
	)
	(segment
		(start 2.920238 -194.097148)
		(end 3.083814 -194.260724)
		(width 0.127)
		(layer "In5.Cu")
		(net "UART_RI_P5_L_N")
	)
	(segment
		(start 10.109708 -187.997592)
		(end 8.662416 -189.444884)
		(width 0.127)
		(layer "In5.Cu")
		(net "UART_RI_P5_L_N")
	)
	(segment
		(start 7.269226 -121.773188)
		(end 15.945866 -130.449828)
		(width 0.127)
		(layer "In5.Cu")
		(net "UART_RI_P5_L_N")
	)
	(segment
		(start 10.109708 -169.135044)
		(end 10.109708 -187.997592)
		(width 0.127)
		(layer "In5.Cu")
		(net "UART_RI_P5_L_N")
	)
	(segment
		(start 2.920238 -201.2442)
		(end 2.920238 -201.699114)
		(width 0.127)
		(layer "In5.Cu")
		(net "UART_RI_P5_L_N")
	)
	(segment
		(start 16.504666 -67.183)
		(end 16.504666 -66.753994)
		(width 0.127)
		(layer "In5.Cu")
		(net "UART_RI_P5_L_N")
	)
	(segment
		(start 3.7846 -112.312196)
		(end 7.269226 -115.796822)
		(width 0.127)
		(layer "In5.Cu")
		(net "UART_RI_P5_L_N")
	)
	(segment
		(start 3.083814 -195.080636)
		(end 2.815082 -195.349368)
		(width 0.127)
		(layer "In5.Cu")
		(net "UART_RI_P5_L_N")
	)
	(segment
		(start 6.054598 -91.428316)
		(end 3.7846 -93.698314)
		(width 0.127)
		(layer "In5.Cu")
		(net "UART_RI_P5_L_N")
	)
	(segment
		(start 2.856738 -200.033636)
		(end 3.03911 -200.216008)
		(width 0.127)
		(layer "In5.Cu")
		(net "UART_RI_P5_L_N")
	)
	(segment
		(start 16.504666 -66.753994)
		(end 14.464538 -64.713866)
		(width 0.127)
		(layer "In5.Cu")
		(net "UART_RI_P5_L_N")
	)
	(segment
		(start 4.20116 -192.40627)
		(end 3.758184 -192.40627)
		(width 0.127)
		(layer "In5.Cu")
		(net "UART_RI_P5_L_N")
	)
	(segment
		(start 2.815082 -195.349368)
		(end 2.815082 -195.991988)
		(width 0.127)
		(layer "In5.Cu")
		(net "UART_RI_P5_L_N")
	)
	(segment
		(start 2.828798 -198.0057)
		(end 3.01117 -198.188072)
		(width 0.127)
		(layer "In5.Cu")
		(net "UART_RI_P5_L_N")
	)
	(segment
		(start 14.464538 -64.713866)
		(end 13.35278 -64.713866)
		(width 0.127)
		(layer "In5.Cu")
		(net "UART_RI_P5_L_N")
	)
	(segment
		(start 19.549364 -159.695134)
		(end 11.229594 -168.014904)
		(width 0.127)
		(layer "In5.Cu")
		(net "UART_RI_P5_L_N")
	)
	(segment
		(start 2.920238 -201.699114)
		(end 1.948942 -202.67041)
		(width 0.127)
		(layer "In5.Cu")
		(net "UART_RI_P5_L_N")
	)
	(segment
		(start 8.021828 -91.428316)
		(end 6.054598 -91.428316)
		(width 0.127)
		(layer "In5.Cu")
		(net "UART_RI_P5_L_N")
	)
	(segment
		(start 8.052054 -189.444884)
		(end 7.099554 -190.397384)
		(width 0.127)
		(layer "In5.Cu")
		(net "UART_RI_P5_L_N")
	)
	(segment
		(start 3.758184 -192.40627)
		(end 2.920238 -193.244216)
		(width 0.127)
		(layer "In5.Cu")
		(net "UART_RI_P5_L_N")
	)
	(segment
		(start 10.588244 -73.158858)
		(end 9.366504 -74.380598)
		(width 0.127)
		(layer "In5.Cu")
		(net "UART_RI_P5_L_N")
	)
	(segment
		(start 16.504666 -101.727)
		(end 16.579088 -101.727)
		(width 0.1524)
		(layer "B.Cu")
		(net "UART_RI_P6_L_N")
	)
	(segment
		(start 19.985228 -140.587984)
		(end 18.166588 -142.406624)
		(width 0.1524)
		(layer "B.Cu")
		(net "UART_RI_P6_L_N")
	)
	(segment
		(start 16.579088 -101.727)
		(end 17.559782 -100.746306)
		(width 0.1524)
		(layer "B.Cu")
		(net "UART_RI_P6_L_N")
	)
	(segment
		(start 19.985228 -132.792978)
		(end 19.985228 -140.587984)
		(width 0.1524)
		(layer "B.Cu")
		(net "UART_RI_P6_L_N")
	)
	(segment
		(start 11.770868 -110.272576)
		(end 7.429246 -114.614198)
		(width 0.1524)
		(layer "B.Cu")
		(net "UART_RI_P6_L_N")
	)
	(segment
		(start 11.770868 -100.757736)
		(end 11.770868 -110.272576)
		(width 0.1524)
		(layer "B.Cu")
		(net "UART_RI_P6_L_N")
	)
	(segment
		(start 17.559782 -98.405442)
		(end 17.09547 -97.94113)
		(width 0.1524)
		(layer "B.Cu")
		(net "UART_RI_P6_L_N")
	)
	(segment
		(start 17.559782 -100.746306)
		(end 17.559782 -98.405442)
		(width 0.1524)
		(layer "B.Cu")
		(net "UART_RI_P6_L_N")
	)
	(segment
		(start 7.429246 -114.614198)
		(end 7.429246 -120.236996)
		(width 0.1524)
		(layer "B.Cu")
		(net "UART_RI_P6_L_N")
	)
	(segment
		(start 18.166588 -142.406624)
		(end 18.166588 -194.079876)
		(width 0.1524)
		(layer "B.Cu")
		(net "UART_RI_P6_L_N")
	)
	(segment
		(start 15.980918 -97.94113)
		(end 14.736064 -99.185984)
		(width 0.1524)
		(layer "B.Cu")
		(net "UART_RI_P6_L_N")
	)
	(segment
		(start 9.576054 -202.67041)
		(end 8.448802 -202.67041)
		(width 0.1524)
		(layer "B.Cu")
		(net "UART_RI_P6_L_N")
	)
	(segment
		(start 17.09547 -97.94113)
		(end 15.980918 -97.94113)
		(width 0.1524)
		(layer "B.Cu")
		(net "UART_RI_P6_L_N")
	)
	(segment
		(start 18.166588 -194.079876)
		(end 9.576054 -202.67041)
		(width 0.1524)
		(layer "B.Cu")
		(net "UART_RI_P6_L_N")
	)
	(segment
		(start 14.736064 -99.185984)
		(end 13.34262 -99.185984)
		(width 0.1524)
		(layer "B.Cu")
		(net "UART_RI_P6_L_N")
	)
	(segment
		(start 13.34262 -99.185984)
		(end 11.770868 -100.757736)
		(width 0.1524)
		(layer "B.Cu")
		(net "UART_RI_P6_L_N")
	)
	(segment
		(start 7.429246 -120.236996)
		(end 19.985228 -132.792978)
		(width 0.1524)
		(layer "B.Cu")
		(net "UART_RI_P6_L_N")
	)
	(segment
		(start 34.114486 -108.229908)
		(end 35.53968 -108.229908)
		(width 0.508)
		(layer "F.Cu")
		(net "P12V_STBY")
	)
	(segment
		(start 35.53968 -373.430038)
		(end 33.490154 -371.380512)
		(width 0.508)
		(layer "F.Cu")
		(net "P12V_STBY")
	)
	(segment
		(start 23.82266 -7.648702)
		(end 24.278082 -7.19328)
		(width 0.508)
		(layer "F.Cu")
		(net "P12V_STBY")
	)
	(segment
		(start 24.62784 -184.266078)
		(end 25.668224 -184.266078)
		(width 0.508)
		(layer "F.Cu")
		(net "P12V_STBY")
	)
	(segment
		(start 33.994598 -283.484828)
		(end 35.53968 -285.02991)
		(width 0.508)
		(layer "F.Cu")
		(net "P12V_STBY")
	)
	(segment
		(start 29.31541 -458.04201)
		(end 28.417266 -458.940154)
		(width 0.508)
		(layer "F.Cu")
		(net "P12V_STBY")
	)
	(segment
		(start 37.547296 -106.222292)
		(end 35.53968 -108.229908)
		(width 0.508)
		(layer "F.Cu")
		(net "P12V_STBY")
	)
	(segment
		(start 36.184586 -197.274942)
		(end 35.53968 -196.630036)
		(width 0.508)
		(layer "F.Cu")
		(net "P12V_STBY")
	)
	(segment
		(start 33.490154 -371.380512)
		(end 33.490154 -356.991666)
		(width 0.508)
		(layer "F.Cu")
		(net "P12V_STBY")
	)
	(segment
		(start 36.081208 -462.37144)
		(end 35.53968 -461.829912)
		(width 0.508)
		(layer "F.Cu")
		(net "P12V_STBY")
	)
	(segment
		(start 39.705534 -106.222292)
		(end 37.547296 -106.222292)
		(width 0.508)
		(layer "F.Cu")
		(net "P12V_STBY")
	)
	(segment
		(start 29.781754 -91.124532)
		(end 28.732226 -90.075004)
		(width 0.508)
		(layer "F.Cu")
		(net "P12V_STBY")
	)
	(segment
		(start 28.03779 -260.639814)
		(end 33.994598 -266.596622)
		(width 0.508)
		(layer "F.Cu")
		(net "P12V_STBY")
	)
	(segment
		(start 39.653718 -283.496258)
		(end 37.073332 -283.496258)
		(width 0.508)
		(layer "F.Cu")
		(net "P12V_STBY")
	)
	(segment
		(start 25.457658 -364.246414)
		(end 25.457658 -363.01553)
		(width 0.508)
		(layer "F.Cu")
		(net "P12V_STBY")
	)
	(segment
		(start 25.457658 -363.01553)
		(end 24.482044 -363.01553)
		(width 0.508)
		(layer "F.Cu")
		(net "P12V_STBY")
	)
	(segment
		(start 39.398702 -197.274942)
		(end 36.184586 -197.274942)
		(width 0.508)
		(layer "F.Cu")
		(net "P12V_STBY")
	)
	(segment
		(start 29.106368 -287.184846)
		(end 30.01137 -286.279844)
		(width 0.508)
		(layer "F.Cu")
		(net "P12V_STBY")
	)
	(segment
		(start 24.100028 -98.09099)
		(end 23.12162 -99.069398)
		(width 0.508)
		(layer "F.Cu")
		(net "P12V_STBY")
	)
	(segment
		(start 33.490154 -356.991666)
		(end 31.679896 -355.181408)
		(width 0.508)
		(layer "F.Cu")
		(net "P12V_STBY")
	)
	(segment
		(start 24.278082 -7.19328)
		(end 25.597612 -7.19328)
		(width 0.508)
		(layer "F.Cu")
		(net "P12V_STBY")
	)
	(segment
		(start 36.955476 -18.414238)
		(end 35.53968 -19.830034)
		(width 0.508)
		(layer "F.Cu")
		(net "P12V_STBY")
	)
	(segment
		(start 29.031438 -180.66893)
		(end 30.059884 -179.640484)
		(width 0.508)
		(layer "F.Cu")
		(net "P12V_STBY")
	)
	(segment
		(start 28.03779 -204.090524)
		(end 28.03779 -260.639814)
		(width 0.508)
		(layer "F.Cu")
		(net "P12V_STBY")
	)
	(segment
		(start 25.518872 -98.09099)
		(end 24.100028 -98.09099)
		(width 0.508)
		(layer "F.Cu")
		(net "P12V_STBY")
	)
	(segment
		(start 25.531572 -96.872044)
		(end 24.570944 -96.872044)
		(width 0.508)
		(layer "F.Cu")
		(net "P12V_STBY")
	)
	(segment
		(start 30.059884 -179.640484)
		(end 35.964114 -179.640484)
		(width 0.508)
		(layer "F.Cu")
		(net "P12V_STBY")
	)
	(segment
		(start 35.964114 -179.640484)
		(end 37.380418 -181.056788)
		(width 0.508)
		(layer "F.Cu")
		(net "P12V_STBY")
	)
	(segment
		(start 27.391106 -113.229898)
		(end 27.391106 -178.044856)
		(width 0.508)
		(layer "F.Cu")
		(net "P12V_STBY")
	)
	(segment
		(start 23.015448 -197.410578)
		(end 27.273758 -201.668888)
		(width 0.508)
		(layer "F.Cu")
		(net "P12V_STBY")
	)
	(segment
		(start 41.509442 -195.573904)
		(end 39.708328 -195.573904)
		(width 0.508)
		(layer "F.Cu")
		(net "P12V_STBY")
	)
	(segment
		(start 23.830534 -358.909366)
		(end 27.558492 -355.181408)
		(width 0.508)
		(layer "F.Cu")
		(net "P12V_STBY")
	)
	(segment
		(start 31.679896 -355.181408)
		(end 27.558492 -355.181408)
		(width 0.508)
		(layer "F.Cu")
		(net "P12V_STBY")
	)
	(segment
		(start 32.058864 -91.124532)
		(end 33.268412 -92.33408)
		(width 0.508)
		(layer "F.Cu")
		(net "P12V_STBY")
	)
	(segment
		(start 24.879554 -180.66893)
		(end 24.011382 -181.537102)
		(width 0.508)
		(layer "F.Cu")
		(net "P12V_STBY")
	)
	(segment
		(start 39.421308 -18.414238)
		(end 36.955476 -18.414238)
		(width 0.508)
		(layer "F.Cu")
		(net "P12V_STBY")
	)
	(segment
		(start 27.558492 -311.419748)
		(end 29.106368 -309.871872)
		(width 0.508)
		(layer "F.Cu")
		(net "P12V_STBY")
	)
	(segment
		(start 39.473886 -462.37144)
		(end 36.081208 -462.37144)
		(width 0.508)
		(layer "F.Cu")
		(net "P12V_STBY")
	)
	(segment
		(start 39.708328 -195.573904)
		(end 39.398702 -195.88353)
		(width 0.508)
		(layer "F.Cu")
		(net "P12V_STBY")
	)
	(segment
		(start 24.011382 -183.64962)
		(end 24.62784 -184.266078)
		(width 0.508)
		(layer "F.Cu")
		(net "P12V_STBY")
	)
	(segment
		(start 31.328868 -379.81509)
		(end 32.60979 -378.534168)
		(width 0.508)
		(layer "F.Cu")
		(net "P12V_STBY")
	)
	(segment
		(start 41.915588 -195.167758)
		(end 41.509442 -195.573904)
		(width 0.508)
		(layer "F.Cu")
		(net "P12V_STBY")
	)
	(segment
		(start 27.558492 -355.181408)
		(end 27.558492 -311.419748)
		(width 0.508)
		(layer "F.Cu")
		(net "P12V_STBY")
	)
	(segment
		(start 23.662386 -95.963486)
		(end 23.662386 -94.041976)
		(width 0.508)
		(layer "F.Cu")
		(net "P12V_STBY")
	)
	(segment
		(start 27.273758 -203.326492)
		(end 28.03779 -204.090524)
		(width 0.508)
		(layer "F.Cu")
		(net "P12V_STBY")
	)
	(segment
		(start 27.741626 -180.660802)
		(end 27.749754 -180.66893)
		(width 0.508)
		(layer "F.Cu")
		(net "P12V_STBY")
	)
	(segment
		(start 22.339046 -104.90454)
		(end 22.339046 -108.177838)
		(width 0.508)
		(layer "F.Cu")
		(net "P12V_STBY")
	)
	(segment
		(start 25.668224 -185.521092)
		(end 24.319992 -185.521092)
		(width 0.508)
		(layer "F.Cu")
		(net "P12V_STBY")
	)
	(segment
		(start 28.417266 -458.940154)
		(end 26.175716 -458.940154)
		(width 0.508)
		(layer "F.Cu")
		(net "P12V_STBY")
	)
	(segment
		(start 23.12162 -99.069398)
		(end 23.12162 -104.121966)
		(width 0.508)
		(layer "F.Cu")
		(net "P12V_STBY")
	)
	(segment
		(start 25.192482 -17.067784)
		(end 23.82266 -15.697962)
		(width 0.508)
		(layer "F.Cu")
		(net "P12V_STBY")
	)
	(segment
		(start 33.268412 -92.33408)
		(end 33.268412 -107.383834)
		(width 0.508)
		(layer "F.Cu")
		(net "P12V_STBY")
	)
	(segment
		(start 28.732226 -90.075004)
		(end 28.732226 -22.093682)
		(width 0.508)
		(layer "F.Cu")
		(net "P12V_STBY")
	)
	(segment
		(start 27.749754 -180.66893)
		(end 29.031438 -180.66893)
		(width 0.508)
		(layer "F.Cu")
		(net "P12V_STBY")
	)
	(segment
		(start 22.339046 -108.177838)
		(end 27.391106 -113.229898)
		(width 0.508)
		(layer "F.Cu")
		(net "P12V_STBY")
	)
	(segment
		(start 36.256722 -374.14708)
		(end 35.53968 -373.430038)
		(width 0.508)
		(layer "F.Cu")
		(net "P12V_STBY")
	)
	(segment
		(start 23.015448 -186.825636)
		(end 23.015448 -197.410578)
		(width 0.508)
		(layer "F.Cu")
		(net "P12V_STBY")
	)
	(segment
		(start 24.319992 -185.521092)
		(end 23.015448 -186.825636)
		(width 0.508)
		(layer "F.Cu")
		(net "P12V_STBY")
	)
	(segment
		(start 25.668224 -185.521092)
		(end 25.668224 -184.266078)
		(width 0.508)
		(layer "F.Cu")
		(net "P12V_STBY")
	)
	(segment
		(start 24.011382 -181.537102)
		(end 24.011382 -183.64962)
		(width 0.508)
		(layer "F.Cu")
		(net "P12V_STBY")
	)
	(segment
		(start 24.396446 -446.314322)
		(end 28.767278 -441.94349)
		(width 0.508)
		(layer "F.Cu")
		(net "P12V_STBY")
	)
	(segment
		(start 27.741626 -178.395376)
		(end 27.741626 -180.660802)
		(width 0.508)
		(layer "F.Cu")
		(net "P12V_STBY")
	)
	(segment
		(start 26.175716 -458.940154)
		(end 23.82774 -456.592178)
		(width 0.508)
		(layer "F.Cu")
		(net "P12V_STBY")
	)
	(segment
		(start 23.82266 -15.697962)
		(end 23.82266 -7.648702)
		(width 0.508)
		(layer "F.Cu")
		(net "P12V_STBY")
	)
	(segment
		(start 37.073332 -283.496258)
		(end 35.53968 -285.02991)
		(width 0.508)
		(layer "F.Cu")
		(net "P12V_STBY")
	)
	(segment
		(start 37.380418 -186.908948)
		(end 41.915588 -191.444118)
		(width 0.508)
		(layer "F.Cu")
		(net "P12V_STBY")
	)
	(segment
		(start 41.915588 -191.444118)
		(end 41.915588 -195.167758)
		(width 0.508)
		(layer "F.Cu")
		(net "P12V_STBY")
	)
	(segment
		(start 25.597612 -6.169152)
		(end 25.576022 -6.147562)
		(width 0.508)
		(layer "F.Cu")
		(net "P12V_STBY")
	)
	(segment
		(start 32.60979 -378.534168)
		(end 32.60979 -376.359928)
		(width 0.508)
		(layer "F.Cu")
		(net "P12V_STBY")
	)
	(segment
		(start 28.732226 -22.093682)
		(end 29.657294 -21.168614)
		(width 0.508)
		(layer "F.Cu")
		(net "P12V_STBY")
	)
	(segment
		(start 23.830534 -362.36402)
		(end 23.830534 -358.909366)
		(width 0.508)
		(layer "F.Cu")
		(net "P12V_STBY")
	)
	(segment
		(start 25.531572 -98.10369)
		(end 25.531572 -96.872044)
		(width 0.508)
		(layer "F.Cu")
		(net "P12V_STBY")
	)
	(segment
		(start 24.482044 -363.01553)
		(end 23.830534 -362.36402)
		(width 0.508)
		(layer "F.Cu")
		(net "P12V_STBY")
	)
	(segment
		(start 29.781754 -91.124532)
		(end 32.058864 -91.124532)
		(width 0.508)
		(layer "F.Cu")
		(net "P12V_STBY")
	)
	(segment
		(start 23.82774 -451.913498)
		(end 24.760682 -450.980556)
		(width 0.508)
		(layer "F.Cu")
		(net "P12V_STBY")
	)
	(segment
		(start 25.702006 -274.774914)
		(end 24.557736 -274.774914)
		(width 0.4572)
		(layer "F.Cu")
		(net "P12V_STBY")
	)
	(segment
		(start 33.994598 -266.596622)
		(end 33.994598 -283.484828)
		(width 0.508)
		(layer "F.Cu")
		(net "P12V_STBY")
	)
	(segment
		(start 30.01137 -286.279844)
		(end 34.289746 -286.279844)
		(width 0.508)
		(layer "F.Cu")
		(net "P12V_STBY")
	)
	(segment
		(start 25.531572 -98.10369)
		(end 25.518872 -98.09099)
		(width 0.508)
		(layer "F.Cu")
		(net "P12V_STBY")
	)
	(segment
		(start 29.106368 -309.871872)
		(end 29.106368 -287.184846)
		(width 0.508)
		(layer "F.Cu")
		(net "P12V_STBY")
	)
	(segment
		(start 32.60979 -376.359928)
		(end 35.53968 -373.430038)
		(width 0.508)
		(layer "F.Cu")
		(net "P12V_STBY")
	)
	(segment
		(start 29.657294 -21.168614)
		(end 34.1757 -21.168614)
		(width 0.508)
		(layer "F.Cu")
		(net "P12V_STBY")
	)
	(segment
		(start 29.408628 -18.562066)
		(end 27.914346 -17.067784)
		(width 0.508)
		(layer "F.Cu")
		(net "P12V_STBY")
	)
	(segment
		(start 23.82774 -456.592178)
		(end 23.82774 -451.913498)
		(width 0.508)
		(layer "F.Cu")
		(net "P12V_STBY")
	)
	(segment
		(start 23.12162 -104.121966)
		(end 22.339046 -104.90454)
		(width 0.508)
		(layer "F.Cu")
		(net "P12V_STBY")
	)
	(segment
		(start 34.1757 -21.168614)
		(end 35.51428 -19.830034)
		(width 0.508)
		(layer "F.Cu")
		(net "P12V_STBY")
	)
	(segment
		(start 39.534592 -374.14708)
		(end 36.256722 -374.14708)
		(width 0.508)
		(layer "F.Cu")
		(net "P12V_STBY")
	)
	(segment
		(start 28.767278 -380.704598)
		(end 29.656786 -379.81509)
		(width 0.508)
		(layer "F.Cu")
		(net "P12V_STBY")
	)
	(segment
		(start 27.391106 -178.044856)
		(end 27.741626 -178.395376)
		(width 0.508)
		(layer "F.Cu")
		(net "P12V_STBY")
	)
	(segment
		(start 25.825958 -449.713858)
		(end 25.214326 -449.713858)
		(width 0.508)
		(layer "F.Cu")
		(net "P12V_STBY")
	)
	(segment
		(start 25.597612 -7.19328)
		(end 25.597612 -6.169152)
		(width 0.508)
		(layer "F.Cu")
		(net "P12V_STBY")
	)
	(segment
		(start 24.0538 -93.650562)
		(end 27.255724 -93.650562)
		(width 0.508)
		(layer "F.Cu")
		(net "P12V_STBY")
	)
	(segment
		(start 34.289746 -286.279844)
		(end 35.53968 -285.02991)
		(width 0.508)
		(layer "F.Cu")
		(net "P12V_STBY")
	)
	(segment
		(start 35.51428 -19.830034)
		(end 35.53968 -19.830034)
		(width 0.508)
		(layer "F.Cu")
		(net "P12V_STBY")
	)
	(segment
		(start 27.255724 -93.650562)
		(end 29.781754 -91.124532)
		(width 0.508)
		(layer "F.Cu")
		(net "P12V_STBY")
	)
	(segment
		(start 27.273758 -201.668888)
		(end 27.273758 -203.326492)
		(width 0.508)
		(layer "F.Cu")
		(net "P12V_STBY")
	)
	(segment
		(start 23.662386 -94.041976)
		(end 24.0538 -93.650562)
		(width 0.508)
		(layer "F.Cu")
		(net "P12V_STBY")
	)
	(segment
		(start 27.749754 -180.66893)
		(end 24.879554 -180.66893)
		(width 0.508)
		(layer "F.Cu")
		(net "P12V_STBY")
	)
	(segment
		(start 39.398702 -195.88353)
		(end 39.398702 -197.274942)
		(width 0.508)
		(layer "F.Cu")
		(net "P12V_STBY")
	)
	(segment
		(start 35.53968 -461.829912)
		(end 31.751778 -458.04201)
		(width 0.508)
		(layer "F.Cu")
		(net "P12V_STBY")
	)
	(segment
		(start 24.570944 -96.872044)
		(end 23.662386 -95.963486)
		(width 0.508)
		(layer "F.Cu")
		(net "P12V_STBY")
	)
	(segment
		(start 29.656786 -379.81509)
		(end 31.328868 -379.81509)
		(width 0.508)
		(layer "F.Cu")
		(net "P12V_STBY")
	)
	(segment
		(start 35.53968 -19.830034)
		(end 34.271712 -18.562066)
		(width 0.508)
		(layer "F.Cu")
		(net "P12V_STBY")
	)
	(segment
		(start 27.914346 -17.067784)
		(end 25.192482 -17.067784)
		(width 0.508)
		(layer "F.Cu")
		(net "P12V_STBY")
	)
	(segment
		(start 25.214326 -449.713858)
		(end 24.396446 -448.895978)
		(width 0.508)
		(layer "F.Cu")
		(net "P12V_STBY")
	)
	(segment
		(start 24.760682 -450.980556)
		(end 25.825958 -450.980556)
		(width 0.508)
		(layer "F.Cu")
		(net "P12V_STBY")
	)
	(segment
		(start 37.380418 -181.056788)
		(end 37.380418 -186.908948)
		(width 0.508)
		(layer "F.Cu")
		(net "P12V_STBY")
	)
	(segment
		(start 25.825958 -449.713858)
		(end 25.825958 -450.980556)
		(width 0.508)
		(layer "F.Cu")
		(net "P12V_STBY")
	)
	(segment
		(start 24.396446 -448.895978)
		(end 24.396446 -446.314322)
		(width 0.508)
		(layer "F.Cu")
		(net "P12V_STBY")
	)
	(segment
		(start 33.268412 -107.383834)
		(end 34.114486 -108.229908)
		(width 0.508)
		(layer "F.Cu")
		(net "P12V_STBY")
	)
	(segment
		(start 25.702006 -274.774914)
		(end 25.702006 -273.532854)
		(width 0.4572)
		(layer "F.Cu")
		(net "P12V_STBY")
	)
	(segment
		(start 28.767278 -441.94349)
		(end 28.767278 -380.704598)
		(width 0.508)
		(layer "F.Cu")
		(net "P12V_STBY")
	)
	(segment
		(start 31.751778 -458.04201)
		(end 29.31541 -458.04201)
		(width 0.508)
		(layer "F.Cu")
		(net "P12V_STBY")
	)
	(segment
		(start 34.271712 -18.562066)
		(end 29.408628 -18.562066)
		(width 0.508)
		(layer "F.Cu")
		(net "P12V_STBY")
	)
	(via
		(at 24.557736 -274.774914)
		(size 0.508)
		(drill 0.254)
		(layers "F.Cu" "B.Cu")
		(net "P12V_STBY")
	)
	(segment
		(start 32.600392 -277.165562)
		(end 31.57093 -276.1361)
		(width 0.4572)
		(layer "In5.Cu")
		(net "P12V_STBY")
	)
	(segment
		(start 32.600392 -282.090622)
		(end 32.600392 -277.165562)
		(width 0.4572)
		(layer "In5.Cu")
		(net "P12V_STBY")
	)
	(segment
		(start 27.035252 -276.1361)
		(end 25.674066 -274.774914)
		(width 0.4572)
		(layer "In5.Cu")
		(net "P12V_STBY")
	)
	(segment
		(start 25.674066 -274.774914)
		(end 24.557736 -274.774914)
		(width 0.4572)
		(layer "In5.Cu")
		(net "P12V_STBY")
	)
	(segment
		(start 35.53968 -285.02991)
		(end 32.600392 -282.090622)
		(width 0.4572)
		(layer "In5.Cu")
		(net "P12V_STBY")
	)
	(segment
		(start 31.57093 -276.1361)
		(end 27.035252 -276.1361)
		(width 0.4572)
		(layer "In5.Cu")
		(net "P12V_STBY")
	)
	(segment
		(start 27.699716 -14.7955)
		(end 26.892758 -14.7955)
		(width 0.1524)
		(layer "F.Cu")
		(net "PSU1_CSAHRE")
	)
	(segment
		(start 28.389834 -14.7955)
		(end 27.699716 -14.7955)
		(width 0.1524)
		(layer "F.Cu")
		(net "PSU1_CSAHRE")
	)
	(segment
		(start 30.45968 -14.750034)
		(end 28.4353 -14.750034)
		(width 0.1524)
		(layer "F.Cu")
		(net "PSU1_CSAHRE")
	)
	(segment
		(start 28.4353 -14.750034)
		(end 28.389834 -14.7955)
		(width 0.1524)
		(layer "F.Cu")
		(net "PSU1_CSAHRE")
	)
	(via
		(at 27.699716 -14.7955)
		(size 0.508)
		(drill 0.254)
		(layers "F.Cu" "B.Cu")
		(net "PSU1_CSAHRE")
	)
	(segment
		(start 30.45968 -191.550036)
		(end 30.443932 -191.550036)
		(width 0.1524)
		(layer "F.Cu")
		(net "PSU3_CSAHRE")
	)
	(segment
		(start 30.4419 -191.548004)
		(end 27.76601 -191.548004)
		(width 0.1524)
		(layer "F.Cu")
		(net "PSU3_CSAHRE")
	)
	(segment
		(start 27.76601 -191.548004)
		(end 26.58618 -190.368174)
		(width 0.1524)
		(layer "F.Cu")
		(net "PSU3_CSAHRE")
	)
	(segment
		(start 30.443932 -191.550036)
		(end 30.4419 -191.548004)
		(width 0.1524)
		(layer "F.Cu")
		(net "PSU3_CSAHRE")
	)
	(segment
		(start 27.132026 -457.76642)
		(end 27.132534 -457.766928)
		(width 0.1524)
		(layer "F.Cu")
		(net "PSU6_CSAHRE")
	)
	(segment
		(start 30.45968 -456.749912)
		(end 29.44368 -456.749912)
		(width 0.1524)
		(layer "F.Cu")
		(net "PSU6_CSAHRE")
	)
	(segment
		(start 29.442664 -456.748896)
		(end 28.14955 -456.748896)
		(width 0.1524)
		(layer "F.Cu")
		(net "PSU6_CSAHRE")
	)
	(segment
		(start 28.14955 -456.748896)
		(end 27.132026 -457.76642)
		(width 0.1524)
		(layer "F.Cu")
		(net "PSU6_CSAHRE")
	)
	(segment
		(start 29.44368 -456.749912)
		(end 29.442664 -456.748896)
		(width 0.1524)
		(layer "F.Cu")
		(net "PSU6_CSAHRE")
	)
	(segment
		(start 27.132534 -457.766928)
		(end 27.132534 -456.748896)
		(width 0.1524)
		(layer "F.Cu")
		(net "PSU6_CSAHRE")
	)
	(via
		(at 27.132026 -457.76642)
		(size 0.508)
		(drill 0.254)
		(layers "F.Cu" "B.Cu")
		(net "PSU6_CSAHRE")
	)
	(segment
		(start 27.69362 -280.04389)
		(end 29.091636 -280.04389)
		(width 0.1524)
		(layer "F.Cu")
		(net "PSU4_CSAHRE")
	)
	(segment
		(start 29.091636 -280.04389)
		(end 29.185616 -279.94991)
		(width 0.1524)
		(layer "F.Cu")
		(net "PSU4_CSAHRE")
	)
	(segment
		(start 29.185616 -279.94991)
		(end 30.45968 -279.94991)
		(width 0.1524)
		(layer "F.Cu")
		(net "PSU4_CSAHRE")
	)
	(segment
		(start 30.443932 -103.149908)
		(end 30.45968 -103.149908)
		(width 0.1524)
		(layer "F.Cu")
		(net "PSU2_CSAHRE")
	)
	(segment
		(start 26.401776 -101.689408)
		(end 28.983432 -101.689408)
		(width 0.1524)
		(layer "F.Cu")
		(net "PSU2_CSAHRE")
	)
	(segment
		(start 28.983432 -101.689408)
		(end 30.443932 -103.149908)
		(width 0.1524)
		(layer "F.Cu")
		(net "PSU2_CSAHRE")
	)
	(segment
		(start 30.443932 -368.350038)
		(end 30.45968 -368.350038)
		(width 0.1524)
		(layer "F.Cu")
		(net "PSU5_CSAHRE")
	)
	(segment
		(start 27.057604 -369.095274)
		(end 27.179524 -368.973354)
		(width 0.1524)
		(layer "F.Cu")
		(net "PSU5_CSAHRE")
	)
	(segment
		(start 27.804364 -368.348514)
		(end 30.442408 -368.348514)
		(width 0.1524)
		(layer "F.Cu")
		(net "PSU5_CSAHRE")
	)
	(segment
		(start 26.204926 -369.095274)
		(end 27.057604 -369.095274)
		(width 0.1524)
		(layer "F.Cu")
		(net "PSU5_CSAHRE")
	)
	(segment
		(start 30.442408 -368.348514)
		(end 30.443932 -368.350038)
		(width 0.1524)
		(layer "F.Cu")
		(net "PSU5_CSAHRE")
	)
	(segment
		(start 27.179524 -368.973354)
		(end 27.804364 -368.348514)
		(width 0.1524)
		(layer "F.Cu")
		(net "PSU5_CSAHRE")
	)
	(via
		(at 27.179524 -368.973354)
		(size 0.508)
		(drill 0.254)
		(layers "F.Cu" "B.Cu")
		(net "PSU5_CSAHRE")
	)
	(segment
		(start 72.532748 -473.59951)
		(end 71.113904 -473.59951)
		(width 0.4572)
		(layer "F.Cu")
		(net "PSU6_REMOTE_R2_P")
	)
	(segment
		(start 39.512494 -463.572098)
		(end 40.40505 -463.572098)
		(width 0.4572)
		(layer "F.Cu")
		(net "PSU6_REMOTE_R2_P")
	)
	(via
		(at 71.113904 -473.59951)
		(size 0.508)
		(drill 0.254)
		(layers "F.Cu" "B.Cu")
		(net "PSU6_REMOTE_R2_P")
	)
	(via
		(at 40.40505 -463.572098)
		(size 0.508)
		(drill 0.254)
		(layers "F.Cu" "B.Cu")
		(net "PSU6_REMOTE_R2_P")
	)
	(segment
		(start 65.118742 -473.273628)
		(end 58.853324 -467.00821)
		(width 0.4572)
		(layer "In5.Cu")
		(net "PSU6_REMOTE_R2_P")
	)
	(segment
		(start 43.734482 -463.572098)
		(end 40.40505 -463.572098)
		(width 0.4572)
		(layer "In5.Cu")
		(net "PSU6_REMOTE_R2_P")
	)
	(segment
		(start 71.113904 -473.59951)
		(end 70.788022 -473.273628)
		(width 0.4572)
		(layer "In5.Cu")
		(net "PSU6_REMOTE_R2_P")
	)
	(segment
		(start 70.788022 -473.273628)
		(end 65.118742 -473.273628)
		(width 0.4572)
		(layer "In5.Cu")
		(net "PSU6_REMOTE_R2_P")
	)
	(segment
		(start 58.853324 -467.00821)
		(end 47.170594 -467.00821)
		(width 0.4572)
		(layer "In5.Cu")
		(net "PSU6_REMOTE_R2_P")
	)
	(segment
		(start 47.170594 -467.00821)
		(end 43.734482 -463.572098)
		(width 0.4572)
		(layer "In5.Cu")
		(net "PSU6_REMOTE_R2_P")
	)
	(segment
		(start 27.640026 -461.029812)
		(end 27.640026 -460.277972)
		(width 0.4572)
		(layer "F.Cu")
		(net "PSU6_REMOTE_R2_N")
	)
	(segment
		(start 72.553576 -472.101672)
		(end 71.18096 -472.101672)
		(width 0.4572)
		(layer "F.Cu")
		(net "PSU6_REMOTE_R2_N")
	)
	(via
		(at 71.18096 -472.101672)
		(size 0.508)
		(drill 0.254)
		(layers "F.Cu" "B.Cu")
		(net "PSU6_REMOTE_R2_N")
	)
	(via
		(at 27.640026 -460.277972)
		(size 0.508)
		(drill 0.254)
		(layers "F.Cu" "B.Cu")
		(net "PSU6_REMOTE_R2_N")
	)
	(segment
		(start 48.020224 -466.141054)
		(end 42.436034 -460.556864)
		(width 0.4572)
		(layer "In5.Cu")
		(net "PSU6_REMOTE_R2_N")
	)
	(segment
		(start 42.436034 -460.556864)
		(end 28.528518 -460.556864)
		(width 0.4572)
		(layer "In5.Cu")
		(net "PSU6_REMOTE_R2_N")
	)
	(segment
		(start 28.528518 -460.556864)
		(end 28.249626 -460.277972)
		(width 0.4572)
		(layer "In5.Cu")
		(net "PSU6_REMOTE_R2_N")
	)
	(segment
		(start 28.249626 -460.277972)
		(end 27.640026 -460.277972)
		(width 0.4572)
		(layer "In5.Cu")
		(net "PSU6_REMOTE_R2_N")
	)
	(segment
		(start 71.18096 -472.101672)
		(end 70.87616 -472.406472)
		(width 0.4572)
		(layer "In5.Cu")
		(net "PSU6_REMOTE_R2_N")
	)
	(segment
		(start 59.212734 -466.141054)
		(end 48.020224 -466.141054)
		(width 0.4572)
		(layer "In5.Cu")
		(net "PSU6_REMOTE_R2_N")
	)
	(segment
		(start 65.478152 -472.406472)
		(end 59.212734 -466.141054)
		(width 0.4572)
		(layer "In5.Cu")
		(net "PSU6_REMOTE_R2_N")
	)
	(segment
		(start 70.87616 -472.406472)
		(end 65.478152 -472.406472)
		(width 0.4572)
		(layer "In5.Cu")
		(net "PSU6_REMOTE_R2_N")
	)
	(segment
		(start 27.577796 -372.632478)
		(end 27.577796 -371.700806)
		(width 0.4572)
		(layer "F.Cu")
		(net "PSU5_REMOTE_R2_N")
	)
	(segment
		(start 77.593444 -384.526282)
		(end 76.640436 -384.526282)
		(width 0.4572)
		(layer "F.Cu")
		(net "PSU5_REMOTE_R2_N")
	)
	(via
		(at 76.640436 -384.526282)
		(size 0.508)
		(drill 0.254)
		(layers "F.Cu" "B.Cu")
		(net "PSU5_REMOTE_R2_N")
	)
	(via
		(at 27.577796 -371.700806)
		(size 0.508)
		(drill 0.254)
		(layers "F.Cu" "B.Cu")
		(net "PSU5_REMOTE_R2_N")
	)
	(segment
		(start 38.619176 -374.378728)
		(end 38.272466 -374.725438)
		(width 0.4572)
		(layer "In5.Cu")
		(net "PSU5_REMOTE_R2_N")
	)
	(segment
		(start 42.217594 -374.378728)
		(end 38.619176 -374.378728)
		(width 0.4572)
		(layer "In5.Cu")
		(net "PSU5_REMOTE_R2_N")
	)
	(segment
		(start 31.990284 -372.102888)
		(end 28.965652 -372.102888)
		(width 0.4572)
		(layer "In5.Cu")
		(net "PSU5_REMOTE_R2_N")
	)
	(segment
		(start 34.612834 -374.725438)
		(end 31.990284 -372.102888)
		(width 0.4572)
		(layer "In5.Cu")
		(net "PSU5_REMOTE_R2_N")
	)
	(segment
		(start 63.145162 -385.475734)
		(end 56.379364 -378.709936)
		(width 0.4572)
		(layer "In5.Cu")
		(net "PSU5_REMOTE_R2_N")
	)
	(segment
		(start 56.379364 -378.709936)
		(end 46.548802 -378.709936)
		(width 0.4572)
		(layer "In5.Cu")
		(net "PSU5_REMOTE_R2_N")
	)
	(segment
		(start 28.965652 -372.102888)
		(end 27.577796 -371.700806)
		(width 0.4572)
		(layer "In5.Cu")
		(net "PSU5_REMOTE_R2_N")
	)
	(segment
		(start 46.548802 -378.709936)
		(end 42.217594 -374.378728)
		(width 0.4572)
		(layer "In5.Cu")
		(net "PSU5_REMOTE_R2_N")
	)
	(segment
		(start 75.690984 -385.475734)
		(end 63.145162 -385.475734)
		(width 0.4572)
		(layer "In5.Cu")
		(net "PSU5_REMOTE_R2_N")
	)
	(segment
		(start 38.272466 -374.725438)
		(end 34.612834 -374.725438)
		(width 0.4572)
		(layer "In5.Cu")
		(net "PSU5_REMOTE_R2_N")
	)
	(segment
		(start 76.640436 -384.526282)
		(end 75.690984 -385.475734)
		(width 0.4572)
		(layer "In5.Cu")
		(net "PSU5_REMOTE_R2_N")
	)
	(segment
		(start 39.577264 -375.189496)
		(end 40.440864 -375.189496)
		(width 0.4572)
		(layer "F.Cu")
		(net "PSU5_REMOTE_R2_P")
	)
	(segment
		(start 77.662024 -387.197854)
		(end 76.775818 -387.197854)
		(width 0.4572)
		(layer "F.Cu")
		(net "PSU5_REMOTE_R2_P")
	)
	(via
		(at 76.775818 -387.197854)
		(size 0.508)
		(drill 0.254)
		(layers "F.Cu" "B.Cu")
		(net "PSU5_REMOTE_R2_P")
	)
	(via
		(at 40.440864 -375.189496)
		(size 0.508)
		(drill 0.254)
		(layers "F.Cu" "B.Cu")
		(net "PSU5_REMOTE_R2_P")
	)
	(segment
		(start 56.164226 -379.641354)
		(end 62.80912 -386.286248)
		(width 0.4572)
		(layer "In5.Cu")
		(net "PSU5_REMOTE_R2_P")
	)
	(segment
		(start 62.80912 -386.286248)
		(end 75.864212 -386.286248)
		(width 0.4572)
		(layer "In5.Cu")
		(net "PSU5_REMOTE_R2_P")
	)
	(segment
		(start 75.864212 -386.286248)
		(end 76.775818 -387.197854)
		(width 0.4572)
		(layer "In5.Cu")
		(net "PSU5_REMOTE_R2_P")
	)
	(segment
		(start 46.177962 -379.641354)
		(end 56.164226 -379.641354)
		(width 0.4572)
		(layer "In5.Cu")
		(net "PSU5_REMOTE_R2_P")
	)
	(segment
		(start 41.726104 -375.189496)
		(end 46.177962 -379.641354)
		(width 0.4572)
		(layer "In5.Cu")
		(net "PSU5_REMOTE_R2_P")
	)
	(segment
		(start 40.440864 -375.189496)
		(end 41.726104 -375.189496)
		(width 0.4572)
		(layer "In5.Cu")
		(net "PSU5_REMOTE_R2_P")
	)
	(segment
		(start 39.436802 -286.77743)
		(end 40.247824 -286.77743)
		(width 0.4572)
		(layer "F.Cu")
		(net "PSU4_REMOTE_R2_P")
	)
	(segment
		(start 80.546956 -297.892216)
		(end 79.425292 -297.892216)
		(width 0.4572)
		(layer "F.Cu")
		(net "PSU4_REMOTE_R2_P")
	)
	(via
		(at 79.425292 -297.892216)
		(size 0.508)
		(drill 0.254)
		(layers "F.Cu" "B.Cu")
		(net "PSU4_REMOTE_R2_P")
	)
	(via
		(at 40.247824 -286.77743)
		(size 0.508)
		(drill 0.254)
		(layers "F.Cu" "B.Cu")
		(net "PSU4_REMOTE_R2_P")
	)
	(segment
		(start 41.414192 -287.943798)
		(end 51.032918 -287.943798)
		(width 0.4572)
		(layer "In2.Cu")
		(net "PSU4_REMOTE_R2_P")
	)
	(segment
		(start 78.45425 -296.921174)
		(end 79.425292 -297.892216)
		(width 0.4572)
		(layer "In2.Cu")
		(net "PSU4_REMOTE_R2_P")
	)
	(segment
		(start 60.010294 -296.921174)
		(end 78.45425 -296.921174)
		(width 0.4572)
		(layer "In2.Cu")
		(net "PSU4_REMOTE_R2_P")
	)
	(segment
		(start 40.247824 -286.77743)
		(end 41.414192 -287.943798)
		(width 0.4572)
		(layer "In2.Cu")
		(net "PSU4_REMOTE_R2_P")
	)
	(segment
		(start 51.032918 -287.943798)
		(end 60.010294 -296.921174)
		(width 0.4572)
		(layer "In2.Cu")
		(net "PSU4_REMOTE_R2_P")
	)
	(segment
		(start 27.774392 -284.22981)
		(end 28.575762 -283.42844)
		(width 0.4572)
		(layer "F.Cu")
		(net "PSU4_REMOTE_R2_N")
	)
	(segment
		(start 80.532732 -295.215564)
		(end 79.381858 -295.215564)
		(width 0.4572)
		(layer "F.Cu")
		(net "PSU4_REMOTE_R2_N")
	)
	(segment
		(start 27.640026 -284.22981)
		(end 27.774392 -284.22981)
		(width 0.4572)
		(layer "F.Cu")
		(net "PSU4_REMOTE_R2_N")
	)
	(via
		(at 79.381858 -295.215564)
		(size 0.508)
		(drill 0.254)
		(layers "F.Cu" "B.Cu")
		(net "PSU4_REMOTE_R2_N")
	)
	(via
		(at 28.575762 -283.42844)
		(size 0.508)
		(drill 0.254)
		(layers "F.Cu" "B.Cu")
		(net "PSU4_REMOTE_R2_N")
	)
	(segment
		(start 41.46042 -286.883348)
		(end 40.371014 -285.793942)
		(width 0.4572)
		(layer "In2.Cu")
		(net "PSU4_REMOTE_R2_N")
	)
	(segment
		(start 78.659736 -295.937686)
		(end 60.41771 -295.937686)
		(width 0.4572)
		(layer "In2.Cu")
		(net "PSU4_REMOTE_R2_N")
	)
	(segment
		(start 32.01289 -283.713428)
		(end 28.86075 -283.713428)
		(width 0.4572)
		(layer "In2.Cu")
		(net "PSU4_REMOTE_R2_N")
	)
	(segment
		(start 60.41771 -295.937686)
		(end 51.363372 -286.883348)
		(width 0.4572)
		(layer "In2.Cu")
		(net "PSU4_REMOTE_R2_N")
	)
	(segment
		(start 79.381858 -295.215564)
		(end 78.659736 -295.937686)
		(width 0.4572)
		(layer "In2.Cu")
		(net "PSU4_REMOTE_R2_N")
	)
	(segment
		(start 38.142164 -285.793942)
		(end 37.686996 -286.24911)
		(width 0.4572)
		(layer "In2.Cu")
		(net "PSU4_REMOTE_R2_N")
	)
	(segment
		(start 51.363372 -286.883348)
		(end 41.46042 -286.883348)
		(width 0.4572)
		(layer "In2.Cu")
		(net "PSU4_REMOTE_R2_N")
	)
	(segment
		(start 40.371014 -285.793942)
		(end 38.142164 -285.793942)
		(width 0.4572)
		(layer "In2.Cu")
		(net "PSU4_REMOTE_R2_N")
	)
	(segment
		(start 28.86075 -283.713428)
		(end 28.575762 -283.42844)
		(width 0.4572)
		(layer "In2.Cu")
		(net "PSU4_REMOTE_R2_N")
	)
	(segment
		(start 37.686996 -286.24911)
		(end 34.548572 -286.24911)
		(width 0.4572)
		(layer "In2.Cu")
		(net "PSU4_REMOTE_R2_N")
	)
	(segment
		(start 34.548572 -286.24911)
		(end 32.01289 -283.713428)
		(width 0.4572)
		(layer "In2.Cu")
		(net "PSU4_REMOTE_R2_N")
	)
	(segment
		(start 28.183078 -195.834254)
		(end 28.660344 -195.356988)
		(width 0.4572)
		(layer "F.Cu")
		(net "PSU3_REMOTE_R2_N")
	)
	(segment
		(start 64.944498 -206.296768)
		(end 66.335402 -206.296768)
		(width 0.4572)
		(layer "F.Cu")
		(net "PSU3_REMOTE_R2_N")
	)
	(segment
		(start 27.334718 -195.834254)
		(end 28.183078 -195.834254)
		(width 0.4572)
		(layer "F.Cu")
		(net "PSU3_REMOTE_R2_N")
	)
	(segment
		(start 66.335402 -206.296768)
		(end 66.34099 -206.29118)
		(width 0.4572)
		(layer "F.Cu")
		(net "PSU3_REMOTE_R2_N")
	)
	(via
		(at 64.944498 -206.296768)
		(size 0.508)
		(drill 0.254)
		(layers "F.Cu" "B.Cu")
		(net "PSU3_REMOTE_R2_N")
	)
	(via
		(at 28.660344 -195.356988)
		(size 0.508)
		(drill 0.254)
		(layers "F.Cu" "B.Cu")
		(net "PSU3_REMOTE_R2_N")
	)
	(segment
		(start 37.968682 -197.881494)
		(end 38.336982 -197.513194)
		(width 0.4572)
		(layer "In5.Cu")
		(net "PSU3_REMOTE_R2_N")
	)
	(segment
		(start 64.222122 -207.019144)
		(end 64.944498 -206.296768)
		(width 0.4572)
		(layer "In5.Cu")
		(net "PSU3_REMOTE_R2_N")
	)
	(segment
		(start 54.801008 -201.782934)
		(end 60.037218 -207.019144)
		(width 0.4572)
		(layer "In5.Cu")
		(net "PSU3_REMOTE_R2_N")
	)
	(segment
		(start 38.336982 -197.513194)
		(end 45.033946 -197.513194)
		(width 0.4572)
		(layer "In5.Cu")
		(net "PSU3_REMOTE_R2_N")
	)
	(segment
		(start 49.303686 -201.782934)
		(end 54.801008 -201.782934)
		(width 0.4572)
		(layer "In5.Cu")
		(net "PSU3_REMOTE_R2_N")
	)
	(segment
		(start 45.033946 -197.513194)
		(end 49.303686 -201.782934)
		(width 0.4572)
		(layer "In5.Cu")
		(net "PSU3_REMOTE_R2_N")
	)
	(segment
		(start 60.037218 -207.019144)
		(end 64.222122 -207.019144)
		(width 0.4572)
		(layer "In5.Cu")
		(net "PSU3_REMOTE_R2_N")
	)
	(segment
		(start 32.41675 -195.356988)
		(end 34.941256 -197.881494)
		(width 0.4572)
		(layer "In5.Cu")
		(net "PSU3_REMOTE_R2_N")
	)
	(segment
		(start 28.660344 -195.356988)
		(end 32.41675 -195.356988)
		(width 0.4572)
		(layer "In5.Cu")
		(net "PSU3_REMOTE_R2_N")
	)
	(segment
		(start 34.941256 -197.881494)
		(end 37.968682 -197.881494)
		(width 0.4572)
		(layer "In5.Cu")
		(net "PSU3_REMOTE_R2_N")
	)
	(segment
		(start 39.460424 -198.369428)
		(end 40.374824 -198.369428)
		(width 0.4572)
		(layer "F.Cu")
		(net "PSU3_REMOTE_R2_P")
	)
	(segment
		(start 66.294762 -209.201004)
		(end 66.30035 -209.195416)
		(width 0.4572)
		(layer "F.Cu")
		(net "PSU3_REMOTE_R2_P")
	)
	(segment
		(start 64.982598 -209.201004)
		(end 66.294762 -209.201004)
		(width 0.4572)
		(layer "F.Cu")
		(net "PSU3_REMOTE_R2_P")
	)
	(via
		(at 64.982598 -209.201004)
		(size 0.508)
		(drill 0.254)
		(layers "F.Cu" "B.Cu")
		(net "PSU3_REMOTE_R2_P")
	)
	(via
		(at 40.374824 -198.369428)
		(size 0.508)
		(drill 0.254)
		(layers "F.Cu" "B.Cu")
		(net "PSU3_REMOTE_R2_P")
	)
	(segment
		(start 60.25769 -208.450688)
		(end 54.535578 -202.728576)
		(width 0.4572)
		(layer "In5.Cu")
		(net "PSU3_REMOTE_R2_P")
	)
	(segment
		(start 64.232282 -208.450688)
		(end 60.25769 -208.450688)
		(width 0.4572)
		(layer "In5.Cu")
		(net "PSU3_REMOTE_R2_P")
	)
	(segment
		(start 44.466764 -198.369428)
		(end 40.374824 -198.369428)
		(width 0.4572)
		(layer "In5.Cu")
		(net "PSU3_REMOTE_R2_P")
	)
	(segment
		(start 54.535578 -202.728576)
		(end 48.825912 -202.728576)
		(width 0.4572)
		(layer "In5.Cu")
		(net "PSU3_REMOTE_R2_P")
	)
	(segment
		(start 64.982598 -209.201004)
		(end 64.232282 -208.450688)
		(width 0.4572)
		(layer "In5.Cu")
		(net "PSU3_REMOTE_R2_P")
	)
	(segment
		(start 48.825912 -202.728576)
		(end 44.466764 -198.369428)
		(width 0.4572)
		(layer "In5.Cu")
		(net "PSU3_REMOTE_R2_P")
	)
	(segment
		(start 39.458392 -109.974126)
		(end 40.336978 -109.974126)
		(width 0.4572)
		(layer "F.Cu")
		(net "PSU2_REMOTE_R2_P")
	)
	(segment
		(start 68.29679 -120.31472)
		(end 68.297552 -120.313958)
		(width 0.4572)
		(layer "F.Cu")
		(net "PSU2_REMOTE_R2_P")
	)
	(segment
		(start 67.497198 -120.31472)
		(end 68.29679 -120.31472)
		(width 0.4572)
		(layer "F.Cu")
		(net "PSU2_REMOTE_R2_P")
	)
	(via
		(at 67.497198 -120.31472)
		(size 0.508)
		(drill 0.254)
		(layers "F.Cu" "B.Cu")
		(net "PSU2_REMOTE_R2_P")
	)
	(via
		(at 40.336978 -109.974126)
		(size 0.508)
		(drill 0.254)
		(layers "F.Cu" "B.Cu")
		(net "PSU2_REMOTE_R2_P")
	)
	(segment
		(start 40.336978 -109.974126)
		(end 55.82539 -109.974126)
		(width 0.508)
		(layer "In5.Cu")
		(net "PSU2_REMOTE_R2_P")
	)
	(segment
		(start 65.311274 -119.46001)
		(end 66.642488 -119.46001)
		(width 0.508)
		(layer "In5.Cu")
		(net "PSU2_REMOTE_R2_P")
	)
	(segment
		(start 55.82539 -109.974126)
		(end 65.311274 -119.46001)
		(width 0.508)
		(layer "In5.Cu")
		(net "PSU2_REMOTE_R2_P")
	)
	(segment
		(start 66.642488 -119.46001)
		(end 67.497198 -120.31472)
		(width 0.508)
		(layer "In5.Cu")
		(net "PSU2_REMOTE_R2_P")
	)
	(segment
		(start 68.315332 -117.627908)
		(end 68.316094 -117.627146)
		(width 0.4572)
		(layer "F.Cu")
		(net "PSU2_REMOTE_R2_N")
	)
	(segment
		(start 67.493388 -117.627908)
		(end 68.315332 -117.627908)
		(width 0.4572)
		(layer "F.Cu")
		(net "PSU2_REMOTE_R2_N")
	)
	(segment
		(start 28.198318 -106.569764)
		(end 27.347672 -107.42041)
		(width 0.4572)
		(layer "F.Cu")
		(net "PSU2_REMOTE_R2_N")
	)
	(segment
		(start 27.347672 -107.42041)
		(end 27.347672 -107.430316)
		(width 0.4572)
		(layer "F.Cu")
		(net "PSU2_REMOTE_R2_N")
	)
	(via
		(at 28.198318 -106.569764)
		(size 0.508)
		(drill 0.254)
		(layers "F.Cu" "B.Cu")
		(net "PSU2_REMOTE_R2_N")
	)
	(via
		(at 67.493388 -117.627908)
		(size 0.508)
		(drill 0.254)
		(layers "F.Cu" "B.Cu")
		(net "PSU2_REMOTE_R2_N")
	)
	(segment
		(start 37.627306 -109.519466)
		(end 38.228778 -108.917994)
		(width 0.508)
		(layer "In5.Cu")
		(net "PSU2_REMOTE_R2_N")
	)
	(segment
		(start 56.263032 -108.917994)
		(end 65.772284 -118.427246)
		(width 0.508)
		(layer "In5.Cu")
		(net "PSU2_REMOTE_R2_N")
	)
	(segment
		(start 65.772284 -118.427246)
		(end 66.69405 -118.427246)
		(width 0.508)
		(layer "In5.Cu")
		(net "PSU2_REMOTE_R2_N")
	)
	(segment
		(start 29.846524 -109.519466)
		(end 37.627306 -109.519466)
		(width 0.508)
		(layer "In5.Cu")
		(net "PSU2_REMOTE_R2_N")
	)
	(segment
		(start 28.198318 -106.569764)
		(end 28.198318 -107.87126)
		(width 0.508)
		(layer "In5.Cu")
		(net "PSU2_REMOTE_R2_N")
	)
	(segment
		(start 66.69405 -118.427246)
		(end 67.493388 -117.627908)
		(width 0.508)
		(layer "In5.Cu")
		(net "PSU2_REMOTE_R2_N")
	)
	(segment
		(start 28.198318 -107.87126)
		(end 29.846524 -109.519466)
		(width 0.508)
		(layer "In5.Cu")
		(net "PSU2_REMOTE_R2_N")
	)
	(segment
		(start 38.228778 -108.917994)
		(end 56.263032 -108.917994)
		(width 0.508)
		(layer "In5.Cu")
		(net "PSU2_REMOTE_R2_N")
	)
	(segment
		(start 27.244802 -19.06397)
		(end 27.244802 -18.349976)
		(width 0.1524)
		(layer "F.Cu")
		(net "PSU1_REMOTE_R2_N")
	)
	(segment
		(start 66.491866 -29.351986)
		(end 65.30975 -29.351986)
		(width 0.4572)
		(layer "F.Cu")
		(net "PSU1_REMOTE_R2_N")
	)
	(via
		(at 65.30975 -29.351986)
		(size 0.508)
		(drill 0.254)
		(layers "F.Cu" "B.Cu")
		(net "PSU1_REMOTE_R2_N")
	)
	(via
		(at 27.244802 -18.349976)
		(size 0.508)
		(drill 0.254)
		(layers "F.Cu" "B.Cu")
		(net "PSU1_REMOTE_R2_N")
	)
	(segment
		(start 65.30975 -29.351986)
		(end 64.282066 -30.37967)
		(width 0.4572)
		(layer "In5.Cu")
		(net "PSU1_REMOTE_R2_N")
	)
	(segment
		(start 64.282066 -30.37967)
		(end 60.4012 -30.37967)
		(width 0.4572)
		(layer "In5.Cu")
		(net "PSU1_REMOTE_R2_N")
	)
	(segment
		(start 28.78963 -18.349976)
		(end 27.244802 -18.349976)
		(width 0.4572)
		(layer "In5.Cu")
		(net "PSU1_REMOTE_R2_N")
	)
	(segment
		(start 29.044392 -18.604738)
		(end 28.78963 -18.349976)
		(width 0.4572)
		(layer "In5.Cu")
		(net "PSU1_REMOTE_R2_N")
	)
	(segment
		(start 32.470344 -18.604738)
		(end 29.044392 -18.604738)
		(width 0.4572)
		(layer "In5.Cu")
		(net "PSU1_REMOTE_R2_N")
	)
	(segment
		(start 34.914332 -21.048726)
		(end 32.470344 -18.604738)
		(width 0.4572)
		(layer "In5.Cu")
		(net "PSU1_REMOTE_R2_N")
	)
	(segment
		(start 60.4012 -30.37967)
		(end 50.78857 -20.76704)
		(width 0.4572)
		(layer "In5.Cu")
		(net "PSU1_REMOTE_R2_N")
	)
	(segment
		(start 50.78857 -20.76704)
		(end 39.637716 -20.76704)
		(width 0.4572)
		(layer "In5.Cu")
		(net "PSU1_REMOTE_R2_N")
	)
	(segment
		(start 39.637716 -20.76704)
		(end 39.35603 -21.048726)
		(width 0.4572)
		(layer "In5.Cu")
		(net "PSU1_REMOTE_R2_N")
	)
	(segment
		(start 39.35603 -21.048726)
		(end 34.914332 -21.048726)
		(width 0.4572)
		(layer "In5.Cu")
		(net "PSU1_REMOTE_R2_N")
	)
	(segment
		(start 39.462964 -21.594318)
		(end 40.360854 -21.594318)
		(width 0.4572)
		(layer "F.Cu")
		(net "PSU1_REMOTE_R2_P")
	)
	(segment
		(start 66.42989 -32.569912)
		(end 66.417698 -32.582104)
		(width 0.4572)
		(layer "F.Cu")
		(net "PSU1_REMOTE_R2_P")
	)
	(segment
		(start 66.417698 -32.582104)
		(end 65.264538 -32.582104)
		(width 0.4572)
		(layer "F.Cu")
		(net "PSU1_REMOTE_R2_P")
	)
	(via
		(at 40.360854 -21.594318)
		(size 0.508)
		(drill 0.254)
		(layers "F.Cu" "B.Cu")
		(net "PSU1_REMOTE_R2_P")
	)
	(via
		(at 65.264538 -32.582104)
		(size 0.508)
		(drill 0.254)
		(layers "F.Cu" "B.Cu")
		(net "PSU1_REMOTE_R2_P")
	)
	(segment
		(start 63.889382 -31.206948)
		(end 65.264538 -32.582104)
		(width 0.4572)
		(layer "In5.Cu")
		(net "PSU1_REMOTE_R2_P")
	)
	(segment
		(start 50.44567 -21.594318)
		(end 60.0583 -31.206948)
		(width 0.4572)
		(layer "In5.Cu")
		(net "PSU1_REMOTE_R2_P")
	)
	(segment
		(start 40.360854 -21.594318)
		(end 50.44567 -21.594318)
		(width 0.4572)
		(layer "In5.Cu")
		(net "PSU1_REMOTE_R2_P")
	)
	(segment
		(start 60.0583 -31.206948)
		(end 63.889382 -31.206948)
		(width 0.4572)
		(layer "In5.Cu")
		(net "PSU1_REMOTE_R2_P")
	)
	(segment
		(start 44.837858 -253.125732)
		(end 46.025562 -253.125732)
		(width 0.4572)
		(layer "F.Cu")
		(net "PSU6_REMOTE_R_N")
	)
	(segment
		(start 44.564046 -253.399544)
		(end 44.837858 -253.125732)
		(width 0.4572)
		(layer "F.Cu")
		(net "PSU6_REMOTE_R_N")
	)
	(segment
		(start 27.640026 -462.630012)
		(end 27.640026 -463.41538)
		(width 0.4572)
		(layer "F.Cu")
		(net "PSU6_REMOTE_R_N")
	)
	(segment
		(start 44.564046 -253.40564)
		(end 44.564046 -253.399544)
		(width 0.4572)
		(layer "F.Cu")
		(net "PSU6_REMOTE_R_N")
	)
	(via
		(at 44.564046 -253.40564)
		(size 0.508)
		(drill 0.254)
		(layers "F.Cu" "B.Cu")
		(net "PSU6_REMOTE_R_N")
	)
	(via
		(at 16.148558 -258.85521)
		(size 0.508)
		(drill 0.254)
		(layers "F.Cu" "B.Cu")
		(net "PSU6_REMOTE_R_N")
	)
	(via
		(at 27.640026 -463.41538)
		(size 0.508)
		(drill 0.254)
		(layers "F.Cu" "B.Cu")
		(net "PSU6_REMOTE_R_N")
	)
	(segment
		(start 25.335738 -288.632646)
		(end 21.314156 -284.611064)
		(width 0.4572)
		(layer "B.Cu")
		(net "PSU6_REMOTE_R_N")
	)
	(segment
		(start 27.640026 -463.41538)
		(end 26.049986 -461.82534)
		(width 0.4572)
		(layer "B.Cu")
		(net "PSU6_REMOTE_R_N")
	)
	(segment
		(start 24.827484 -441.004452)
		(end 24.827484 -381.249428)
		(width 0.4572)
		(layer "B.Cu")
		(net "PSU6_REMOTE_R_N")
	)
	(segment
		(start 20.854924 -322.816982)
		(end 25.335738 -318.336168)
		(width 0.4572)
		(layer "B.Cu")
		(net "PSU6_REMOTE_R_N")
	)
	(segment
		(start 22.674326 -379.09627)
		(end 22.674326 -359.995724)
		(width 0.4572)
		(layer "B.Cu")
		(net "PSU6_REMOTE_R_N")
	)
	(segment
		(start 21.314156 -280.231342)
		(end 16.148558 -275.065744)
		(width 0.4572)
		(layer "B.Cu")
		(net "PSU6_REMOTE_R_N")
	)
	(segment
		(start 24.827484 -381.249428)
		(end 22.674326 -379.09627)
		(width 0.4572)
		(layer "B.Cu")
		(net "PSU6_REMOTE_R_N")
	)
	(segment
		(start 16.148558 -275.065744)
		(end 16.148558 -258.85521)
		(width 0.4572)
		(layer "B.Cu")
		(net "PSU6_REMOTE_R_N")
	)
	(segment
		(start 25.335738 -318.336168)
		(end 25.335738 -288.632646)
		(width 0.4572)
		(layer "B.Cu")
		(net "PSU6_REMOTE_R_N")
	)
	(segment
		(start 26.049986 -461.82534)
		(end 26.049986 -442.226954)
		(width 0.4572)
		(layer "B.Cu")
		(net "PSU6_REMOTE_R_N")
	)
	(segment
		(start 20.854924 -358.176322)
		(end 20.854924 -322.816982)
		(width 0.4572)
		(layer "B.Cu")
		(net "PSU6_REMOTE_R_N")
	)
	(segment
		(start 21.314156 -284.611064)
		(end 21.314156 -280.231342)
		(width 0.4572)
		(layer "B.Cu")
		(net "PSU6_REMOTE_R_N")
	)
	(segment
		(start 26.049986 -442.226954)
		(end 24.827484 -441.004452)
		(width 0.4572)
		(layer "B.Cu")
		(net "PSU6_REMOTE_R_N")
	)
	(segment
		(start 22.674326 -359.995724)
		(end 20.854924 -358.176322)
		(width 0.4572)
		(layer "B.Cu")
		(net "PSU6_REMOTE_R_N")
	)
	(segment
		(start 44.132754 -253.836932)
		(end 44.564046 -253.40564)
		(width 0.4572)
		(layer "In5.Cu")
		(net "PSU6_REMOTE_R_N")
	)
	(segment
		(start 28.947618 -253.836932)
		(end 44.132754 -253.836932)
		(width 0.4572)
		(layer "In5.Cu")
		(net "PSU6_REMOTE_R_N")
	)
	(segment
		(start 16.148558 -258.85521)
		(end 16.148558 -256.048764)
		(width 0.4572)
		(layer "In5.Cu")
		(net "PSU6_REMOTE_R_N")
	)
	(segment
		(start 16.148558 -256.048764)
		(end 19.025362 -253.17196)
		(width 0.4572)
		(layer "In5.Cu")
		(net "PSU6_REMOTE_R_N")
	)
	(segment
		(start 19.025362 -253.17196)
		(end 28.282646 -253.17196)
		(width 0.4572)
		(layer "In5.Cu")
		(net "PSU6_REMOTE_R_N")
	)
	(segment
		(start 28.282646 -253.17196)
		(end 28.947618 -253.836932)
		(width 0.4572)
		(layer "In5.Cu")
		(net "PSU6_REMOTE_R_N")
	)
	(segment
		(start 44.638468 -251.449332)
		(end 44.892468 -251.703332)
		(width 0.4572)
		(layer "F.Cu")
		(net "PSU6_REMOTE_R_P")
	)
	(segment
		(start 39.51478 -465.17052)
		(end 40.594788 -465.17052)
		(width 0.4572)
		(layer "F.Cu")
		(net "PSU6_REMOTE_R_P")
	)
	(segment
		(start 44.892468 -251.703332)
		(end 46.036738 -251.703332)
		(width 0.4572)
		(layer "F.Cu")
		(net "PSU6_REMOTE_R_P")
	)
	(via
		(at 15.44701 -258.832604)
		(size 0.508)
		(drill 0.254)
		(layers "F.Cu" "B.Cu")
		(net "PSU6_REMOTE_R_P")
	)
	(via
		(at 44.638468 -251.449332)
		(size 0.508)
		(drill 0.254)
		(layers "F.Cu" "B.Cu")
		(net "PSU6_REMOTE_R_P")
	)
	(via
		(at 40.594788 -465.17052)
		(size 0.508)
		(drill 0.254)
		(layers "F.Cu" "B.Cu")
		(net "PSU6_REMOTE_R_P")
	)
	(segment
		(start 37.480748 -465.71662)
		(end 38.026848 -465.17052)
		(width 0.4572)
		(layer "B.Cu")
		(net "PSU6_REMOTE_R_P")
	)
	(segment
		(start 25.38095 -445.840358)
		(end 24.359362 -446.861946)
		(width 0.4572)
		(layer "B.Cu")
		(net "PSU6_REMOTE_R_P")
	)
	(segment
		(start 25.38095 -442.88329)
		(end 25.38095 -445.840358)
		(width 0.4572)
		(layer "B.Cu")
		(net "PSU6_REMOTE_R_P")
	)
	(segment
		(start 24.359362 -461.92567)
		(end 28.150312 -465.71662)
		(width 0.4572)
		(layer "B.Cu")
		(net "PSU6_REMOTE_R_P")
	)
	(segment
		(start 21.972778 -379.3871)
		(end 24.167084 -381.581406)
		(width 0.4572)
		(layer "B.Cu")
		(net "PSU6_REMOTE_R_P")
	)
	(segment
		(start 15.44701 -275.356574)
		(end 20.612608 -280.522172)
		(width 0.4572)
		(layer "B.Cu")
		(net "PSU6_REMOTE_R_P")
	)
	(segment
		(start 20.153376 -358.467152)
		(end 21.972778 -360.286554)
		(width 0.4572)
		(layer "B.Cu")
		(net "PSU6_REMOTE_R_P")
	)
	(segment
		(start 20.612608 -284.901894)
		(end 24.63419 -288.923476)
		(width 0.4572)
		(layer "B.Cu")
		(net "PSU6_REMOTE_R_P")
	)
	(segment
		(start 20.612608 -280.522172)
		(end 20.612608 -284.901894)
		(width 0.4572)
		(layer "B.Cu")
		(net "PSU6_REMOTE_R_P")
	)
	(segment
		(start 24.359362 -446.861946)
		(end 24.359362 -461.92567)
		(width 0.4572)
		(layer "B.Cu")
		(net "PSU6_REMOTE_R_P")
	)
	(segment
		(start 15.44701 -258.832604)
		(end 15.44701 -275.356574)
		(width 0.4572)
		(layer "B.Cu")
		(net "PSU6_REMOTE_R_P")
	)
	(segment
		(start 24.167084 -441.669424)
		(end 25.38095 -442.88329)
		(width 0.4572)
		(layer "B.Cu")
		(net "PSU6_REMOTE_R_P")
	)
	(segment
		(start 24.167084 -381.581406)
		(end 24.167084 -441.669424)
		(width 0.4572)
		(layer "B.Cu")
		(net "PSU6_REMOTE_R_P")
	)
	(segment
		(start 21.972778 -360.286554)
		(end 21.972778 -379.3871)
		(width 0.4572)
		(layer "B.Cu")
		(net "PSU6_REMOTE_R_P")
	)
	(segment
		(start 28.150312 -465.71662)
		(end 37.480748 -465.71662)
		(width 0.4572)
		(layer "B.Cu")
		(net "PSU6_REMOTE_R_P")
	)
	(segment
		(start 24.63419 -318.045338)
		(end 20.153376 -322.526152)
		(width 0.4572)
		(layer "B.Cu")
		(net "PSU6_REMOTE_R_P")
	)
	(segment
		(start 24.63419 -288.923476)
		(end 24.63419 -318.045338)
		(width 0.4572)
		(layer "B.Cu")
		(net "PSU6_REMOTE_R_P")
	)
	(segment
		(start 38.026848 -465.17052)
		(end 40.594788 -465.17052)
		(width 0.4572)
		(layer "B.Cu")
		(net "PSU6_REMOTE_R_P")
	)
	(segment
		(start 20.153376 -322.526152)
		(end 20.153376 -358.467152)
		(width 0.4572)
		(layer "B.Cu")
		(net "PSU6_REMOTE_R_P")
	)
	(segment
		(start 18.683224 -252.510544)
		(end 28.147772 -252.510544)
		(width 0.4572)
		(layer "In5.Cu")
		(net "PSU6_REMOTE_R_P")
	)
	(segment
		(start 44.028868 -251.449332)
		(end 44.638468 -251.449332)
		(width 0.4572)
		(layer "In5.Cu")
		(net "PSU6_REMOTE_R_P")
	)
	(segment
		(start 28.147772 -252.510544)
		(end 29.493972 -251.164344)
		(width 0.4572)
		(layer "In5.Cu")
		(net "PSU6_REMOTE_R_P")
	)
	(segment
		(start 15.44701 -258.832604)
		(end 15.44701 -255.746758)
		(width 0.4572)
		(layer "In5.Cu")
		(net "PSU6_REMOTE_R_P")
	)
	(segment
		(start 43.74388 -251.164344)
		(end 44.028868 -251.449332)
		(width 0.4572)
		(layer "In5.Cu")
		(net "PSU6_REMOTE_R_P")
	)
	(segment
		(start 15.44701 -255.746758)
		(end 18.683224 -252.510544)
		(width 0.4572)
		(layer "In5.Cu")
		(net "PSU6_REMOTE_R_P")
	)
	(segment
		(start 29.493972 -251.164344)
		(end 43.74388 -251.164344)
		(width 0.4572)
		(layer "In5.Cu")
		(net "PSU6_REMOTE_R_P")
	)
	(segment
		(start 28.439618 -201.996294)
		(end 28.439618 -201.311002)
		(width 0.4572)
		(layer "F.Cu")
		(net "PSU3_REMOTE_R_N")
	)
	(segment
		(start 44.741846 -248.705116)
		(end 46.096428 -248.705116)
		(width 0.4572)
		(layer "F.Cu")
		(net "PSU3_REMOTE_R_N")
	)
	(segment
		(start 28.439618 -201.311002)
		(end 27.33421 -200.205594)
		(width 0.4572)
		(layer "F.Cu")
		(net "PSU3_REMOTE_R_N")
	)
	(segment
		(start 44.455588 -248.991374)
		(end 44.741846 -248.705116)
		(width 0.4572)
		(layer "F.Cu")
		(net "PSU3_REMOTE_R_N")
	)
	(segment
		(start 27.33421 -200.205594)
		(end 27.33421 -197.433946)
		(width 0.4572)
		(layer "F.Cu")
		(net "PSU3_REMOTE_R_N")
	)
	(via
		(at 44.455588 -248.991374)
		(size 0.508)
		(drill 0.254)
		(layers "F.Cu" "B.Cu")
		(net "PSU3_REMOTE_R_N")
	)
	(via
		(at 28.439618 -201.996294)
		(size 0.508)
		(drill 0.254)
		(layers "F.Cu" "B.Cu")
		(net "PSU3_REMOTE_R_N")
	)
	(via
		(at 26.063194 -246.94388)
		(size 0.508)
		(drill 0.254)
		(layers "F.Cu" "B.Cu")
		(net "PSU3_REMOTE_R_N")
	)
	(segment
		(start 28.439618 -201.996294)
		(end 25.205182 -205.23073)
		(width 0.4572)
		(layer "B.Cu")
		(net "PSU3_REMOTE_R_N")
	)
	(segment
		(start 25.205182 -246.085868)
		(end 26.063194 -246.94388)
		(width 0.4572)
		(layer "B.Cu")
		(net "PSU3_REMOTE_R_N")
	)
	(segment
		(start 25.205182 -205.23073)
		(end 25.205182 -246.085868)
		(width 0.4572)
		(layer "B.Cu")
		(net "PSU3_REMOTE_R_N")
	)
	(segment
		(start 26.063194 -247.560084)
		(end 27.226514 -248.723404)
		(width 0.4572)
		(layer "In5.Cu")
		(net "PSU3_REMOTE_R_N")
	)
	(segment
		(start 27.226514 -248.723404)
		(end 43.578018 -248.723404)
		(width 0.4572)
		(layer "In5.Cu")
		(net "PSU3_REMOTE_R_N")
	)
	(segment
		(start 43.845988 -248.991374)
		(end 44.455588 -248.991374)
		(width 0.4572)
		(layer "In5.Cu")
		(net "PSU3_REMOTE_R_N")
	)
	(segment
		(start 43.578018 -248.723404)
		(end 43.845988 -248.991374)
		(width 0.4572)
		(layer "In5.Cu")
		(net "PSU3_REMOTE_R_N")
	)
	(segment
		(start 26.063194 -246.94388)
		(end 26.063194 -247.560084)
		(width 0.4572)
		(layer "In5.Cu")
		(net "PSU3_REMOTE_R_N")
	)
	(segment
		(start 44.754546 -247.282716)
		(end 46.072806 -247.282716)
		(width 0.4572)
		(layer "F.Cu")
		(net "PSU3_REMOTE_R_P")
	)
	(segment
		(start 40.399462 -199.96912)
		(end 39.461948 -199.96912)
		(width 0.4572)
		(layer "F.Cu")
		(net "PSU3_REMOTE_R_P")
	)
	(segment
		(start 44.48429 -247.01246)
		(end 44.754546 -247.282716)
		(width 0.4572)
		(layer "F.Cu")
		(net "PSU3_REMOTE_R_P")
	)
	(via
		(at 40.399462 -199.96912)
		(size 0.508)
		(drill 0.254)
		(layers "F.Cu" "B.Cu")
		(net "PSU3_REMOTE_R_P")
	)
	(via
		(at 26.77033 -246.89816)
		(size 0.508)
		(drill 0.254)
		(layers "F.Cu" "B.Cu")
		(net "PSU3_REMOTE_R_P")
	)
	(via
		(at 44.48429 -247.01246)
		(size 0.508)
		(drill 0.254)
		(layers "F.Cu" "B.Cu")
		(net "PSU3_REMOTE_R_P")
	)
	(segment
		(start 25.865582 -207.066896)
		(end 25.865582 -245.721886)
		(width 0.4572)
		(layer "B.Cu")
		(net "PSU3_REMOTE_R_P")
	)
	(segment
		(start 29.925264 -203.007214)
		(end 25.865582 -207.066896)
		(width 0.4572)
		(layer "B.Cu")
		(net "PSU3_REMOTE_R_P")
	)
	(segment
		(start 25.865582 -245.721886)
		(end 26.77033 -246.626634)
		(width 0.4572)
		(layer "B.Cu")
		(net "PSU3_REMOTE_R_P")
	)
	(segment
		(start 26.77033 -246.626634)
		(end 26.77033 -246.89816)
		(width 0.4572)
		(layer "B.Cu")
		(net "PSU3_REMOTE_R_P")
	)
	(segment
		(start 40.399462 -199.96912)
		(end 37.361368 -203.007214)
		(width 0.4572)
		(layer "B.Cu")
		(net "PSU3_REMOTE_R_P")
	)
	(segment
		(start 37.361368 -203.007214)
		(end 29.925264 -203.007214)
		(width 0.4572)
		(layer "B.Cu")
		(net "PSU3_REMOTE_R_P")
	)
	(segment
		(start 28.752546 -246.89816)
		(end 29.459682 -246.191024)
		(width 0.4572)
		(layer "In5.Cu")
		(net "PSU3_REMOTE_R_P")
	)
	(segment
		(start 26.77033 -246.89816)
		(end 28.752546 -246.89816)
		(width 0.4572)
		(layer "In5.Cu")
		(net "PSU3_REMOTE_R_P")
	)
	(segment
		(start 43.662854 -246.191024)
		(end 44.48429 -247.01246)
		(width 0.4572)
		(layer "In5.Cu")
		(net "PSU3_REMOTE_R_P")
	)
	(segment
		(start 29.459682 -246.191024)
		(end 43.662854 -246.191024)
		(width 0.4572)
		(layer "In5.Cu")
		(net "PSU3_REMOTE_R_P")
	)
	(segment
		(start 44.592494 -242.814856)
		(end 44.873672 -243.096034)
		(width 0.4572)
		(layer "F.Cu")
		(net "PSU2_REMOTE_R_P")
	)
	(segment
		(start 39.459154 -111.574072)
		(end 40.390826 -111.574072)
		(width 0.4572)
		(layer "F.Cu")
		(net "PSU2_REMOTE_R_P")
	)
	(segment
		(start 44.873672 -243.096034)
		(end 46.00829 -243.096034)
		(width 0.4572)
		(layer "F.Cu")
		(net "PSU2_REMOTE_R_P")
	)
	(via
		(at 44.592494 -242.814856)
		(size 0.508)
		(drill 0.254)
		(layers "F.Cu" "B.Cu")
		(net "PSU2_REMOTE_R_P")
	)
	(via
		(at 40.390826 -111.574072)
		(size 0.508)
		(drill 0.254)
		(layers "F.Cu" "B.Cu")
		(net "PSU2_REMOTE_R_P")
	)
	(segment
		(start 43.223688 -201.347578)
		(end 36.439348 -208.131918)
		(width 0.4572)
		(layer "B.Cu")
		(net "PSU2_REMOTE_R_P")
	)
	(segment
		(start 37.994082 -180.369972)
		(end 37.994082 -186.244738)
		(width 0.4572)
		(layer "B.Cu")
		(net "PSU2_REMOTE_R_P")
	)
	(segment
		(start 27.186382 -238.468916)
		(end 29.882592 -241.165126)
		(width 0.4572)
		(layer "B.Cu")
		(net "PSU2_REMOTE_R_P")
	)
	(segment
		(start 40.02659 -111.938308)
		(end 30.178756 -111.938308)
		(width 0.4572)
		(layer "B.Cu")
		(net "PSU2_REMOTE_R_P")
	)
	(segment
		(start 37.994082 -186.244738)
		(end 43.223688 -191.474344)
		(width 0.4572)
		(layer "B.Cu")
		(net "PSU2_REMOTE_R_P")
	)
	(segment
		(start 26.81224 -115.304824)
		(end 26.81224 -172.699426)
		(width 0.4572)
		(layer "B.Cu")
		(net "PSU2_REMOTE_R_P")
	)
	(segment
		(start 33.143698 -179.030884)
		(end 36.654994 -179.030884)
		(width 0.4572)
		(layer "B.Cu")
		(net "PSU2_REMOTE_R_P")
	)
	(segment
		(start 36.654994 -179.030884)
		(end 37.994082 -180.369972)
		(width 0.4572)
		(layer "B.Cu")
		(net "PSU2_REMOTE_R_P")
	)
	(segment
		(start 29.191966 -208.131918)
		(end 27.186382 -210.137502)
		(width 0.4572)
		(layer "B.Cu")
		(net "PSU2_REMOTE_R_P")
	)
	(segment
		(start 27.186382 -210.137502)
		(end 27.186382 -238.468916)
		(width 0.4572)
		(layer "B.Cu")
		(net "PSU2_REMOTE_R_P")
	)
	(segment
		(start 44.158916 -243.248434)
		(end 44.592494 -242.814856)
		(width 0.4572)
		(layer "B.Cu")
		(net "PSU2_REMOTE_R_P")
	)
	(segment
		(start 43.223688 -191.474344)
		(end 43.223688 -201.347578)
		(width 0.4572)
		(layer "B.Cu")
		(net "PSU2_REMOTE_R_P")
	)
	(segment
		(start 40.390826 -111.574072)
		(end 40.02659 -111.938308)
		(width 0.4572)
		(layer "B.Cu")
		(net "PSU2_REMOTE_R_P")
	)
	(segment
		(start 30.178756 -111.938308)
		(end 26.81224 -115.304824)
		(width 0.4572)
		(layer "B.Cu")
		(net "PSU2_REMOTE_R_P")
	)
	(segment
		(start 36.754816 -241.165126)
		(end 38.838124 -243.248434)
		(width 0.4572)
		(layer "B.Cu")
		(net "PSU2_REMOTE_R_P")
	)
	(segment
		(start 38.838124 -243.248434)
		(end 44.158916 -243.248434)
		(width 0.4572)
		(layer "B.Cu")
		(net "PSU2_REMOTE_R_P")
	)
	(segment
		(start 29.882592 -241.165126)
		(end 36.754816 -241.165126)
		(width 0.4572)
		(layer "B.Cu")
		(net "PSU2_REMOTE_R_P")
	)
	(segment
		(start 36.439348 -208.131918)
		(end 29.191966 -208.131918)
		(width 0.4572)
		(layer "B.Cu")
		(net "PSU2_REMOTE_R_P")
	)
	(segment
		(start 26.81224 -172.699426)
		(end 33.143698 -179.030884)
		(width 0.4572)
		(layer "B.Cu")
		(net "PSU2_REMOTE_R_P")
	)
	(segment
		(start 44.748196 -244.518434)
		(end 45.985684 -244.518434)
		(width 0.4572)
		(layer "F.Cu")
		(net "PSU2_REMOTE_R_N")
	)
	(segment
		(start 27.80665 -110.424722)
		(end 27.347672 -109.965744)
		(width 0.4572)
		(layer "F.Cu")
		(net "PSU2_REMOTE_R_N")
	)
	(segment
		(start 44.541186 -244.725444)
		(end 44.748196 -244.518434)
		(width 0.4572)
		(layer "F.Cu")
		(net "PSU2_REMOTE_R_N")
	)
	(segment
		(start 27.347672 -109.965744)
		(end 27.347672 -109.030516)
		(width 0.4572)
		(layer "F.Cu")
		(net "PSU2_REMOTE_R_N")
	)
	(via
		(at 44.541186 -244.725444)
		(size 0.508)
		(drill 0.254)
		(layers "F.Cu" "B.Cu")
		(net "PSU2_REMOTE_R_N")
	)
	(via
		(at 27.80665 -110.424722)
		(size 0.508)
		(drill 0.254)
		(layers "F.Cu" "B.Cu")
		(net "PSU2_REMOTE_R_N")
	)
	(segment
		(start 27.80665 -110.424722)
		(end 25.49144 -112.739932)
		(width 0.4572)
		(layer "B.Cu")
		(net "PSU2_REMOTE_R_N")
	)
	(segment
		(start 29.271722 -205.530958)
		(end 26.525982 -208.276698)
		(width 0.4572)
		(layer "B.Cu")
		(net "PSU2_REMOTE_R_N")
	)
	(segment
		(start 38.513258 -244.183916)
		(end 43.999658 -244.183916)
		(width 0.4572)
		(layer "B.Cu")
		(net "PSU2_REMOTE_R_N")
	)
	(segment
		(start 25.49144 -112.739932)
		(end 25.49144 -172.583602)
		(width 0.4572)
		(layer "B.Cu")
		(net "PSU2_REMOTE_R_N")
	)
	(segment
		(start 26.525982 -208.276698)
		(end 26.525982 -240.640108)
		(width 0.4572)
		(layer "B.Cu")
		(net "PSU2_REMOTE_R_N")
	)
	(segment
		(start 42.288206 -191.861948)
		(end 42.288206 -200.959974)
		(width 0.4572)
		(layer "B.Cu")
		(net "PSU2_REMOTE_R_N")
	)
	(segment
		(start 37.182044 -186.755786)
		(end 42.288206 -191.861948)
		(width 0.4572)
		(layer "B.Cu")
		(net "PSU2_REMOTE_R_N")
	)
	(segment
		(start 42.288206 -200.959974)
		(end 37.717222 -205.530958)
		(width 0.4572)
		(layer "B.Cu")
		(net "PSU2_REMOTE_R_N")
	)
	(segment
		(start 43.999658 -244.183916)
		(end 44.541186 -244.725444)
		(width 0.4572)
		(layer "B.Cu")
		(net "PSU2_REMOTE_R_N")
	)
	(segment
		(start 29.471874 -243.586)
		(end 37.915342 -243.586)
		(width 0.4572)
		(layer "B.Cu")
		(net "PSU2_REMOTE_R_N")
	)
	(segment
		(start 36.228782 -179.966366)
		(end 37.182044 -180.919628)
		(width 0.4572)
		(layer "B.Cu")
		(net "PSU2_REMOTE_R_N")
	)
	(segment
		(start 37.717222 -205.530958)
		(end 29.271722 -205.530958)
		(width 0.4572)
		(layer "B.Cu")
		(net "PSU2_REMOTE_R_N")
	)
	(segment
		(start 37.182044 -180.919628)
		(end 37.182044 -186.755786)
		(width 0.4572)
		(layer "B.Cu")
		(net "PSU2_REMOTE_R_N")
	)
	(segment
		(start 26.525982 -240.640108)
		(end 29.471874 -243.586)
		(width 0.4572)
		(layer "B.Cu")
		(net "PSU2_REMOTE_R_N")
	)
	(segment
		(start 25.49144 -172.583602)
		(end 32.874204 -179.966366)
		(width 0.4572)
		(layer "B.Cu")
		(net "PSU2_REMOTE_R_N")
	)
	(segment
		(start 37.915342 -243.586)
		(end 38.513258 -244.183916)
		(width 0.4572)
		(layer "B.Cu")
		(net "PSU2_REMOTE_R_N")
	)
	(segment
		(start 32.874204 -179.966366)
		(end 36.228782 -179.966366)
		(width 0.4572)
		(layer "B.Cu")
		(net "PSU2_REMOTE_R_N")
	)
	(segment
		(start 44.998894 -238.246666)
		(end 46.030642 -238.246666)
		(width 0.4572)
		(layer "F.Cu")
		(net "PSU1_REMOTE_R_P")
	)
	(segment
		(start 39.46398 -23.185374)
		(end 40.491918 -23.185374)
		(width 0.4572)
		(layer "F.Cu")
		(net "PSU1_REMOTE_R_P")
	)
	(segment
		(start 44.706794 -237.954566)
		(end 44.998894 -238.246666)
		(width 0.4572)
		(layer "F.Cu")
		(net "PSU1_REMOTE_R_P")
	)
	(via
		(at 40.491918 -23.185374)
		(size 0.508)
		(drill 0.254)
		(layers "F.Cu" "B.Cu")
		(net "PSU1_REMOTE_R_P")
	)
	(via
		(at 44.706794 -237.954566)
		(size 0.508)
		(drill 0.254)
		(layers "F.Cu" "B.Cu")
		(net "PSU1_REMOTE_R_P")
	)
	(segment
		(start 33.783524 -177.240184)
		(end 37.17544 -177.240184)
		(width 0.4572)
		(layer "B.Cu")
		(net "PSU1_REMOTE_R_P")
	)
	(segment
		(start 36.455604 -213.093808)
		(end 29.952188 -213.093808)
		(width 0.4572)
		(layer "B.Cu")
		(net "PSU1_REMOTE_R_P")
	)
	(segment
		(start 35.773106 -89.365328)
		(end 38.667436 -92.259658)
		(width 0.4572)
		(layer "B.Cu")
		(net "PSU1_REMOTE_R_P")
	)
	(segment
		(start 28.321254 -171.777914)
		(end 33.783524 -177.240184)
		(width 0.4572)
		(layer "B.Cu")
		(net "PSU1_REMOTE_R_P")
	)
	(segment
		(start 37.17544 -177.240184)
		(end 39.573708 -179.638452)
		(width 0.4572)
		(layer "B.Cu")
		(net "PSU1_REMOTE_R_P")
	)
	(segment
		(start 38.667436 -96.619568)
		(end 42.637456 -100.589588)
		(width 0.4572)
		(layer "B.Cu")
		(net "PSU1_REMOTE_R_P")
	)
	(segment
		(start 27.389074 -83.97113)
		(end 32.783272 -89.365328)
		(width 0.4572)
		(layer "B.Cu")
		(net "PSU1_REMOTE_R_P")
	)
	(segment
		(start 28.321254 -118.464838)
		(end 28.321254 -171.777914)
		(width 0.4572)
		(layer "B.Cu")
		(net "PSU1_REMOTE_R_P")
	)
	(segment
		(start 45.031406 -202.048872)
		(end 38.055804 -209.024474)
		(width 0.4572)
		(layer "B.Cu")
		(net "PSU1_REMOTE_R_P")
	)
	(segment
		(start 28.88488 -23.657306)
		(end 27.389074 -25.153112)
		(width 0.4572)
		(layer "B.Cu")
		(net "PSU1_REMOTE_R_P")
	)
	(segment
		(start 38.667436 -92.259658)
		(end 38.667436 -96.619568)
		(width 0.4572)
		(layer "B.Cu")
		(net "PSU1_REMOTE_R_P")
	)
	(segment
		(start 29.952188 -213.093808)
		(end 28.5115 -214.534496)
		(width 0.4572)
		(layer "B.Cu")
		(net "PSU1_REMOTE_R_P")
	)
	(segment
		(start 42.637456 -111.894112)
		(end 37.41801 -117.113558)
		(width 0.4572)
		(layer "B.Cu")
		(net "PSU1_REMOTE_R_P")
	)
	(segment
		(start 39.573708 -185.611516)
		(end 45.031406 -191.069214)
		(width 0.4572)
		(layer "B.Cu")
		(net "PSU1_REMOTE_R_P")
	)
	(segment
		(start 36.65474 -236.042962)
		(end 39.14902 -238.537242)
		(width 0.4572)
		(layer "B.Cu")
		(net "PSU1_REMOTE_R_P")
	)
	(segment
		(start 45.031406 -191.069214)
		(end 45.031406 -202.048872)
		(width 0.4572)
		(layer "B.Cu")
		(net "PSU1_REMOTE_R_P")
	)
	(segment
		(start 39.14902 -238.537242)
		(end 44.124118 -238.537242)
		(width 0.4572)
		(layer "B.Cu")
		(net "PSU1_REMOTE_R_P")
	)
	(segment
		(start 38.055804 -209.024474)
		(end 38.055804 -211.493608)
		(width 0.4572)
		(layer "B.Cu")
		(net "PSU1_REMOTE_R_P")
	)
	(segment
		(start 32.783272 -89.365328)
		(end 35.773106 -89.365328)
		(width 0.4572)
		(layer "B.Cu")
		(net "PSU1_REMOTE_R_P")
	)
	(segment
		(start 42.637456 -100.589588)
		(end 42.637456 -111.894112)
		(width 0.4572)
		(layer "B.Cu")
		(net "PSU1_REMOTE_R_P")
	)
	(segment
		(start 28.5115 -234.522264)
		(end 30.032198 -236.042962)
		(width 0.4572)
		(layer "B.Cu")
		(net "PSU1_REMOTE_R_P")
	)
	(segment
		(start 30.032198 -236.042962)
		(end 36.65474 -236.042962)
		(width 0.4572)
		(layer "B.Cu")
		(net "PSU1_REMOTE_R_P")
	)
	(segment
		(start 40.019986 -23.657306)
		(end 28.88488 -23.657306)
		(width 0.4572)
		(layer "B.Cu")
		(net "PSU1_REMOTE_R_P")
	)
	(segment
		(start 39.573708 -179.638452)
		(end 39.573708 -185.611516)
		(width 0.4572)
		(layer "B.Cu")
		(net "PSU1_REMOTE_R_P")
	)
	(segment
		(start 38.055804 -211.493608)
		(end 36.455604 -213.093808)
		(width 0.4572)
		(layer "B.Cu")
		(net "PSU1_REMOTE_R_P")
	)
	(segment
		(start 37.41801 -117.113558)
		(end 29.672534 -117.113558)
		(width 0.4572)
		(layer "B.Cu")
		(net "PSU1_REMOTE_R_P")
	)
	(segment
		(start 44.124118 -238.537242)
		(end 44.706794 -237.954566)
		(width 0.4572)
		(layer "B.Cu")
		(net "PSU1_REMOTE_R_P")
	)
	(segment
		(start 28.5115 -214.534496)
		(end 28.5115 -234.522264)
		(width 0.4572)
		(layer "B.Cu")
		(net "PSU1_REMOTE_R_P")
	)
	(segment
		(start 29.672534 -117.113558)
		(end 28.321254 -118.464838)
		(width 0.4572)
		(layer "B.Cu")
		(net "PSU1_REMOTE_R_P")
	)
	(segment
		(start 40.491918 -23.185374)
		(end 40.019986 -23.657306)
		(width 0.4572)
		(layer "B.Cu")
		(net "PSU1_REMOTE_R_P")
	)
	(segment
		(start 27.389074 -25.153112)
		(end 27.389074 -83.97113)
		(width 0.4572)
		(layer "B.Cu")
		(net "PSU1_REMOTE_R_P")
	)
	(segment
		(start 44.944538 -239.669066)
		(end 46.008036 -239.669066)
		(width 0.4572)
		(layer "F.Cu")
		(net "PSU1_REMOTE_R_N")
	)
	(segment
		(start 27.246072 -21.525484)
		(end 27.602688 -21.8821)
		(width 0.4572)
		(layer "F.Cu")
		(net "PSU1_REMOTE_R_N")
	)
	(segment
		(start 27.246072 -20.66417)
		(end 27.246072 -21.525484)
		(width 0.4572)
		(layer "F.Cu")
		(net "PSU1_REMOTE_R_N")
	)
	(segment
		(start 44.701206 -239.912398)
		(end 44.944538 -239.669066)
		(width 0.4572)
		(layer "F.Cu")
		(net "PSU1_REMOTE_R_N")
	)
	(via
		(at 44.701206 -239.912398)
		(size 0.508)
		(drill 0.254)
		(layers "F.Cu" "B.Cu")
		(net "PSU1_REMOTE_R_N")
	)
	(via
		(at 27.602688 -21.8821)
		(size 0.508)
		(drill 0.254)
		(layers "F.Cu" "B.Cu")
		(net "PSU1_REMOTE_R_N")
	)
	(segment
		(start 38.676834 -114.624104)
		(end 29.152342 -114.624104)
		(width 0.4572)
		(layer "B.Cu")
		(net "PSU1_REMOTE_R_N")
	)
	(segment
		(start 38.21557 -239.373918)
		(end 44.162726 -239.373918)
		(width 0.4572)
		(layer "B.Cu")
		(net "PSU1_REMOTE_R_N")
	)
	(segment
		(start 26.728674 -24.322278)
		(end 26.728674 -84.244942)
		(width 0.4572)
		(layer "B.Cu")
		(net "PSU1_REMOTE_R_N")
	)
	(segment
		(start 37.055298 -208.841594)
		(end 37.055298 -209.872834)
		(width 0.4572)
		(layer "B.Cu")
		(net "PSU1_REMOTE_R_N")
	)
	(segment
		(start 33.58388 -178.24069)
		(end 36.995608 -178.24069)
		(width 0.4572)
		(layer "B.Cu")
		(net "PSU1_REMOTE_R_N")
	)
	(segment
		(start 27.47264 -172.12945)
		(end 33.58388 -178.24069)
		(width 0.4572)
		(layer "B.Cu")
		(net "PSU1_REMOTE_R_N")
	)
	(segment
		(start 35.491928 -90.092784)
		(end 38.007036 -92.607892)
		(width 0.4572)
		(layer "B.Cu")
		(net "PSU1_REMOTE_R_N")
	)
	(segment
		(start 29.872432 -210.63331)
		(end 27.846782 -212.65896)
		(width 0.4572)
		(layer "B.Cu")
		(net "PSU1_REMOTE_R_N")
	)
	(segment
		(start 44.19473 -201.702162)
		(end 37.055298 -208.841594)
		(width 0.4572)
		(layer "B.Cu")
		(net "PSU1_REMOTE_R_N")
	)
	(segment
		(start 29.792422 -238.514128)
		(end 37.35578 -238.514128)
		(width 0.4572)
		(layer "B.Cu")
		(net "PSU1_REMOTE_R_N")
	)
	(segment
		(start 29.152342 -114.624104)
		(end 27.47264 -116.303806)
		(width 0.4572)
		(layer "B.Cu")
		(net "PSU1_REMOTE_R_N")
	)
	(segment
		(start 32.576516 -90.092784)
		(end 35.491928 -90.092784)
		(width 0.4572)
		(layer "B.Cu")
		(net "PSU1_REMOTE_R_N")
	)
	(segment
		(start 27.846782 -236.568488)
		(end 29.792422 -238.514128)
		(width 0.4572)
		(layer "B.Cu")
		(net "PSU1_REMOTE_R_N")
	)
	(segment
		(start 27.602688 -23.448264)
		(end 26.728674 -24.322278)
		(width 0.4572)
		(layer "B.Cu")
		(net "PSU1_REMOTE_R_N")
	)
	(segment
		(start 27.47264 -116.303806)
		(end 27.47264 -172.12945)
		(width 0.4572)
		(layer "B.Cu")
		(net "PSU1_REMOTE_R_N")
	)
	(segment
		(start 44.19473 -191.415924)
		(end 44.19473 -201.702162)
		(width 0.4572)
		(layer "B.Cu")
		(net "PSU1_REMOTE_R_N")
	)
	(segment
		(start 27.846782 -212.65896)
		(end 27.846782 -236.568488)
		(width 0.4572)
		(layer "B.Cu")
		(net "PSU1_REMOTE_R_N")
	)
	(segment
		(start 36.995608 -178.24069)
		(end 38.832282 -180.077364)
		(width 0.4572)
		(layer "B.Cu")
		(net "PSU1_REMOTE_R_N")
	)
	(segment
		(start 26.728674 -84.244942)
		(end 32.576516 -90.092784)
		(width 0.4572)
		(layer "B.Cu")
		(net "PSU1_REMOTE_R_N")
	)
	(segment
		(start 37.35578 -238.514128)
		(end 38.21557 -239.373918)
		(width 0.4572)
		(layer "B.Cu")
		(net "PSU1_REMOTE_R_N")
	)
	(segment
		(start 37.055298 -209.872834)
		(end 36.294822 -210.63331)
		(width 0.4572)
		(layer "B.Cu")
		(net "PSU1_REMOTE_R_N")
	)
	(segment
		(start 41.91 -100.891086)
		(end 41.91 -111.390938)
		(width 0.4572)
		(layer "B.Cu")
		(net "PSU1_REMOTE_R_N")
	)
	(segment
		(start 44.162726 -239.373918)
		(end 44.701206 -239.912398)
		(width 0.4572)
		(layer "B.Cu")
		(net "PSU1_REMOTE_R_N")
	)
	(segment
		(start 38.832282 -180.077364)
		(end 38.832282 -186.053476)
		(width 0.4572)
		(layer "B.Cu")
		(net "PSU1_REMOTE_R_N")
	)
	(segment
		(start 38.007036 -92.607892)
		(end 38.007036 -96.988122)
		(width 0.4572)
		(layer "B.Cu")
		(net "PSU1_REMOTE_R_N")
	)
	(segment
		(start 38.007036 -96.988122)
		(end 41.91 -100.891086)
		(width 0.4572)
		(layer "B.Cu")
		(net "PSU1_REMOTE_R_N")
	)
	(segment
		(start 36.294822 -210.63331)
		(end 29.872432 -210.63331)
		(width 0.4572)
		(layer "B.Cu")
		(net "PSU1_REMOTE_R_N")
	)
	(segment
		(start 38.832282 -186.053476)
		(end 44.19473 -191.415924)
		(width 0.4572)
		(layer "B.Cu")
		(net "PSU1_REMOTE_R_N")
	)
	(segment
		(start 27.602688 -21.8821)
		(end 27.602688 -23.448264)
		(width 0.4572)
		(layer "B.Cu")
		(net "PSU1_REMOTE_R_N")
	)
	(segment
		(start 41.91 -111.390938)
		(end 38.676834 -114.624104)
		(width 0.4572)
		(layer "B.Cu")
		(net "PSU1_REMOTE_R_N")
	)
	(segment
		(start 27.639264 -286.750252)
		(end 27.639264 -285.829502)
		(width 0.4572)
		(layer "F.Cu")
		(net "PSU4_REMOTE_R_N")
	)
	(segment
		(start 45.965872 -257.889502)
		(end 44.819824 -257.889502)
		(width 0.4572)
		(layer "F.Cu")
		(net "PSU4_REMOTE_R_N")
	)
	(segment
		(start 44.819824 -257.889502)
		(end 44.570142 -258.139184)
		(width 0.4572)
		(layer "F.Cu")
		(net "PSU4_REMOTE_R_N")
	)
	(segment
		(start 27.550872 -286.838644)
		(end 27.639264 -286.750252)
		(width 0.4572)
		(layer "F.Cu")
		(net "PSU4_REMOTE_R_N")
	)
	(via
		(at 27.550872 -286.838644)
		(size 0.508)
		(drill 0.254)
		(layers "F.Cu" "B.Cu")
		(net "PSU4_REMOTE_R_N")
	)
	(via
		(at 44.570142 -258.139184)
		(size 0.508)
		(drill 0.254)
		(layers "F.Cu" "B.Cu")
		(net "PSU4_REMOTE_R_N")
	)
	(via
		(at 20.192746 -257.777234)
		(size 0.508)
		(drill 0.254)
		(layers "F.Cu" "B.Cu")
		(net "PSU4_REMOTE_R_N")
	)
	(segment
		(start 23.717504 -279.13584)
		(end 20.192746 -275.611082)
		(width 0.4572)
		(layer "B.Cu")
		(net "PSU4_REMOTE_R_N")
	)
	(segment
		(start 27.550872 -286.838644)
		(end 26.802842 -286.838644)
		(width 0.4572)
		(layer "B.Cu")
		(net "PSU4_REMOTE_R_N")
	)
	(segment
		(start 26.802842 -286.838644)
		(end 23.717504 -283.753306)
		(width 0.4572)
		(layer "B.Cu")
		(net "PSU4_REMOTE_R_N")
	)
	(segment
		(start 20.192746 -275.611082)
		(end 20.192746 -257.777234)
		(width 0.4572)
		(layer "B.Cu")
		(net "PSU4_REMOTE_R_N")
	)
	(segment
		(start 23.717504 -283.753306)
		(end 23.717504 -279.13584)
		(width 0.4572)
		(layer "B.Cu")
		(net "PSU4_REMOTE_R_N")
	)
	(segment
		(start 39.626286 -257.824478)
		(end 43.645836 -257.824478)
		(width 0.4572)
		(layer "In5.Cu")
		(net "PSU4_REMOTE_R_N")
	)
	(segment
		(start 38.575742 -258.875022)
		(end 39.626286 -257.824478)
		(width 0.4572)
		(layer "In5.Cu")
		(net "PSU4_REMOTE_R_N")
	)
	(segment
		(start 43.960542 -258.139184)
		(end 44.570142 -258.139184)
		(width 0.4572)
		(layer "In5.Cu")
		(net "PSU4_REMOTE_R_N")
	)
	(segment
		(start 43.645836 -257.824478)
		(end 43.960542 -258.139184)
		(width 0.4572)
		(layer "In5.Cu")
		(net "PSU4_REMOTE_R_N")
	)
	(segment
		(start 20.192746 -257.777234)
		(end 20.192746 -257.388106)
		(width 0.4572)
		(layer "In5.Cu")
		(net "PSU4_REMOTE_R_N")
	)
	(segment
		(start 20.192746 -257.388106)
		(end 21.491702 -256.08915)
		(width 0.4572)
		(layer "In5.Cu")
		(net "PSU4_REMOTE_R_N")
	)
	(segment
		(start 27.05227 -256.08915)
		(end 29.838142 -258.875022)
		(width 0.4572)
		(layer "In5.Cu")
		(net "PSU4_REMOTE_R_N")
	)
	(segment
		(start 21.491702 -256.08915)
		(end 27.05227 -256.08915)
		(width 0.4572)
		(layer "In5.Cu")
		(net "PSU4_REMOTE_R_N")
	)
	(segment
		(start 29.838142 -258.875022)
		(end 38.575742 -258.875022)
		(width 0.4572)
		(layer "In5.Cu")
		(net "PSU4_REMOTE_R_N")
	)
	(segment
		(start 44.876974 -256.467102)
		(end 45.96511 -256.467102)
		(width 0.4572)
		(layer "F.Cu")
		(net "PSU4_REMOTE_R_P")
	)
	(segment
		(start 39.437056 -288.377376)
		(end 39.642034 -288.582354)
		(width 0.4572)
		(layer "F.Cu")
		(net "PSU4_REMOTE_R_P")
	)
	(segment
		(start 39.642034 -288.582354)
		(end 40.483028 -288.582354)
		(width 0.4572)
		(layer "F.Cu")
		(net "PSU4_REMOTE_R_P")
	)
	(segment
		(start 44.627292 -256.21742)
		(end 44.876974 -256.467102)
		(width 0.4572)
		(layer "F.Cu")
		(net "PSU4_REMOTE_R_P")
	)
	(via
		(at 44.627292 -256.21742)
		(size 0.508)
		(drill 0.254)
		(layers "F.Cu" "B.Cu")
		(net "PSU4_REMOTE_R_P")
	)
	(via
		(at 19.417284 -257.777234)
		(size 0.508)
		(drill 0.254)
		(layers "F.Cu" "B.Cu")
		(net "PSU4_REMOTE_R_P")
	)
	(via
		(at 40.483028 -288.582354)
		(size 0.508)
		(drill 0.254)
		(layers "F.Cu" "B.Cu")
		(net "PSU4_REMOTE_R_P")
	)
	(segment
		(start 23.045674 -279.560782)
		(end 19.417284 -275.932392)
		(width 0.4572)
		(layer "B.Cu")
		(net "PSU4_REMOTE_R_P")
	)
	(segment
		(start 29.356812 -286.26562)
		(end 27.849322 -287.77311)
		(width 0.4572)
		(layer "B.Cu")
		(net "PSU4_REMOTE_R_P")
	)
	(segment
		(start 27.849322 -287.77311)
		(end 26.753312 -287.77311)
		(width 0.4572)
		(layer "B.Cu")
		(net "PSU4_REMOTE_R_P")
	)
	(segment
		(start 38.166294 -286.26562)
		(end 29.356812 -286.26562)
		(width 0.4572)
		(layer "B.Cu")
		(net "PSU4_REMOTE_R_P")
	)
	(segment
		(start 26.753312 -287.77311)
		(end 23.045674 -284.065472)
		(width 0.4572)
		(layer "B.Cu")
		(net "PSU4_REMOTE_R_P")
	)
	(segment
		(start 23.045674 -284.065472)
		(end 23.045674 -279.560782)
		(width 0.4572)
		(layer "B.Cu")
		(net "PSU4_REMOTE_R_P")
	)
	(segment
		(start 40.483028 -288.582354)
		(end 38.166294 -286.26562)
		(width 0.4572)
		(layer "B.Cu")
		(net "PSU4_REMOTE_R_P")
	)
	(segment
		(start 19.417284 -275.932392)
		(end 19.417284 -257.777234)
		(width 0.4572)
		(layer "B.Cu")
		(net "PSU4_REMOTE_R_P")
	)
	(segment
		(start 44.196 -255.786128)
		(end 44.627292 -256.21742)
		(width 0.4572)
		(layer "In5.Cu")
		(net "PSU4_REMOTE_R_P")
	)
	(segment
		(start 19.417284 -257.047492)
		(end 21.09216 -255.372616)
		(width 0.4572)
		(layer "In5.Cu")
		(net "PSU4_REMOTE_R_P")
	)
	(segment
		(start 40.423592 -256.388616)
		(end 41.02608 -255.786128)
		(width 0.4572)
		(layer "In5.Cu")
		(net "PSU4_REMOTE_R_P")
	)
	(segment
		(start 28.217876 -255.372616)
		(end 29.233876 -256.388616)
		(width 0.4572)
		(layer "In5.Cu")
		(net "PSU4_REMOTE_R_P")
	)
	(segment
		(start 19.417284 -257.777234)
		(end 19.417284 -257.047492)
		(width 0.4572)
		(layer "In5.Cu")
		(net "PSU4_REMOTE_R_P")
	)
	(segment
		(start 29.233876 -256.388616)
		(end 40.423592 -256.388616)
		(width 0.4572)
		(layer "In5.Cu")
		(net "PSU4_REMOTE_R_P")
	)
	(segment
		(start 21.09216 -255.372616)
		(end 28.217876 -255.372616)
		(width 0.4572)
		(layer "In5.Cu")
		(net "PSU4_REMOTE_R_P")
	)
	(segment
		(start 41.02608 -255.786128)
		(end 44.196 -255.786128)
		(width 0.4572)
		(layer "In5.Cu")
		(net "PSU4_REMOTE_R_P")
	)
	(segment
		(start 27.577542 -377.095004)
		(end 28.833572 -378.351034)
		(width 0.4572)
		(layer "F.Cu")
		(net "PSU5_REMOTE_R_N")
	)
	(segment
		(start 45.511466 -260.355588)
		(end 44.938188 -260.355588)
		(width 0.4572)
		(layer "F.Cu")
		(net "PSU5_REMOTE_R_N")
	)
	(segment
		(start 44.938188 -260.355588)
		(end 44.677838 -260.095238)
		(width 0.4572)
		(layer "F.Cu")
		(net "PSU5_REMOTE_R_N")
	)
	(segment
		(start 27.577542 -374.232678)
		(end 27.577542 -377.095004)
		(width 0.4572)
		(layer "F.Cu")
		(net "PSU5_REMOTE_R_N")
	)
	(via
		(at 28.833572 -378.351034)
		(size 0.508)
		(drill 0.254)
		(layers "F.Cu" "B.Cu")
		(net "PSU5_REMOTE_R_N")
	)
	(via
		(at 44.677838 -260.095238)
		(size 0.508)
		(drill 0.254)
		(layers "F.Cu" "B.Cu")
		(net "PSU5_REMOTE_R_N")
	)
	(segment
		(start 39.843202 -291.384736)
		(end 43.373294 -287.854644)
		(width 0.4572)
		(layer "B.Cu")
		(net "PSU5_REMOTE_R_N")
	)
	(segment
		(start 40.520874 -260.7056)
		(end 44.067476 -260.7056)
		(width 0.4572)
		(layer "B.Cu")
		(net "PSU5_REMOTE_R_N")
	)
	(segment
		(start 37.56152 -355.096318)
		(end 32.793686 -355.096318)
		(width 0.4572)
		(layer "B.Cu")
		(net "PSU5_REMOTE_R_N")
	)
	(segment
		(start 29.892244 -291.384736)
		(end 39.843202 -291.384736)
		(width 0.4572)
		(layer "B.Cu")
		(net "PSU5_REMOTE_R_N")
	)
	(segment
		(start 28.505404 -292.771576)
		(end 29.892244 -291.384736)
		(width 0.4572)
		(layer "B.Cu")
		(net "PSU5_REMOTE_R_N")
	)
	(segment
		(start 38.279324 -262.94715)
		(end 40.520874 -260.7056)
		(width 0.4572)
		(layer "B.Cu")
		(net "PSU5_REMOTE_R_N")
	)
	(segment
		(start 29.997908 -377.186698)
		(end 36.203382 -377.186698)
		(width 0.4572)
		(layer "B.Cu")
		(net "PSU5_REMOTE_R_N")
	)
	(segment
		(start 44.067476 -260.7056)
		(end 44.677838 -260.095238)
		(width 0.4572)
		(layer "B.Cu")
		(net "PSU5_REMOTE_R_N")
	)
	(segment
		(start 38.279324 -275.895054)
		(end 38.279324 -262.94715)
		(width 0.4572)
		(layer "B.Cu")
		(net "PSU5_REMOTE_R_N")
	)
	(segment
		(start 38.719252 -374.670828)
		(end 38.719252 -356.25405)
		(width 0.4572)
		(layer "B.Cu")
		(net "PSU5_REMOTE_R_N")
	)
	(segment
		(start 36.203382 -377.186698)
		(end 38.719252 -374.670828)
		(width 0.4572)
		(layer "B.Cu")
		(net "PSU5_REMOTE_R_N")
	)
	(segment
		(start 32.793686 -355.096318)
		(end 28.505404 -350.808036)
		(width 0.4572)
		(layer "B.Cu")
		(net "PSU5_REMOTE_R_N")
	)
	(segment
		(start 38.719252 -356.25405)
		(end 37.56152 -355.096318)
		(width 0.4572)
		(layer "B.Cu")
		(net "PSU5_REMOTE_R_N")
	)
	(segment
		(start 28.505404 -350.808036)
		(end 28.505404 -292.771576)
		(width 0.4572)
		(layer "B.Cu")
		(net "PSU5_REMOTE_R_N")
	)
	(segment
		(start 28.833572 -378.351034)
		(end 29.997908 -377.186698)
		(width 0.4572)
		(layer "B.Cu")
		(net "PSU5_REMOTE_R_N")
	)
	(segment
		(start 43.373294 -287.854644)
		(end 43.373294 -280.989024)
		(width 0.4572)
		(layer "B.Cu")
		(net "PSU5_REMOTE_R_N")
	)
	(segment
		(start 43.373294 -280.989024)
		(end 38.279324 -275.895054)
		(width 0.4572)
		(layer "B.Cu")
		(net "PSU5_REMOTE_R_N")
	)
	(segment
		(start 39.581836 -376.789696)
		(end 40.519604 -376.792236)
		(width 0.4572)
		(layer "F.Cu")
		(net "PSU5_REMOTE_R_P")
	)
	(segment
		(start 44.854368 -261.777988)
		(end 44.563792 -262.068564)
		(width 0.4572)
		(layer "F.Cu")
		(net "PSU5_REMOTE_R_P")
	)
	(segment
		(start 45.510958 -261.777988)
		(end 44.854368 -261.777988)
		(width 0.4572)
		(layer "F.Cu")
		(net "PSU5_REMOTE_R_P")
	)
	(via
		(at 44.563792 -262.068564)
		(size 0.508)
		(drill 0.254)
		(layers "F.Cu" "B.Cu")
		(net "PSU5_REMOTE_R_P")
	)
	(via
		(at 40.519604 -376.792236)
		(size 0.508)
		(drill 0.254)
		(layers "F.Cu" "B.Cu")
		(net "PSU5_REMOTE_R_P")
	)
	(segment
		(start 44.563792 -262.068564)
		(end 43.976036 -261.480808)
		(width 0.4572)
		(layer "B.Cu")
		(net "PSU5_REMOTE_R_P")
	)
	(segment
		(start 29.227018 -294.540686)
		(end 29.227018 -350.414844)
		(width 0.4572)
		(layer "B.Cu")
		(net "PSU5_REMOTE_R_P")
	)
	(segment
		(start 39.49446 -355.628702)
		(end 39.49446 -375.767092)
		(width 0.4572)
		(layer "B.Cu")
		(net "PSU5_REMOTE_R_P")
	)
	(segment
		(start 33.184084 -354.37191)
		(end 38.237668 -354.37191)
		(width 0.4572)
		(layer "B.Cu")
		(net "PSU5_REMOTE_R_P")
	)
	(segment
		(start 39.49446 -375.767092)
		(end 40.519604 -376.792236)
		(width 0.4572)
		(layer "B.Cu")
		(net "PSU5_REMOTE_R_P")
	)
	(segment
		(start 44.148502 -288.175954)
		(end 38.438582 -293.885874)
		(width 0.4572)
		(layer "B.Cu")
		(net "PSU5_REMOTE_R_P")
	)
	(segment
		(start 38.237668 -354.37191)
		(end 39.49446 -355.628702)
		(width 0.4572)
		(layer "B.Cu")
		(net "PSU5_REMOTE_R_P")
	)
	(segment
		(start 38.438582 -293.885874)
		(end 29.88183 -293.885874)
		(width 0.4572)
		(layer "B.Cu")
		(net "PSU5_REMOTE_R_P")
	)
	(segment
		(start 29.227018 -350.414844)
		(end 33.184084 -354.37191)
		(width 0.4572)
		(layer "B.Cu")
		(net "PSU5_REMOTE_R_P")
	)
	(segment
		(start 44.148502 -280.667714)
		(end 44.148502 -288.175954)
		(width 0.4572)
		(layer "B.Cu")
		(net "PSU5_REMOTE_R_P")
	)
	(segment
		(start 43.976036 -261.480808)
		(end 40.842184 -261.480808)
		(width 0.4572)
		(layer "B.Cu")
		(net "PSU5_REMOTE_R_P")
	)
	(segment
		(start 29.88183 -293.885874)
		(end 29.227018 -294.540686)
		(width 0.4572)
		(layer "B.Cu")
		(net "PSU5_REMOTE_R_P")
	)
	(segment
		(start 40.842184 -261.480808)
		(end 39.054532 -263.26846)
		(width 0.4572)
		(layer "B.Cu")
		(net "PSU5_REMOTE_R_P")
	)
	(segment
		(start 39.054532 -263.26846)
		(end 39.054532 -275.573744)
		(width 0.4572)
		(layer "B.Cu")
		(net "PSU5_REMOTE_R_P")
	)
	(segment
		(start 39.054532 -275.573744)
		(end 44.148502 -280.667714)
		(width 0.4572)
		(layer "B.Cu")
		(net "PSU5_REMOTE_R_P")
	)
	(segment
		(start 26.626058 -453.535034)
		(end 26.626058 -452.257668)
		(width 0.1524)
		(layer "F.Cu")
		(net "PSU6_PS_KILL")
	)
	(segment
		(start 28.657042 -452.258176)
		(end 29.245306 -451.669912)
		(width 0.1524)
		(layer "F.Cu")
		(net "PSU6_PS_KILL")
	)
	(segment
		(start 27.272234 -452.257668)
		(end 27.272742 -452.258176)
		(width 0.1524)
		(layer "F.Cu")
		(net "PSU6_PS_KILL")
	)
	(segment
		(start 26.626058 -450.980556)
		(end 26.626058 -452.257668)
		(width 0.1524)
		(layer "F.Cu")
		(net "PSU6_PS_KILL")
	)
	(segment
		(start 29.245306 -451.669912)
		(end 30.45968 -451.669912)
		(width 0.1524)
		(layer "F.Cu")
		(net "PSU6_PS_KILL")
	)
	(segment
		(start 27.272742 -452.258176)
		(end 28.657042 -452.258176)
		(width 0.1524)
		(layer "F.Cu")
		(net "PSU6_PS_KILL")
	)
	(segment
		(start 26.626058 -452.257668)
		(end 27.272234 -452.257668)
		(width 0.1524)
		(layer "F.Cu")
		(net "PSU6_PS_KILL")
	)
	(via
		(at 27.272742 -452.258176)
		(size 0.508)
		(drill 0.254)
		(layers "F.Cu" "B.Cu")
		(net "PSU6_PS_KILL")
	)
	(segment
		(start 27.26817 -449.690998)
		(end 29.898594 -449.690998)
		(width 0.1524)
		(layer "F.Cu")
		(net "PSU6_RESET")
	)
	(segment
		(start 26.626058 -449.713858)
		(end 26.626058 -448.493388)
		(width 0.1524)
		(layer "F.Cu")
		(net "PSU6_RESET")
	)
	(segment
		(start 27.24531 -449.713858)
		(end 27.26817 -449.690998)
		(width 0.1524)
		(layer "F.Cu")
		(net "PSU6_RESET")
	)
	(segment
		(start 26.626058 -448.493388)
		(end 26.626058 -447.250058)
		(width 0.1524)
		(layer "F.Cu")
		(net "PSU6_RESET")
	)
	(segment
		(start 26.626058 -449.713858)
		(end 27.24531 -449.713858)
		(width 0.1524)
		(layer "F.Cu")
		(net "PSU6_RESET")
	)
	(segment
		(start 29.898594 -449.690998)
		(end 30.45968 -449.129912)
		(width 0.1524)
		(layer "F.Cu")
		(net "PSU6_RESET")
	)
	(via
		(at 27.26817 -449.690998)
		(size 0.508)
		(drill 0.254)
		(layers "F.Cu" "B.Cu")
		(net "PSU6_RESET")
	)
	(segment
		(start 30.045152 -360.550968)
		(end 30.224222 -360.730038)
		(width 0.1524)
		(layer "F.Cu")
		(net "PSU5_RESET")
	)
	(segment
		(start 26.257758 -361.78236)
		(end 26.257758 -360.550968)
		(width 0.1524)
		(layer "F.Cu")
		(net "PSU5_RESET")
	)
	(segment
		(start 26.257758 -360.550968)
		(end 27.157934 -360.550968)
		(width 0.1524)
		(layer "F.Cu")
		(net "PSU5_RESET")
	)
	(segment
		(start 26.257758 -363.01553)
		(end 26.257758 -361.78236)
		(width 0.1524)
		(layer "F.Cu")
		(net "PSU5_RESET")
	)
	(segment
		(start 30.224222 -360.730038)
		(end 30.45968 -360.730038)
		(width 0.1524)
		(layer "F.Cu")
		(net "PSU5_RESET")
	)
	(segment
		(start 27.157934 -360.550968)
		(end 30.045152 -360.550968)
		(width 0.1524)
		(layer "F.Cu")
		(net "PSU5_RESET")
	)
	(via
		(at 27.157934 -360.550968)
		(size 0.508)
		(drill 0.254)
		(layers "F.Cu" "B.Cu")
		(net "PSU5_RESET")
	)
	(segment
		(start 27.168348 -364.246414)
		(end 26.257758 -364.246414)
		(width 0.1524)
		(layer "F.Cu")
		(net "PSU5_PS_KILL")
	)
	(segment
		(start 30.45968 -363.270038)
		(end 29.483304 -364.246414)
		(width 0.1524)
		(layer "F.Cu")
		(net "PSU5_PS_KILL")
	)
	(segment
		(start 29.483304 -364.246414)
		(end 27.168348 -364.246414)
		(width 0.1524)
		(layer "F.Cu")
		(net "PSU5_PS_KILL")
	)
	(segment
		(start 26.257758 -365.50092)
		(end 26.257758 -364.246414)
		(width 0.1524)
		(layer "F.Cu")
		(net "PSU5_PS_KILL")
	)
	(segment
		(start 26.257758 -366.710722)
		(end 26.257758 -365.50092)
		(width 0.1524)
		(layer "F.Cu")
		(net "PSU5_PS_KILL")
	)
	(via
		(at 27.168348 -364.246414)
		(size 0.508)
		(drill 0.254)
		(layers "F.Cu" "B.Cu")
		(net "PSU5_PS_KILL")
	)
	(segment
		(start 26.502106 -273.532854)
		(end 26.502106 -272.345404)
		(width 0.1524)
		(layer "F.Cu")
		(net "PSU4_RESET")
	)
	(segment
		(start 27.318208 -272.340832)
		(end 26.502106 -272.345404)
		(width 0.1524)
		(layer "F.Cu")
		(net "PSU4_RESET")
	)
	(segment
		(start 27.318208 -272.340832)
		(end 27.32913 -272.32991)
		(width 0.1524)
		(layer "F.Cu")
		(net "PSU4_RESET")
	)
	(segment
		(start 27.32913 -272.32991)
		(end 30.45968 -272.32991)
		(width 0.1524)
		(layer "F.Cu")
		(net "PSU4_RESET")
	)
	(segment
		(start 27.23261 -272.340832)
		(end 27.318208 -272.340832)
		(width 0.1524)
		(layer "F.Cu")
		(net "PSU4_RESET")
	)
	(segment
		(start 26.502106 -272.345404)
		(end 26.502106 -271.14881)
		(width 0.1524)
		(layer "F.Cu")
		(net "PSU4_RESET")
	)
	(via
		(at 27.23261 -272.340832)
		(size 0.508)
		(drill 0.254)
		(layers "F.Cu" "B.Cu")
		(net "PSU4_RESET")
	)
	(segment
		(start 27.23769 -274.770342)
		(end 27.23769 -274.774914)
		(width 0.1524)
		(layer "F.Cu")
		(net "PSU4_PS_KILL")
	)
	(segment
		(start 26.502106 -277.377144)
		(end 26.502106 -276.12213)
		(width 0.1524)
		(layer "F.Cu")
		(net "PSU4_PS_KILL")
	)
	(segment
		(start 29.290518 -274.76831)
		(end 29.392118 -274.86991)
		(width 0.1524)
		(layer "F.Cu")
		(net "PSU4_PS_KILL")
	)
	(segment
		(start 27.244294 -274.76831)
		(end 29.290518 -274.76831)
		(width 0.1524)
		(layer "F.Cu")
		(net "PSU4_PS_KILL")
	)
	(segment
		(start 27.23769 -274.774914)
		(end 27.244294 -274.76831)
		(width 0.1524)
		(layer "F.Cu")
		(net "PSU4_PS_KILL")
	)
	(segment
		(start 29.392118 -274.86991)
		(end 30.45968 -274.86991)
		(width 0.1524)
		(layer "F.Cu")
		(net "PSU4_PS_KILL")
	)
	(segment
		(start 26.502106 -274.774914)
		(end 27.23769 -274.770342)
		(width 0.1524)
		(layer "F.Cu")
		(net "PSU4_PS_KILL")
	)
	(segment
		(start 26.502106 -276.12213)
		(end 26.502106 -274.774914)
		(width 0.1524)
		(layer "F.Cu")
		(net "PSU4_PS_KILL")
	)
	(via
		(at 27.23769 -274.774914)
		(size 0.508)
		(drill 0.254)
		(layers "F.Cu" "B.Cu")
		(net "PSU4_PS_KILL")
	)
	(segment
		(start 26.468324 -185.521092)
		(end 26.468324 -186.752992)
		(width 0.1524)
		(layer "F.Cu")
		(net "PSU3_PS_KILL")
	)
	(segment
		(start 30.45968 -186.470036)
		(end 29.068014 -186.470036)
		(width 0.1524)
		(layer "F.Cu")
		(net "PSU3_PS_KILL")
	)
	(segment
		(start 27.214576 -186.752992)
		(end 27.221942 -186.745626)
		(width 0.1524)
		(layer "F.Cu")
		(net "PSU3_PS_KILL")
	)
	(segment
		(start 29.068014 -186.470036)
		(end 28.792424 -186.745626)
		(width 0.1524)
		(layer "F.Cu")
		(net "PSU3_PS_KILL")
	)
	(segment
		(start 26.468324 -186.752992)
		(end 26.468324 -187.950348)
		(width 0.1524)
		(layer "F.Cu")
		(net "PSU3_PS_KILL")
	)
	(segment
		(start 28.792424 -186.745626)
		(end 27.221942 -186.745626)
		(width 0.1524)
		(layer "F.Cu")
		(net "PSU3_PS_KILL")
	)
	(segment
		(start 26.468324 -186.752992)
		(end 27.214576 -186.752992)
		(width 0.1524)
		(layer "F.Cu")
		(net "PSU3_PS_KILL")
	)
	(via
		(at 27.221942 -186.745626)
		(size 0.508)
		(drill 0.254)
		(layers "F.Cu" "B.Cu")
		(net "PSU3_PS_KILL")
	)
	(segment
		(start 28.778708 -184.243472)
		(end 27.18435 -184.243472)
		(width 0.1524)
		(layer "F.Cu")
		(net "PSU3_RESET")
	)
	(segment
		(start 27.161744 -184.266078)
		(end 27.18435 -184.243472)
		(width 0.1524)
		(layer "F.Cu")
		(net "PSU3_RESET")
	)
	(segment
		(start 30.45968 -183.930036)
		(end 29.092144 -183.930036)
		(width 0.1524)
		(layer "F.Cu")
		(net "PSU3_RESET")
	)
	(segment
		(start 29.092144 -183.930036)
		(end 28.778708 -184.243472)
		(width 0.1524)
		(layer "F.Cu")
		(net "PSU3_RESET")
	)
	(segment
		(start 26.468324 -184.266078)
		(end 27.161744 -184.266078)
		(width 0.1524)
		(layer "F.Cu")
		(net "PSU3_RESET")
	)
	(segment
		(start 26.468324 -184.266078)
		(end 26.468324 -183.06923)
		(width 0.1524)
		(layer "F.Cu")
		(net "PSU3_RESET")
	)
	(segment
		(start 26.468324 -183.06923)
		(end 26.468324 -181.847998)
		(width 0.1524)
		(layer "F.Cu")
		(net "PSU3_RESET")
	)
	(via
		(at 27.18435 -184.243472)
		(size 0.508)
		(drill 0.254)
		(layers "F.Cu" "B.Cu")
		(net "PSU3_RESET")
	)
	(segment
		(start 26.331672 -100.590096)
		(end 26.331672 -99.36988)
		(width 0.1524)
		(layer "F.Cu")
		(net "PSU2_PS_KILL")
	)
	(segment
		(start 29.159962 -99.369626)
		(end 30.45968 -98.069908)
		(width 0.1524)
		(layer "F.Cu")
		(net "PSU2_PS_KILL")
	)
	(segment
		(start 26.331672 -99.36988)
		(end 27.103832 -99.36988)
		(width 0.1524)
		(layer "F.Cu")
		(net "PSU2_PS_KILL")
	)
	(segment
		(start 27.103832 -99.36988)
		(end 27.104086 -99.369626)
		(width 0.1524)
		(layer "F.Cu")
		(net "PSU2_PS_KILL")
	)
	(segment
		(start 26.331672 -99.36988)
		(end 26.331672 -98.10369)
		(width 0.1524)
		(layer "F.Cu")
		(net "PSU2_PS_KILL")
	)
	(segment
		(start 27.104086 -99.369626)
		(end 29.159962 -99.369626)
		(width 0.1524)
		(layer "F.Cu")
		(net "PSU2_PS_KILL")
	)
	(via
		(at 27.104086 -99.369626)
		(size 0.508)
		(drill 0.254)
		(layers "F.Cu" "B.Cu")
		(net "PSU2_PS_KILL")
	)
	(segment
		(start 26.331672 -96.872044)
		(end 26.331672 -95.65132)
		(width 0.1524)
		(layer "F.Cu")
		(net "PSU2_RESET")
	)
	(segment
		(start 27.106118 -95.65132)
		(end 26.331672 -95.65132)
		(width 0.1524)
		(layer "F.Cu")
		(net "PSU2_RESET")
	)
	(segment
		(start 26.331672 -95.65132)
		(end 26.331672 -94.464886)
		(width 0.1524)
		(layer "F.Cu")
		(net "PSU2_RESET")
	)
	(segment
		(start 27.136344 -95.621094)
		(end 27.106118 -95.65132)
		(width 0.1524)
		(layer "F.Cu")
		(net "PSU2_RESET")
	)
	(segment
		(start 27.136344 -95.621094)
		(end 27.22753 -95.529908)
		(width 0.1524)
		(layer "F.Cu")
		(net "PSU2_RESET")
	)
	(segment
		(start 27.22753 -95.529908)
		(end 30.45968 -95.529908)
		(width 0.1524)
		(layer "F.Cu")
		(net "PSU2_RESET")
	)
	(via
		(at 27.136344 -95.621094)
		(size 0.508)
		(drill 0.254)
		(layers "F.Cu" "B.Cu")
		(net "PSU2_RESET")
	)
	(segment
		(start 26.638504 -6.147562)
		(end 27.167332 -6.67639)
		(width 0.1524)
		(layer "F.Cu")
		(net "PSU1_RESET")
	)
	(segment
		(start 27.68473 -4.025138)
		(end 27.68473 -5.10032)
		(width 0.1524)
		(layer "F.Cu")
		(net "PSU1_RESET")
	)
	(segment
		(start 27.68473 -5.10032)
		(end 27.68473 -6.158992)
		(width 0.1524)
		(layer "F.Cu")
		(net "PSU1_RESET")
	)
	(segment
		(start 27.68473 -6.158992)
		(end 27.167332 -6.67639)
		(width 0.1524)
		(layer "F.Cu")
		(net "PSU1_RESET")
	)
	(segment
		(start 26.376122 -6.147562)
		(end 26.638504 -6.147562)
		(width 0.1524)
		(layer "F.Cu")
		(net "PSU1_RESET")
	)
	(segment
		(start 30.45968 -7.130034)
		(end 27.620976 -7.130034)
		(width 0.1524)
		(layer "F.Cu")
		(net "PSU1_RESET")
	)
	(segment
		(start 27.620976 -7.130034)
		(end 27.167332 -6.67639)
		(width 0.1524)
		(layer "F.Cu")
		(net "PSU1_RESET")
	)
	(via
		(at 27.167332 -6.67639)
		(size 0.508)
		(drill 0.254)
		(layers "F.Cu" "B.Cu")
		(net "PSU1_RESET")
	)
	(segment
		(start 26.721562 -8.344662)
		(end 27.187398 -8.810498)
		(width 0.1524)
		(layer "F.Cu")
		(net "PSU1_PS_KILL")
	)
	(segment
		(start 26.397712 -7.19328)
		(end 26.397712 -8.344662)
		(width 0.1524)
		(layer "F.Cu")
		(net "PSU1_PS_KILL")
	)
	(segment
		(start 30.45968 -9.670034)
		(end 28.046934 -9.670034)
		(width 0.1524)
		(layer "F.Cu")
		(net "PSU1_PS_KILL")
	)
	(segment
		(start 26.397712 -9.509252)
		(end 26.397712 -8.344662)
		(width 0.1524)
		(layer "F.Cu")
		(net "PSU1_PS_KILL")
	)
	(segment
		(start 26.397712 -8.344662)
		(end 26.721562 -8.344662)
		(width 0.1524)
		(layer "F.Cu")
		(net "PSU1_PS_KILL")
	)
	(segment
		(start 28.046934 -9.670034)
		(end 27.187398 -8.810498)
		(width 0.1524)
		(layer "F.Cu")
		(net "PSU1_PS_KILL")
	)
	(via
		(at 27.187398 -8.810498)
		(size 0.508)
		(drill 0.254)
		(layers "F.Cu" "B.Cu")
		(net "PSU1_PS_KILL")
	)
	(segment
		(start 26.708608 -284.068774)
		(end 27.856942 -282.92044)
		(width 0.1524)
		(layer "F.Cu")
		(net "MATE_A1")
	)
	(segment
		(start 31.296864 -283.623512)
		(end 33.06953 -281.850846)
		(width 0.1524)
		(layer "F.Cu")
		(net "MATE_A1")
	)
	(segment
		(start 27.418284 -249.748548)
		(end 25.45461 -247.784874)
		(width 0.1524)
		(layer "F.Cu")
		(net "MATE_A1")
	)
	(segment
		(start 27.856942 -282.92044)
		(end 29.219906 -282.92044)
		(width 0.1524)
		(layer "F.Cu")
		(net "MATE_A1")
	)
	(segment
		(start 28.317444 -288.791142)
		(end 26.142696 -286.616394)
		(width 0.1524)
		(layer "F.Cu")
		(net "MATE_A1")
	)
	(segment
		(start 21.085302 -344.488516)
		(end 24.246332 -341.327486)
		(width 0.1524)
		(layer "F.Cu")
		(net "MATE_A1")
	)
	(segment
		(start 25.45461 -237.918498)
		(end 26.651458 -236.72165)
		(width 0.1524)
		(layer "F.Cu")
		(net "MATE_A1")
	)
	(segment
		(start 33.06953 -267.37564)
		(end 27.418284 -261.724394)
		(width 0.1524)
		(layer "F.Cu")
		(net "MATE_A1")
	)
	(segment
		(start 24.246332 -341.327486)
		(end 25.176226 -341.327486)
		(width 0.1524)
		(layer "F.Cu")
		(net "MATE_A1")
	)
	(segment
		(start 33.06953 -281.850846)
		(end 33.06953 -267.37564)
		(width 0.1524)
		(layer "F.Cu")
		(net "MATE_A1")
	)
	(segment
		(start 26.651458 -202.440032)
		(end 22.179026 -197.9676)
		(width 0.1524)
		(layer "F.Cu")
		(net "MATE_A1")
	)
	(segment
		(start 22.179026 -197.9676)
		(end 22.179026 -184.228232)
		(width 0.1524)
		(layer "F.Cu")
		(net "MATE_A1")
	)
	(segment
		(start 25.45461 -247.784874)
		(end 25.45461 -237.918498)
		(width 0.1524)
		(layer "F.Cu")
		(net "MATE_A1")
	)
	(segment
		(start 26.854404 -339.649308)
		(end 26.854404 -311.10682)
		(width 0.1524)
		(layer "F.Cu")
		(net "MATE_A1")
	)
	(segment
		(start 9.83234 -351.780348)
		(end 9.83234 -345.72321)
		(width 0.1524)
		(layer "F.Cu")
		(net "MATE_A1")
	)
	(segment
		(start 26.854404 -311.10682)
		(end 28.317444 -309.64378)
		(width 0.1524)
		(layer "F.Cu")
		(net "MATE_A1")
	)
	(segment
		(start 8.942832 -352.669856)
		(end 9.83234 -351.780348)
		(width 0.1524)
		(layer "F.Cu")
		(net "MATE_A1")
	)
	(segment
		(start 7.629398 -179.584096)
		(end 6.799326 -180.414168)
		(width 0.1524)
		(layer "F.Cu")
		(net "MATE_A1")
	)
	(segment
		(start 26.651458 -236.72165)
		(end 26.651458 -202.440032)
		(width 0.1524)
		(layer "F.Cu")
		(net "MATE_A1")
	)
	(segment
		(start 27.418284 -261.724394)
		(end 27.418284 -249.748548)
		(width 0.1524)
		(layer "F.Cu")
		(net "MATE_A1")
	)
	(segment
		(start 26.142696 -286.616394)
		(end 26.142696 -284.634686)
		(width 0.1524)
		(layer "F.Cu")
		(net "MATE_A1")
	)
	(segment
		(start 11.067034 -344.488516)
		(end 21.085302 -344.488516)
		(width 0.1524)
		(layer "F.Cu")
		(net "MATE_A1")
	)
	(segment
		(start 26.142696 -284.634686)
		(end 26.708608 -284.068774)
		(width 0.1524)
		(layer "F.Cu")
		(net "MATE_A1")
	)
	(segment
		(start 9.83234 -345.72321)
		(end 11.067034 -344.488516)
		(width 0.1524)
		(layer "F.Cu")
		(net "MATE_A1")
	)
	(segment
		(start 25.176226 -341.327486)
		(end 26.854404 -339.649308)
		(width 0.1524)
		(layer "F.Cu")
		(net "MATE_A1")
	)
	(segment
		(start 29.219906 -282.92044)
		(end 29.922978 -283.623512)
		(width 0.1524)
		(layer "F.Cu")
		(net "MATE_A1")
	)
	(segment
		(start 6.799326 -180.414168)
		(end 4.69265 -180.414168)
		(width 0.1524)
		(layer "F.Cu")
		(net "MATE_A1")
	)
	(segment
		(start 29.922978 -283.623512)
		(end 31.296864 -283.623512)
		(width 0.1524)
		(layer "F.Cu")
		(net "MATE_A1")
	)
	(segment
		(start 28.317444 -309.64378)
		(end 28.317444 -288.791142)
		(width 0.1524)
		(layer "F.Cu")
		(net "MATE_A1")
	)
	(segment
		(start 6.449822 -352.669856)
		(end 8.942832 -352.669856)
		(width 0.1524)
		(layer "F.Cu")
		(net "MATE_A1")
	)
	(segment
		(start 22.179026 -184.228232)
		(end 17.53489 -179.584096)
		(width 0.1524)
		(layer "F.Cu")
		(net "MATE_A1")
	)
	(segment
		(start 4.69265 -180.414168)
		(end 3.948938 -179.670456)
		(width 0.1524)
		(layer "F.Cu")
		(net "MATE_A1")
	)
	(segment
		(start 17.53489 -179.584096)
		(end 7.629398 -179.584096)
		(width 0.1524)
		(layer "F.Cu")
		(net "MATE_A1")
	)
	(via
		(at 26.708608 -284.068774)
		(size 0.508)
		(drill 0.254)
		(layers "F.Cu" "B.Cu")
		(net "MATE_A1")
	)
	(via
		(at 23.964138 -107.076748)
		(size 0.508)
		(drill 0.254)
		(layers "F.Cu" "B.Cu")
		(net "PSU2_DC_OK")
	)
	(segment
		(start 10.541 -201.854816)
		(end 8.215122 -201.854816)
		(width 0.127)
		(layer "In2.Cu")
		(net "PSU2_DC_OK")
	)
	(segment
		(start 23.964138 -107.076748)
		(end 23.865078 -107.175808)
		(width 0.127)
		(layer "In2.Cu")
		(net "PSU2_DC_OK")
	)
	(segment
		(start 23.865078 -168.109392)
		(end 15.099792 -176.874678)
		(width 0.127)
		(layer "In2.Cu")
		(net "PSU2_DC_OK")
	)
	(segment
		(start 23.865078 -107.175808)
		(end 23.865078 -168.109392)
		(width 0.127)
		(layer "In2.Cu")
		(net "PSU2_DC_OK")
	)
	(segment
		(start 15.099792 -176.874678)
		(end 15.099792 -197.296024)
		(width 0.127)
		(layer "In2.Cu")
		(net "PSU2_DC_OK")
	)
	(segment
		(start 15.099792 -197.296024)
		(end 10.541 -201.854816)
		(width 0.127)
		(layer "In2.Cu")
		(net "PSU2_DC_OK")
	)
	(segment
		(start 8.215122 -201.854816)
		(end 7.670546 -202.399392)
		(width 0.127)
		(layer "In2.Cu")
		(net "PSU2_DC_OK")
	)
	(segment
		(start 7.670546 -213.892384)
		(end 8.448802 -214.67064)
		(width 0.127)
		(layer "In2.Cu")
		(net "PSU2_DC_OK")
	)
	(segment
		(start 7.670546 -202.399392)
		(end 7.670546 -213.892384)
		(width 0.127)
		(layer "In2.Cu")
		(net "PSU2_DC_OK")
	)
	(segment
		(start 23.964138 -107.076748)
		(end 26.779982 -104.260904)
		(width 0.127)
		(layer "In5.Cu")
		(net "PSU2_DC_OK")
	)
	(segment
		(start 31.414974 -104.260904)
		(end 32.52597 -103.149908)
		(width 0.127)
		(layer "In5.Cu")
		(net "PSU2_DC_OK")
	)
	(segment
		(start 32.52597 -103.149908)
		(end 35.53968 -103.149908)
		(width 0.127)
		(layer "In5.Cu")
		(net "PSU2_DC_OK")
	)
	(segment
		(start 26.779982 -104.260904)
		(end 31.414974 -104.260904)
		(width 0.127)
		(layer "In5.Cu")
		(net "PSU2_DC_OK")
	)
	(segment
		(start 26.504646 -262.296148)
		(end 32.322262 -268.113764)
		(width 0.1524)
		(layer "F.Cu")
		(net "PSU6_DC_OK")
	)
	(segment
		(start 25.388316 -287.281366)
		(end 27.479244 -289.372294)
		(width 0.1524)
		(layer "F.Cu")
		(net "PSU6_DC_OK")
	)
	(segment
		(start 14.764766 -216.986612)
		(end 21.123148 -216.986612)
		(width 0.1524)
		(layer "F.Cu")
		(net "PSU6_DC_OK")
	)
	(segment
		(start 32.322262 -279.902666)
		(end 31.191708 -281.03322)
		(width 0.1524)
		(layer "F.Cu")
		(net "PSU6_DC_OK")
	)
	(segment
		(start 24.404828 -247.908572)
		(end 26.504646 -250.00839)
		(width 0.1524)
		(layer "F.Cu")
		(net "PSU6_DC_OK")
	)
	(segment
		(start 28.217368 -281.03322)
		(end 25.388316 -283.862272)
		(width 0.1524)
		(layer "F.Cu")
		(net "PSU6_DC_OK")
	)
	(segment
		(start 27.479244 -289.372294)
		(end 27.479244 -308.47665)
		(width 0.1524)
		(layer "F.Cu")
		(net "PSU6_DC_OK")
	)
	(segment
		(start 25.582626 -310.373268)
		(end 25.582626 -331.92974)
		(width 0.1524)
		(layer "F.Cu")
		(net "PSU6_DC_OK")
	)
	(segment
		(start 21.123148 -216.986612)
		(end 25.927304 -221.790768)
		(width 0.1524)
		(layer "F.Cu")
		(net "PSU6_DC_OK")
	)
	(segment
		(start 25.388316 -283.862272)
		(end 25.388316 -287.281366)
		(width 0.1524)
		(layer "F.Cu")
		(net "PSU6_DC_OK")
	)
	(segment
		(start 24.404828 -237.295436)
		(end 24.404828 -247.908572)
		(width 0.1524)
		(layer "F.Cu")
		(net "PSU6_DC_OK")
	)
	(segment
		(start 8.448802 -210.670648)
		(end 14.764766 -216.986612)
		(width 0.1524)
		(layer "F.Cu")
		(net "PSU6_DC_OK")
	)
	(segment
		(start 25.927304 -235.77296)
		(end 24.404828 -237.295436)
		(width 0.1524)
		(layer "F.Cu")
		(net "PSU6_DC_OK")
	)
	(segment
		(start 25.927304 -221.790768)
		(end 25.927304 -235.77296)
		(width 0.1524)
		(layer "F.Cu")
		(net "PSU6_DC_OK")
	)
	(segment
		(start 31.191708 -281.03322)
		(end 28.217368 -281.03322)
		(width 0.1524)
		(layer "F.Cu")
		(net "PSU6_DC_OK")
	)
	(segment
		(start 27.479244 -308.47665)
		(end 25.582626 -310.373268)
		(width 0.1524)
		(layer "F.Cu")
		(net "PSU6_DC_OK")
	)
	(segment
		(start 26.504646 -250.00839)
		(end 26.504646 -262.296148)
		(width 0.1524)
		(layer "F.Cu")
		(net "PSU6_DC_OK")
	)
	(segment
		(start 32.322262 -268.113764)
		(end 32.322262 -279.902666)
		(width 0.1524)
		(layer "F.Cu")
		(net "PSU6_DC_OK")
	)
	(via
		(at 25.582626 -331.92974)
		(size 0.508)
		(drill 0.254)
		(layers "F.Cu" "B.Cu")
		(net "PSU6_DC_OK")
	)
	(segment
		(start 31.721044 -374.951498)
		(end 29.525214 -374.951498)
		(width 0.1524)
		(layer "B.Cu")
		(net "PSU6_DC_OK")
	)
	(segment
		(start 37.250116 -446.701926)
		(end 37.250116 -456.039728)
		(width 0.1524)
		(layer "B.Cu")
		(net "PSU6_DC_OK")
	)
	(segment
		(start 32.297878 -356.399592)
		(end 37.0713 -356.399592)
		(width 0.1524)
		(layer "B.Cu")
		(net "PSU6_DC_OK")
	)
	(segment
		(start 34.428684 -372.243858)
		(end 31.721044 -374.951498)
		(width 0.1524)
		(layer "B.Cu")
		(net "PSU6_DC_OK")
	)
	(segment
		(start 25.582626 -331.92974)
		(end 27.064716 -333.41183)
		(width 0.1524)
		(layer "B.Cu")
		(net "PSU6_DC_OK")
	)
	(segment
		(start 35.784536 -445.236346)
		(end 37.250116 -446.701926)
		(width 0.1524)
		(layer "B.Cu")
		(net "PSU6_DC_OK")
	)
	(segment
		(start 27.064716 -333.41183)
		(end 27.064716 -351.16643)
		(width 0.1524)
		(layer "B.Cu")
		(net "PSU6_DC_OK")
	)
	(segment
		(start 36.249356 -372.243858)
		(end 34.428684 -372.243858)
		(width 0.1524)
		(layer "B.Cu")
		(net "PSU6_DC_OK")
	)
	(segment
		(start 37.447474 -356.775766)
		(end 37.447474 -371.04574)
		(width 0.1524)
		(layer "B.Cu")
		(net "PSU6_DC_OK")
	)
	(segment
		(start 27.064716 -351.16643)
		(end 32.297878 -356.399592)
		(width 0.1524)
		(layer "B.Cu")
		(net "PSU6_DC_OK")
	)
	(segment
		(start 27.313128 -438.622694)
		(end 33.92678 -445.236346)
		(width 0.1524)
		(layer "B.Cu")
		(net "PSU6_DC_OK")
	)
	(segment
		(start 36.539932 -456.749912)
		(end 35.53968 -456.749912)
		(width 0.1524)
		(layer "B.Cu")
		(net "PSU6_DC_OK")
	)
	(segment
		(start 37.0713 -356.399592)
		(end 37.447474 -356.775766)
		(width 0.1524)
		(layer "B.Cu")
		(net "PSU6_DC_OK")
	)
	(segment
		(start 37.250116 -456.039728)
		(end 36.539932 -456.749912)
		(width 0.1524)
		(layer "B.Cu")
		(net "PSU6_DC_OK")
	)
	(segment
		(start 29.525214 -374.951498)
		(end 27.313128 -377.163584)
		(width 0.1524)
		(layer "B.Cu")
		(net "PSU6_DC_OK")
	)
	(segment
		(start 33.92678 -445.236346)
		(end 35.784536 -445.236346)
		(width 0.1524)
		(layer "B.Cu")
		(net "PSU6_DC_OK")
	)
	(segment
		(start 37.447474 -371.04574)
		(end 36.249356 -372.243858)
		(width 0.1524)
		(layer "B.Cu")
		(net "PSU6_DC_OK")
	)
	(segment
		(start 27.313128 -377.163584)
		(end 27.313128 -438.622694)
		(width 0.1524)
		(layer "B.Cu")
		(net "PSU6_DC_OK")
	)
	(segment
		(start 26.132282 -192.678558)
		(end 24.32685 -190.873126)
		(width 0.1524)
		(layer "F.Cu")
		(net "PSU3_DC_OK")
	)
	(segment
		(start 32.829754 -191.550036)
		(end 31.701232 -192.678558)
		(width 0.1524)
		(layer "F.Cu")
		(net "PSU3_DC_OK")
	)
	(segment
		(start 35.53968 -191.550036)
		(end 32.829754 -191.550036)
		(width 0.1524)
		(layer "F.Cu")
		(net "PSU3_DC_OK")
	)
	(segment
		(start 31.701232 -192.678558)
		(end 26.132282 -192.678558)
		(width 0.1524)
		(layer "F.Cu")
		(net "PSU3_DC_OK")
	)
	(via
		(at 24.32685 -190.873126)
		(size 0.508)
		(drill 0.254)
		(layers "F.Cu" "B.Cu")
		(net "PSU3_DC_OK")
	)
	(segment
		(start 9.355074 -210.99399)
		(end 8.655558 -211.693506)
		(width 0.1524)
		(layer "B.Cu")
		(net "PSU3_DC_OK")
	)
	(segment
		(start 8.655558 -211.693506)
		(end 7.992364 -211.693506)
		(width 0.1524)
		(layer "B.Cu")
		(net "PSU3_DC_OK")
	)
	(segment
		(start 24.32685 -190.873126)
		(end 23.954232 -190.873126)
		(width 0.1524)
		(layer "B.Cu")
		(net "PSU3_DC_OK")
	)
	(segment
		(start 10.65784 -206.148178)
		(end 10.0076 -206.798418)
		(width 0.1524)
		(layer "B.Cu")
		(net "PSU3_DC_OK")
	)
	(segment
		(start 10.0076 -206.798418)
		(end 10.0076 -209.145886)
		(width 0.1524)
		(layer "B.Cu")
		(net "PSU3_DC_OK")
	)
	(segment
		(start 23.954232 -190.873126)
		(end 10.65784 -204.169518)
		(width 0.1524)
		(layer "B.Cu")
		(net "PSU3_DC_OK")
	)
	(segment
		(start 10.65784 -204.169518)
		(end 10.65784 -206.148178)
		(width 0.1524)
		(layer "B.Cu")
		(net "PSU3_DC_OK")
	)
	(segment
		(start 6.448806 -213.237064)
		(end 6.448806 -213.670642)
		(width 0.1524)
		(layer "B.Cu")
		(net "PSU3_DC_OK")
	)
	(segment
		(start 9.355074 -209.798412)
		(end 9.355074 -210.99399)
		(width 0.1524)
		(layer "B.Cu")
		(net "PSU3_DC_OK")
	)
	(segment
		(start 10.0076 -209.145886)
		(end 9.355074 -209.798412)
		(width 0.1524)
		(layer "B.Cu")
		(net "PSU3_DC_OK")
	)
	(segment
		(start 7.992364 -211.693506)
		(end 6.448806 -213.237064)
		(width 0.1524)
		(layer "B.Cu")
		(net "PSU3_DC_OK")
	)
	(segment
		(start 24.520144 -309.992522)
		(end 26.768044 -307.744622)
		(width 0.1524)
		(layer "F.Cu")
		(net "PSU5_DC_OK")
	)
	(segment
		(start 24.586692 -288.103818)
		(end 24.586692 -281.144472)
		(width 0.1524)
		(layer "F.Cu")
		(net "PSU5_DC_OK")
	)
	(segment
		(start 31.241492 -278.652478)
		(end 31.935166 -277.958804)
		(width 0.1524)
		(layer "F.Cu")
		(net "PSU5_DC_OK")
	)
	(segment
		(start 24.586692 -281.144472)
		(end 26.527252 -279.203912)
		(width 0.1524)
		(layer "F.Cu")
		(net "PSU5_DC_OK")
	)
	(segment
		(start 26.768044 -290.28517)
		(end 24.586692 -288.103818)
		(width 0.1524)
		(layer "F.Cu")
		(net "PSU5_DC_OK")
	)
	(segment
		(start 8.184896 -215.484456)
		(end 7.177786 -214.477346)
		(width 0.1524)
		(layer "F.Cu")
		(net "PSU5_DC_OK")
	)
	(segment
		(start 15.070836 -220.61424)
		(end 9.941052 -215.484456)
		(width 0.1524)
		(layer "F.Cu")
		(net "PSU5_DC_OK")
	)
	(segment
		(start 20.006818 -222.267018)
		(end 18.35404 -220.61424)
		(width 0.1524)
		(layer "F.Cu")
		(net "PSU5_DC_OK")
	)
	(segment
		(start 26.768044 -307.744622)
		(end 26.768044 -290.28517)
		(width 0.1524)
		(layer "F.Cu")
		(net "PSU5_DC_OK")
	)
	(segment
		(start 23.622 -248.034302)
		(end 23.622 -236.868462)
		(width 0.1524)
		(layer "F.Cu")
		(net "PSU5_DC_OK")
	)
	(segment
		(start 26.077672 -262.64235)
		(end 26.077672 -250.489974)
		(width 0.1524)
		(layer "F.Cu")
		(net "PSU5_DC_OK")
	)
	(segment
		(start 23.622 -236.868462)
		(end 25.364948 -235.125514)
		(width 0.1524)
		(layer "F.Cu")
		(net "PSU5_DC_OK")
	)
	(segment
		(start 25.364948 -235.125514)
		(end 25.364948 -224.166938)
		(width 0.1524)
		(layer "F.Cu")
		(net "PSU5_DC_OK")
	)
	(segment
		(start 24.520144 -333.915258)
		(end 24.520144 -309.992522)
		(width 0.1524)
		(layer "F.Cu")
		(net "PSU5_DC_OK")
	)
	(segment
		(start 7.177786 -214.477346)
		(end 7.177786 -212.399626)
		(width 0.1524)
		(layer "F.Cu")
		(net "PSU5_DC_OK")
	)
	(segment
		(start 31.935166 -277.958804)
		(end 31.935166 -268.499844)
		(width 0.1524)
		(layer "F.Cu")
		(net "PSU5_DC_OK")
	)
	(segment
		(start 26.077672 -250.489974)
		(end 23.622 -248.034302)
		(width 0.1524)
		(layer "F.Cu")
		(net "PSU5_DC_OK")
	)
	(segment
		(start 7.177786 -212.399626)
		(end 6.448806 -211.670646)
		(width 0.1524)
		(layer "F.Cu")
		(net "PSU5_DC_OK")
	)
	(segment
		(start 26.527252 -279.203912)
		(end 29.053282 -279.203912)
		(width 0.1524)
		(layer "F.Cu")
		(net "PSU5_DC_OK")
	)
	(segment
		(start 25.364948 -224.166938)
		(end 23.465028 -222.267018)
		(width 0.1524)
		(layer "F.Cu")
		(net "PSU5_DC_OK")
	)
	(segment
		(start 18.35404 -220.61424)
		(end 15.070836 -220.61424)
		(width 0.1524)
		(layer "F.Cu")
		(net "PSU5_DC_OK")
	)
	(segment
		(start 31.935166 -268.499844)
		(end 26.077672 -262.64235)
		(width 0.1524)
		(layer "F.Cu")
		(net "PSU5_DC_OK")
	)
	(segment
		(start 29.053282 -279.203912)
		(end 29.604716 -278.652478)
		(width 0.1524)
		(layer "F.Cu")
		(net "PSU5_DC_OK")
	)
	(segment
		(start 29.604716 -278.652478)
		(end 31.241492 -278.652478)
		(width 0.1524)
		(layer "F.Cu")
		(net "PSU5_DC_OK")
	)
	(segment
		(start 23.465028 -222.267018)
		(end 20.006818 -222.267018)
		(width 0.1524)
		(layer "F.Cu")
		(net "PSU5_DC_OK")
	)
	(segment
		(start 9.941052 -215.484456)
		(end 8.184896 -215.484456)
		(width 0.1524)
		(layer "F.Cu")
		(net "PSU5_DC_OK")
	)
	(segment
		(start 25.582626 -334.97774)
		(end 24.520144 -333.915258)
		(width 0.1524)
		(layer "F.Cu")
		(net "PSU5_DC_OK")
	)
	(via
		(at 25.582626 -334.97774)
		(size 0.508)
		(drill 0.254)
		(layers "F.Cu" "B.Cu")
		(net "PSU5_DC_OK")
	)
	(segment
		(start 26.63952 -351.3582)
		(end 32.051498 -356.770178)
		(width 0.1524)
		(layer "B.Cu")
		(net "PSU5_DC_OK")
	)
	(segment
		(start 32.051498 -356.770178)
		(end 36.71951 -356.770178)
		(width 0.1524)
		(layer "B.Cu")
		(net "PSU5_DC_OK")
	)
	(segment
		(start 26.63952 -336.034634)
		(end 26.63952 -351.3582)
		(width 0.1524)
		(layer "B.Cu")
		(net "PSU5_DC_OK")
	)
	(segment
		(start 25.582626 -334.97774)
		(end 26.63952 -336.034634)
		(width 0.1524)
		(layer "B.Cu")
		(net "PSU5_DC_OK")
	)
	(segment
		(start 36.71951 -356.770178)
		(end 37.075872 -357.12654)
		(width 0.1524)
		(layer "B.Cu")
		(net "PSU5_DC_OK")
	)
	(segment
		(start 37.075872 -366.813846)
		(end 35.53968 -368.350038)
		(width 0.1524)
		(layer "B.Cu")
		(net "PSU5_DC_OK")
	)
	(segment
		(start 37.075872 -357.12654)
		(end 37.075872 -366.813846)
		(width 0.1524)
		(layer "B.Cu")
		(net "PSU5_DC_OK")
	)
	(segment
		(start 7.259066 -214.860378)
		(end 6.448806 -215.670638)
		(width 0.127)
		(layer "In2.Cu")
		(net "PSU1_DC_OK")
	)
	(segment
		(start 32.33547 -20.920456)
		(end 29.660088 -20.920456)
		(width 0.127)
		(layer "In2.Cu")
		(net "PSU1_DC_OK")
	)
	(segment
		(start 29.660088 -20.920456)
		(end 24.42591 -26.154634)
		(width 0.127)
		(layer "In2.Cu")
		(net "PSU1_DC_OK")
	)
	(segment
		(start 33.038288 -20.217638)
		(end 32.33547 -20.920456)
		(width 0.127)
		(layer "In2.Cu")
		(net "PSU1_DC_OK")
	)
	(segment
		(start 24.123142 -105.61193)
		(end 24.123142 -106.289094)
		(width 0.127)
		(layer "In2.Cu")
		(net "PSU1_DC_OK")
	)
	(segment
		(start 24.123142 -106.289094)
		(end 23.51151 -106.900726)
		(width 0.127)
		(layer "In2.Cu")
		(net "PSU1_DC_OK")
	)
	(segment
		(start 35.53968 -14.750034)
		(end 35.536632 -14.750034)
		(width 0.127)
		(layer "In2.Cu")
		(net "PSU1_DC_OK")
	)
	(segment
		(start 33.038288 -17.248378)
		(end 33.038288 -20.217638)
		(width 0.127)
		(layer "In2.Cu")
		(net "PSU1_DC_OK")
	)
	(segment
		(start 7.99465 -201.443336)
		(end 7.259066 -202.17892)
		(width 0.127)
		(layer "In2.Cu")
		(net "PSU1_DC_OK")
	)
	(segment
		(start 7.259066 -202.17892)
		(end 7.259066 -214.860378)
		(width 0.127)
		(layer "In2.Cu")
		(net "PSU1_DC_OK")
	)
	(segment
		(start 10.48512 -201.443336)
		(end 7.99465 -201.443336)
		(width 0.127)
		(layer "In2.Cu")
		(net "PSU1_DC_OK")
	)
	(segment
		(start 22.204934 -91.288362)
		(end 22.204934 -103.693722)
		(width 0.127)
		(layer "In2.Cu")
		(net "PSU1_DC_OK")
	)
	(segment
		(start 22.204934 -103.693722)
		(end 24.123142 -105.61193)
		(width 0.127)
		(layer "In2.Cu")
		(net "PSU1_DC_OK")
	)
	(segment
		(start 35.536632 -14.750034)
		(end 33.038288 -17.248378)
		(width 0.127)
		(layer "In2.Cu")
		(net "PSU1_DC_OK")
	)
	(segment
		(start 24.42591 -89.067386)
		(end 22.204934 -91.288362)
		(width 0.127)
		(layer "In2.Cu")
		(net "PSU1_DC_OK")
	)
	(segment
		(start 14.674342 -176.833022)
		(end 14.674342 -197.254114)
		(width 0.127)
		(layer "In2.Cu")
		(net "PSU1_DC_OK")
	)
	(segment
		(start 14.674342 -197.254114)
		(end 10.48512 -201.443336)
		(width 0.127)
		(layer "In2.Cu")
		(net "PSU1_DC_OK")
	)
	(segment
		(start 23.51151 -167.995854)
		(end 14.674342 -176.833022)
		(width 0.127)
		(layer "In2.Cu")
		(net "PSU1_DC_OK")
	)
	(segment
		(start 24.42591 -26.154634)
		(end 24.42591 -89.067386)
		(width 0.127)
		(layer "In2.Cu")
		(net "PSU1_DC_OK")
	)
	(segment
		(start 23.51151 -106.900726)
		(end 23.51151 -167.995854)
		(width 0.127)
		(layer "In2.Cu")
		(net "PSU1_DC_OK")
	)
	(segment
		(start 17.99971 -218.510612)
		(end 14.28877 -218.510612)
		(width 0.1524)
		(layer "F.Cu")
		(net "PSU4_DC_OK")
	)
	(segment
		(start 14.28877 -218.510612)
		(end 8.448802 -212.670644)
		(width 0.1524)
		(layer "F.Cu")
		(net "PSU4_DC_OK")
	)
	(via
		(at 17.99971 -218.510612)
		(size 0.508)
		(drill 0.254)
		(layers "F.Cu" "B.Cu")
		(net "PSU4_DC_OK")
	)
	(segment
		(start 29.374338 -280.993342)
		(end 28.79471 -281.57297)
		(width 0.1524)
		(layer "B.Cu")
		(net "PSU4_DC_OK")
	)
	(segment
		(start 28.79471 -281.57297)
		(end 27.440128 -281.57297)
		(width 0.1524)
		(layer "B.Cu")
		(net "PSU4_DC_OK")
	)
	(segment
		(start 35.53968 -279.94991)
		(end 34.496248 -280.993342)
		(width 0.1524)
		(layer "B.Cu")
		(net "PSU4_DC_OK")
	)
	(segment
		(start 34.496248 -280.993342)
		(end 29.374338 -280.993342)
		(width 0.1524)
		(layer "B.Cu")
		(net "PSU4_DC_OK")
	)
	(segment
		(start 26.47315 -280.605992)
		(end 26.47315 -270.448024)
		(width 0.1524)
		(layer "B.Cu")
		(net "PSU4_DC_OK")
	)
	(segment
		(start 18.78076 -219.291662)
		(end 17.99971 -218.510612)
		(width 0.1524)
		(layer "B.Cu")
		(net "PSU4_DC_OK")
	)
	(segment
		(start 27.440128 -281.57297)
		(end 26.47315 -280.605992)
		(width 0.1524)
		(layer "B.Cu")
		(net "PSU4_DC_OK")
	)
	(segment
		(start 21.33727 -238.287306)
		(end 18.78076 -235.730796)
		(width 0.1524)
		(layer "B.Cu")
		(net "PSU4_DC_OK")
	)
	(segment
		(start 18.78076 -235.730796)
		(end 18.78076 -219.291662)
		(width 0.1524)
		(layer "B.Cu")
		(net "PSU4_DC_OK")
	)
	(segment
		(start 26.47315 -270.448024)
		(end 21.33727 -265.312144)
		(width 0.1524)
		(layer "B.Cu")
		(net "PSU4_DC_OK")
	)
	(segment
		(start 21.33727 -265.312144)
		(end 21.33727 -238.287306)
		(width 0.1524)
		(layer "B.Cu")
		(net "PSU4_DC_OK")
	)
	(segment
		(start 7.045706 -210.670648)
		(end 1.948942 -210.670648)
		(width 0.1524)
		(layer "F.Cu")
		(net "PSU6_AC_OK")
	)
	(segment
		(start 17.99971 -220.034612)
		(end 17.97431 -220.060012)
		(width 0.1524)
		(layer "F.Cu")
		(net "PSU6_AC_OK")
	)
	(segment
		(start 8.566404 -213.923626)
		(end 7.693152 -213.050374)
		(width 0.1524)
		(layer "F.Cu")
		(net "PSU6_AC_OK")
	)
	(segment
		(start 15.089124 -220.060012)
		(end 8.952738 -213.923626)
		(width 0.1524)
		(layer "F.Cu")
		(net "PSU6_AC_OK")
	)
	(segment
		(start 7.693152 -213.050374)
		(end 7.693152 -211.318094)
		(width 0.1524)
		(layer "F.Cu")
		(net "PSU6_AC_OK")
	)
	(segment
		(start 7.693152 -211.318094)
		(end 7.045706 -210.670648)
		(width 0.1524)
		(layer "F.Cu")
		(net "PSU6_AC_OK")
	)
	(segment
		(start 17.97431 -220.060012)
		(end 15.089124 -220.060012)
		(width 0.1524)
		(layer "F.Cu")
		(net "PSU6_AC_OK")
	)
	(segment
		(start 8.952738 -213.923626)
		(end 8.566404 -213.923626)
		(width 0.1524)
		(layer "F.Cu")
		(net "PSU6_AC_OK")
	)
	(via
		(at 17.99971 -220.034612)
		(size 0.508)
		(drill 0.254)
		(layers "F.Cu" "B.Cu")
		(net "PSU6_AC_OK")
	)
	(segment
		(start 17.32534 -254.187706)
		(end 15.889986 -252.752352)
		(width 0.1524)
		(layer "B.Cu")
		(net "PSU6_AC_OK")
	)
	(segment
		(start 26.662888 -441.678822)
		(end 25.335484 -440.351418)
		(width 0.1524)
		(layer "B.Cu")
		(net "PSU6_AC_OK")
	)
	(segment
		(start 25.905968 -318.699642)
		(end 25.905968 -288.399474)
		(width 0.1524)
		(layer "B.Cu")
		(net "PSU6_AC_OK")
	)
	(segment
		(start 21.906738 -279.985724)
		(end 17.32534 -275.404326)
		(width 0.1524)
		(layer "B.Cu")
		(net "PSU6_AC_OK")
	)
	(segment
		(start 23.461726 -378.762768)
		(end 23.461726 -359.81259)
		(width 0.1524)
		(layer "B.Cu")
		(net "PSU6_AC_OK")
	)
	(segment
		(start 15.889986 -252.752352)
		(end 15.889986 -222.144336)
		(width 0.1524)
		(layer "B.Cu")
		(net "PSU6_AC_OK")
	)
	(segment
		(start 25.335484 -380.636526)
		(end 23.461726 -378.762768)
		(width 0.1524)
		(layer "B.Cu")
		(net "PSU6_AC_OK")
	)
	(segment
		(start 23.461726 -359.81259)
		(end 21.459444 -357.810308)
		(width 0.1524)
		(layer "B.Cu")
		(net "PSU6_AC_OK")
	)
	(segment
		(start 25.335484 -440.351418)
		(end 25.335484 -380.636526)
		(width 0.1524)
		(layer "B.Cu")
		(net "PSU6_AC_OK")
	)
	(segment
		(start 25.905968 -288.399474)
		(end 21.906738 -284.400244)
		(width 0.1524)
		(layer "B.Cu")
		(net "PSU6_AC_OK")
	)
	(segment
		(start 17.32534 -275.404326)
		(end 17.32534 -254.187706)
		(width 0.1524)
		(layer "B.Cu")
		(net "PSU6_AC_OK")
	)
	(segment
		(start 21.459444 -323.146166)
		(end 25.905968 -318.699642)
		(width 0.1524)
		(layer "B.Cu")
		(net "PSU6_AC_OK")
	)
	(segment
		(start 27.46375 -457.002896)
		(end 26.662888 -456.202034)
		(width 0.1524)
		(layer "B.Cu")
		(net "PSU6_AC_OK")
	)
	(segment
		(start 21.906738 -284.400244)
		(end 21.906738 -279.985724)
		(width 0.1524)
		(layer "B.Cu")
		(net "PSU6_AC_OK")
	)
	(segment
		(start 26.662888 -456.202034)
		(end 26.662888 -441.678822)
		(width 0.1524)
		(layer "B.Cu")
		(net "PSU6_AC_OK")
	)
	(segment
		(start 30.45968 -459.289912)
		(end 28.172664 -457.002896)
		(width 0.1524)
		(layer "B.Cu")
		(net "PSU6_AC_OK")
	)
	(segment
		(start 21.459444 -357.810308)
		(end 21.459444 -323.146166)
		(width 0.1524)
		(layer "B.Cu")
		(net "PSU6_AC_OK")
	)
	(segment
		(start 28.172664 -457.002896)
		(end 27.46375 -457.002896)
		(width 0.1524)
		(layer "B.Cu")
		(net "PSU6_AC_OK")
	)
	(segment
		(start 15.889986 -222.144336)
		(end 17.99971 -220.034612)
		(width 0.1524)
		(layer "B.Cu")
		(net "PSU6_AC_OK")
	)
	(segment
		(start 14.450314 -221.415864)
		(end 10.475722 -217.441272)
		(width 0.1524)
		(layer "F.Cu")
		(net "PSU3_AC_OK")
	)
	(segment
		(start 5.04952 -214.771224)
		(end 3.948938 -213.670642)
		(width 0.1524)
		(layer "F.Cu")
		(net "PSU3_AC_OK")
	)
	(segment
		(start 16.139668 -221.415864)
		(end 14.450314 -221.415864)
		(width 0.1524)
		(layer "F.Cu")
		(net "PSU3_AC_OK")
	)
	(segment
		(start 17.892014 -223.16821)
		(end 16.139668 -221.415864)
		(width 0.1524)
		(layer "F.Cu")
		(net "PSU3_AC_OK")
	)
	(segment
		(start 22.691852 -223.086676)
		(end 22.610318 -223.16821)
		(width 0.1524)
		(layer "F.Cu")
		(net "PSU3_AC_OK")
	)
	(segment
		(start 6.948932 -216.786714)
		(end 5.956046 -216.786714)
		(width 0.1524)
		(layer "F.Cu")
		(net "PSU3_AC_OK")
	)
	(segment
		(start 10.475722 -217.441272)
		(end 7.60349 -217.441272)
		(width 0.1524)
		(layer "F.Cu")
		(net "PSU3_AC_OK")
	)
	(segment
		(start 5.956046 -216.786714)
		(end 5.04952 -215.880188)
		(width 0.1524)
		(layer "F.Cu")
		(net "PSU3_AC_OK")
	)
	(segment
		(start 5.04952 -215.880188)
		(end 5.04952 -214.771224)
		(width 0.1524)
		(layer "F.Cu")
		(net "PSU3_AC_OK")
	)
	(segment
		(start 7.60349 -217.441272)
		(end 6.948932 -216.786714)
		(width 0.1524)
		(layer "F.Cu")
		(net "PSU3_AC_OK")
	)
	(segment
		(start 22.610318 -223.16821)
		(end 17.892014 -223.16821)
		(width 0.1524)
		(layer "F.Cu")
		(net "PSU3_AC_OK")
	)
	(via
		(at 22.691852 -223.086676)
		(size 0.508)
		(drill 0.254)
		(layers "F.Cu" "B.Cu")
		(net "PSU3_AC_OK")
	)
	(segment
		(start 26.552652 -197.251828)
		(end 26.552652 -196.58203)
		(width 0.1524)
		(layer "B.Cu")
		(net "PSU3_AC_OK")
	)
	(segment
		(start 29.044646 -194.090036)
		(end 30.45968 -194.090036)
		(width 0.1524)
		(layer "B.Cu")
		(net "PSU3_AC_OK")
	)
	(segment
		(start 22.691852 -223.086676)
		(end 22.81428 -222.964248)
		(width 0.1524)
		(layer "B.Cu")
		(net "PSU3_AC_OK")
	)
	(segment
		(start 22.81428 -200.9902)
		(end 26.552652 -197.251828)
		(width 0.1524)
		(layer "B.Cu")
		(net "PSU3_AC_OK")
	)
	(segment
		(start 22.81428 -222.964248)
		(end 22.81428 -200.9902)
		(width 0.1524)
		(layer "B.Cu")
		(net "PSU3_AC_OK")
	)
	(segment
		(start 26.552652 -196.58203)
		(end 29.044646 -194.090036)
		(width 0.1524)
		(layer "B.Cu")
		(net "PSU3_AC_OK")
	)
	(segment
		(start 17.99971 -226.089464)
		(end 14.431518 -226.089464)
		(width 0.1524)
		(layer "F.Cu")
		(net "PSU4_AC_OK")
	)
	(segment
		(start 4.33197 -216.84869)
		(end 3.816604 -216.84869)
		(width 0.1524)
		(layer "F.Cu")
		(net "PSU4_AC_OK")
	)
	(segment
		(start 11.728704 -222.71863)
		(end 8.731758 -219.721684)
		(width 0.1524)
		(layer "F.Cu")
		(net "PSU4_AC_OK")
	)
	(segment
		(start 14.431518 -226.089464)
		(end 11.728704 -223.38665)
		(width 0.1524)
		(layer "F.Cu")
		(net "PSU4_AC_OK")
	)
	(segment
		(start 2.73812 -215.770206)
		(end 2.73812 -213.459822)
		(width 0.1524)
		(layer "F.Cu")
		(net "PSU4_AC_OK")
	)
	(segment
		(start 6.899402 -218.767152)
		(end 6.250432 -218.767152)
		(width 0.1524)
		(layer "F.Cu")
		(net "PSU4_AC_OK")
	)
	(segment
		(start 8.731758 -219.721684)
		(end 7.853934 -219.721684)
		(width 0.1524)
		(layer "F.Cu")
		(net "PSU4_AC_OK")
	)
	(segment
		(start 7.853934 -219.721684)
		(end 6.899402 -218.767152)
		(width 0.1524)
		(layer "F.Cu")
		(net "PSU4_AC_OK")
	)
	(segment
		(start 6.250432 -218.767152)
		(end 4.33197 -216.84869)
		(width 0.1524)
		(layer "F.Cu")
		(net "PSU4_AC_OK")
	)
	(segment
		(start 2.73812 -213.459822)
		(end 1.948942 -212.670644)
		(width 0.1524)
		(layer "F.Cu")
		(net "PSU4_AC_OK")
	)
	(segment
		(start 3.816604 -216.84869)
		(end 2.73812 -215.770206)
		(width 0.1524)
		(layer "F.Cu")
		(net "PSU4_AC_OK")
	)
	(segment
		(start 11.728704 -223.38665)
		(end 11.728704 -222.71863)
		(width 0.1524)
		(layer "F.Cu")
		(net "PSU4_AC_OK")
	)
	(via
		(at 17.99971 -226.089464)
		(size 0.508)
		(drill 0.254)
		(layers "F.Cu" "B.Cu")
		(net "PSU4_AC_OK")
	)
	(segment
		(start 16.9545 -227.134674)
		(end 17.99971 -226.089464)
		(width 0.1524)
		(layer "B.Cu")
		(net "PSU4_AC_OK")
	)
	(segment
		(start 16.9545 -236.180376)
		(end 16.9545 -227.134674)
		(width 0.1524)
		(layer "B.Cu")
		(net "PSU4_AC_OK")
	)
	(segment
		(start 29.22778 -282.48991)
		(end 28.887674 -282.830016)
		(width 0.1524)
		(layer "B.Cu")
		(net "PSU4_AC_OK")
	)
	(segment
		(start 28.887674 -282.830016)
		(end 27.115008 -282.830016)
		(width 0.1524)
		(layer "B.Cu")
		(net "PSU4_AC_OK")
	)
	(segment
		(start 27.115008 -282.830016)
		(end 25.646634 -281.361642)
		(width 0.1524)
		(layer "B.Cu")
		(net "PSU4_AC_OK")
	)
	(segment
		(start 20.897342 -265.62431)
		(end 20.897342 -240.123218)
		(width 0.1524)
		(layer "B.Cu")
		(net "PSU4_AC_OK")
	)
	(segment
		(start 25.646634 -270.373602)
		(end 20.897342 -265.62431)
		(width 0.1524)
		(layer "B.Cu")
		(net "PSU4_AC_OK")
	)
	(segment
		(start 20.897342 -240.123218)
		(end 16.9545 -236.180376)
		(width 0.1524)
		(layer "B.Cu")
		(net "PSU4_AC_OK")
	)
	(segment
		(start 25.646634 -281.361642)
		(end 25.646634 -270.373602)
		(width 0.1524)
		(layer "B.Cu")
		(net "PSU4_AC_OK")
	)
	(segment
		(start 30.45968 -282.48991)
		(end 29.22778 -282.48991)
		(width 0.1524)
		(layer "B.Cu")
		(net "PSU4_AC_OK")
	)
	(segment
		(start 24.093678 -105.689908)
		(end 23.678642 -106.104944)
		(width 0.1524)
		(layer "F.Cu")
		(net "PSU2_AC_OK")
	)
	(segment
		(start 30.45968 -105.689908)
		(end 24.093678 -105.689908)
		(width 0.1524)
		(layer "F.Cu")
		(net "PSU2_AC_OK")
	)
	(via
		(at 23.678642 -106.104944)
		(size 0.508)
		(drill 0.254)
		(layers "F.Cu" "B.Cu")
		(net "PSU2_AC_OK")
	)
	(segment
		(start 11.522456 -199.938894)
		(end 14.316202 -197.145148)
		(width 0.127)
		(layer "In2.Cu")
		(net "PSU2_AC_OK")
	)
	(segment
		(start 23.157942 -167.882316)
		(end 23.157942 -106.625644)
		(width 0.127)
		(layer "In2.Cu")
		(net "PSU2_AC_OK")
	)
	(segment
		(start 8.095488 -199.938894)
		(end 11.522456 -199.938894)
		(width 0.127)
		(layer "In2.Cu")
		(net "PSU2_AC_OK")
	)
	(segment
		(start 14.316202 -197.145148)
		(end 14.316202 -176.724056)
		(width 0.127)
		(layer "In2.Cu")
		(net "PSU2_AC_OK")
	)
	(segment
		(start 3.655314 -216.377012)
		(end 4.247642 -216.377012)
		(width 0.127)
		(layer "In2.Cu")
		(net "PSU2_AC_OK")
	)
	(segment
		(start 4.247642 -216.377012)
		(end 5.678678 -214.945976)
		(width 0.127)
		(layer "In2.Cu")
		(net "PSU2_AC_OK")
	)
	(segment
		(start 5.678678 -201.31659)
		(end 6.132322 -200.862946)
		(width 0.127)
		(layer "In2.Cu")
		(net "PSU2_AC_OK")
	)
	(segment
		(start 23.157942 -106.625644)
		(end 23.678642 -106.104944)
		(width 0.127)
		(layer "In2.Cu")
		(net "PSU2_AC_OK")
	)
	(segment
		(start 1.948942 -214.67064)
		(end 3.655314 -216.377012)
		(width 0.127)
		(layer "In2.Cu")
		(net "PSU2_AC_OK")
	)
	(segment
		(start 6.132322 -200.862946)
		(end 7.171436 -200.862946)
		(width 0.127)
		(layer "In2.Cu")
		(net "PSU2_AC_OK")
	)
	(segment
		(start 14.316202 -176.724056)
		(end 23.157942 -167.882316)
		(width 0.127)
		(layer "In2.Cu")
		(net "PSU2_AC_OK")
	)
	(segment
		(start 7.171436 -200.862946)
		(end 8.095488 -199.938894)
		(width 0.127)
		(layer "In2.Cu")
		(net "PSU2_AC_OK")
	)
	(segment
		(start 5.678678 -214.945976)
		(end 5.678678 -201.31659)
		(width 0.127)
		(layer "In2.Cu")
		(net "PSU2_AC_OK")
	)
	(segment
		(start 6.188202 -214.868506)
		(end 4.952238 -213.632542)
		(width 0.1524)
		(layer "F.Cu")
		(net "PSU5_AC_OK")
	)
	(segment
		(start 17.4371 -220.996002)
		(end 14.758924 -220.996002)
		(width 0.1524)
		(layer "F.Cu")
		(net "PSU5_AC_OK")
	)
	(segment
		(start 7.76478 -215.913462)
		(end 6.719824 -214.868506)
		(width 0.1524)
		(layer "F.Cu")
		(net "PSU5_AC_OK")
	)
	(segment
		(start 4.952238 -213.632542)
		(end 4.952238 -212.673946)
		(width 0.1524)
		(layer "F.Cu")
		(net "PSU5_AC_OK")
	)
	(segment
		(start 6.719824 -214.868506)
		(end 6.188202 -214.868506)
		(width 0.1524)
		(layer "F.Cu")
		(net "PSU5_AC_OK")
	)
	(segment
		(start 9.676384 -215.913462)
		(end 7.76478 -215.913462)
		(width 0.1524)
		(layer "F.Cu")
		(net "PSU5_AC_OK")
	)
	(segment
		(start 14.758924 -220.996002)
		(end 9.676384 -215.913462)
		(width 0.1524)
		(layer "F.Cu")
		(net "PSU5_AC_OK")
	)
	(segment
		(start 4.952238 -212.673946)
		(end 3.948938 -211.670646)
		(width 0.1524)
		(layer "F.Cu")
		(net "PSU5_AC_OK")
	)
	(segment
		(start 17.99971 -221.558612)
		(end 17.4371 -220.996002)
		(width 0.1524)
		(layer "F.Cu")
		(net "PSU5_AC_OK")
	)
	(via
		(at 17.99971 -221.558612)
		(size 0.508)
		(drill 0.254)
		(layers "F.Cu" "B.Cu")
		(net "PSU5_AC_OK")
	)
	(segment
		(start 22.310344 -356.24897)
		(end 26.200608 -360.139234)
		(width 0.1524)
		(layer "B.Cu")
		(net "PSU5_AC_OK")
	)
	(segment
		(start 26.333704 -319.584578)
		(end 22.310344 -323.607938)
		(width 0.1524)
		(layer "B.Cu")
		(net "PSU5_AC_OK")
	)
	(segment
		(start 26.200608 -364.92942)
		(end 29.253688 -367.9825)
		(width 0.1524)
		(layer "B.Cu")
		(net "PSU5_AC_OK")
	)
	(segment
		(start 26.200608 -360.139234)
		(end 26.200608 -364.92942)
		(width 0.1524)
		(layer "B.Cu")
		(net "PSU5_AC_OK")
	)
	(segment
		(start 22.351492 -284.175962)
		(end 26.333704 -288.158174)
		(width 0.1524)
		(layer "B.Cu")
		(net "PSU5_AC_OK")
	)
	(segment
		(start 16.358616 -252.310646)
		(end 17.86001 -253.81204)
		(width 0.1524)
		(layer "B.Cu")
		(net "PSU5_AC_OK")
	)
	(segment
		(start 22.310344 -323.607938)
		(end 22.310344 -356.24897)
		(width 0.1524)
		(layer "B.Cu")
		(net "PSU5_AC_OK")
	)
	(segment
		(start 22.351492 -279.638506)
		(end 22.351492 -284.175962)
		(width 0.1524)
		(layer "B.Cu")
		(net "PSU5_AC_OK")
	)
	(segment
		(start 29.253688 -369.684046)
		(end 30.45968 -370.890038)
		(width 0.1524)
		(layer "B.Cu")
		(net "PSU5_AC_OK")
	)
	(segment
		(start 29.253688 -367.9825)
		(end 29.253688 -369.684046)
		(width 0.1524)
		(layer "B.Cu")
		(net "PSU5_AC_OK")
	)
	(segment
		(start 16.358616 -223.199706)
		(end 16.358616 -252.310646)
		(width 0.1524)
		(layer "B.Cu")
		(net "PSU5_AC_OK")
	)
	(segment
		(start 26.333704 -288.158174)
		(end 26.333704 -319.584578)
		(width 0.1524)
		(layer "B.Cu")
		(net "PSU5_AC_OK")
	)
	(segment
		(start 17.99971 -221.558612)
		(end 16.358616 -223.199706)
		(width 0.1524)
		(layer "B.Cu")
		(net "PSU5_AC_OK")
	)
	(segment
		(start 17.86001 -253.81204)
		(end 17.86001 -275.147024)
		(width 0.1524)
		(layer "B.Cu")
		(net "PSU5_AC_OK")
	)
	(segment
		(start 17.86001 -275.147024)
		(end 22.351492 -279.638506)
		(width 0.1524)
		(layer "B.Cu")
		(net "PSU5_AC_OK")
	)
	(segment
		(start 21.84781 -91.17838)
		(end 21.84781 -105.588816)
		(width 0.127)
		(layer "In2.Cu")
		(net "PSU1_AC_OK")
	)
	(segment
		(start 6.008116 -200.414636)
		(end 5.109972 -201.31278)
		(width 0.127)
		(layer "In2.Cu")
		(net "PSU1_AC_OK")
	)
	(segment
		(start 5.109972 -214.509604)
		(end 3.948938 -215.670638)
		(width 0.127)
		(layer "In2.Cu")
		(net "PSU1_AC_OK")
	)
	(segment
		(start 6.804406 -200.414636)
		(end 6.008116 -200.414636)
		(width 0.127)
		(layer "In2.Cu")
		(net "PSU1_AC_OK")
	)
	(segment
		(start 21.84781 -105.588816)
		(end 22.816058 -106.557064)
		(width 0.127)
		(layer "In2.Cu")
		(net "PSU1_AC_OK")
	)
	(segment
		(start 7.78891 -199.430132)
		(end 6.804406 -200.414636)
		(width 0.127)
		(layer "In2.Cu")
		(net "PSU1_AC_OK")
	)
	(segment
		(start 22.816058 -106.557064)
		(end 22.816058 -167.757094)
		(width 0.127)
		(layer "In2.Cu")
		(net "PSU1_AC_OK")
	)
	(segment
		(start 13.98016 -196.659246)
		(end 11.209274 -199.430132)
		(width 0.127)
		(layer "In2.Cu")
		(net "PSU1_AC_OK")
	)
	(segment
		(start 29.083762 -21.029676)
		(end 24.091392 -26.022046)
		(width 0.127)
		(layer "In2.Cu")
		(net "PSU1_AC_OK")
	)
	(segment
		(start 24.091392 -88.934798)
		(end 21.84781 -91.17838)
		(width 0.127)
		(layer "In2.Cu")
		(net "PSU1_AC_OK")
	)
	(segment
		(start 22.816058 -167.757094)
		(end 13.98016 -176.592992)
		(width 0.127)
		(layer "In2.Cu")
		(net "PSU1_AC_OK")
	)
	(segment
		(start 5.109972 -201.31278)
		(end 5.109972 -214.509604)
		(width 0.127)
		(layer "In2.Cu")
		(net "PSU1_AC_OK")
	)
	(segment
		(start 24.091392 -26.022046)
		(end 24.091392 -88.934798)
		(width 0.127)
		(layer "In2.Cu")
		(net "PSU1_AC_OK")
	)
	(segment
		(start 11.209274 -199.430132)
		(end 7.78891 -199.430132)
		(width 0.127)
		(layer "In2.Cu")
		(net "PSU1_AC_OK")
	)
	(segment
		(start 29.083762 -18.665952)
		(end 29.083762 -21.029676)
		(width 0.127)
		(layer "In2.Cu")
		(net "PSU1_AC_OK")
	)
	(segment
		(start 13.98016 -176.592992)
		(end 13.98016 -196.659246)
		(width 0.127)
		(layer "In2.Cu")
		(net "PSU1_AC_OK")
	)
	(segment
		(start 30.45968 -17.290034)
		(end 29.083762 -18.665952)
		(width 0.127)
		(layer "In2.Cu")
		(net "PSU1_AC_OK")
	)
	(segment
		(start 9.474708 -321.669918)
		(end 11.705844 -319.438782)
		(width 0.1524)
		(layer "F.Cu")
		(net "FAN_PWM")
	)
	(segment
		(start 11.705844 -319.438782)
		(end 12.986258 -319.438782)
		(width 0.1524)
		(layer "F.Cu")
		(net "FAN_PWM")
	)
	(segment
		(start 13.020802 -319.404238)
		(end 12.986258 -319.438782)
		(width 0.1524)
		(layer "F.Cu")
		(net "FAN_PWM")
	)
	(segment
		(start 8.449818 -321.669918)
		(end 9.474708 -321.669918)
		(width 0.1524)
		(layer "F.Cu")
		(net "FAN_PWM")
	)
	(segment
		(start 13.020802 -318.358012)
		(end 13.020802 -319.404238)
		(width 0.1524)
		(layer "F.Cu")
		(net "FAN_PWM")
	)
	(segment
		(start 8.877046 -328.78776)
		(end 9.523222 -329.433936)
		(width 0.1524)
		(layer "B.Cu")
		(net "FAN_PWM")
	)
	(segment
		(start 5.944108 -423.299636)
		(end 5.944108 -423.893996)
		(width 0.1524)
		(layer "B.Cu")
		(net "FAN_PWM")
	)
	(segment
		(start 6.698488 -323.677534)
		(end 6.32206 -323.677534)
		(width 0.1524)
		(layer "B.Cu")
		(net "FAN_PWM")
	)
	(segment
		(start 22.236684 -382.497076)
		(end 22.236684 -407.00706)
		(width 0.1524)
		(layer "B.Cu")
		(net "FAN_PWM")
	)
	(segment
		(start 7.691374 -322.428362)
		(end 7.691374 -322.684648)
		(width 0.1524)
		(layer "B.Cu")
		(net "FAN_PWM")
	)
	(segment
		(start 9.523222 -329.433936)
		(end 9.523222 -343.273888)
		(width 0.1524)
		(layer "B.Cu")
		(net "FAN_PWM")
	)
	(segment
		(start 7.07136 -327.568052)
		(end 8.291068 -328.78776)
		(width 0.1524)
		(layer "B.Cu")
		(net "FAN_PWM")
	)
	(segment
		(start 9.523222 -343.273888)
		(end 12.226798 -345.977464)
		(width 0.1524)
		(layer "B.Cu")
		(net "FAN_PWM")
	)
	(segment
		(start 5.944108 -436.49392)
		(end 7.450074 -434.987954)
		(width 0.1524)
		(layer "B.Cu")
		(net "FAN_PWM")
	)
	(segment
		(start 6.32206 -323.677534)
		(end 5.308092 -324.691502)
		(width 0.1524)
		(layer "B.Cu")
		(net "FAN_PWM")
	)
	(segment
		(start 5.308092 -326.627744)
		(end 6.2484 -327.568052)
		(width 0.1524)
		(layer "B.Cu")
		(net "FAN_PWM")
	)
	(segment
		(start 12.226798 -372.48719)
		(end 22.236684 -382.497076)
		(width 0.1524)
		(layer "B.Cu")
		(net "FAN_PWM")
	)
	(segment
		(start 8.449818 -321.669918)
		(end 7.691374 -322.428362)
		(width 0.1524)
		(layer "B.Cu")
		(net "FAN_PWM")
	)
	(segment
		(start 7.691374 -322.684648)
		(end 6.698488 -323.677534)
		(width 0.1524)
		(layer "B.Cu")
		(net "FAN_PWM")
	)
	(segment
		(start 7.450074 -434.987954)
		(end 7.450074 -425.399962)
		(width 0.1524)
		(layer "B.Cu")
		(net "FAN_PWM")
	)
	(segment
		(start 22.236684 -407.00706)
		(end 5.944108 -423.299636)
		(width 0.1524)
		(layer "B.Cu")
		(net "FAN_PWM")
	)
	(segment
		(start 8.291068 -328.78776)
		(end 8.877046 -328.78776)
		(width 0.1524)
		(layer "B.Cu")
		(net "FAN_PWM")
	)
	(segment
		(start 12.226798 -345.977464)
		(end 12.226798 -372.48719)
		(width 0.1524)
		(layer "B.Cu")
		(net "FAN_PWM")
	)
	(segment
		(start 7.450074 -425.399962)
		(end 5.944108 -423.893996)
		(width 0.1524)
		(layer "B.Cu")
		(net "FAN_PWM")
	)
	(segment
		(start 6.2484 -327.568052)
		(end 7.07136 -327.568052)
		(width 0.1524)
		(layer "B.Cu")
		(net "FAN_PWM")
	)
	(segment
		(start 5.308092 -324.691502)
		(end 5.308092 -326.627744)
		(width 0.1524)
		(layer "B.Cu")
		(net "FAN_PWM")
	)
	(segment
		(start 12.784074 -330.08062)
		(end 12.784074 -329.042776)
		(width 0.508)
		(layer "F.Cu")
		(net "P3V3")
	)
	(segment
		(start 14.923008 -329.150726)
		(end 14.923008 -329.123802)
		(width 0.508)
		(layer "F.Cu")
		(net "P3V3")
	)
	(segment
		(start 19.954748 -338.633562)
		(end 20.660614 -337.927696)
		(width 0.508)
		(layer "F.Cu")
		(net "P3V3")
	)
	(segment
		(start 11.93292 -339.304122)
		(end 12.683744 -338.553298)
		(width 0.508)
		(layer "F.Cu")
		(net "P3V3")
	)
	(segment
		(start 14.357858 -328.585576)
		(end 14.923008 -329.150726)
		(width 0.508)
		(layer "F.Cu")
		(net "P3V3")
	)
	(segment
		(start 3.297936 -337.691222)
		(end 1.949958 -339.0392)
		(width 0.508)
		(layer "F.Cu")
		(net "P3V3")
	)
	(segment
		(start 12.683744 -338.553298)
		(end 12.683744 -333.081122)
		(width 0.508)
		(layer "F.Cu")
		(net "P3V3")
	)
	(segment
		(start 11.93292 -339.304122)
		(end 12.689586 -340.060788)
		(width 0.508)
		(layer "F.Cu")
		(net "P3V3")
	)
	(segment
		(start 10.198354 -338.712556)
		(end 8.1915 -338.712556)
		(width 0.508)
		(layer "F.Cu")
		(net "P3V3")
	)
	(segment
		(start 7.170166 -337.691222)
		(end 3.297936 -337.691222)
		(width 0.508)
		(layer "F.Cu")
		(net "P3V3")
	)
	(segment
		(start 12.689586 -340.060788)
		(end 13.265658 -340.060788)
		(width 0.508)
		(layer "F.Cu")
		(net "P3V3")
	)
	(segment
		(start 17.621758 -328.585068)
		(end 18.264886 -329.228196)
		(width 0.508)
		(layer "F.Cu")
		(net "P3V3")
	)
	(segment
		(start 11.93292 -339.304122)
		(end 10.78992 -339.304122)
		(width 0.508)
		(layer "F.Cu")
		(net "P3V3")
	)
	(segment
		(start 18.264886 -329.228196)
		(end 18.264886 -330.05522)
		(width 0.508)
		(layer "F.Cu")
		(net "P3V3")
	)
	(segment
		(start 12.784074 -329.042776)
		(end 13.241274 -328.585576)
		(width 0.508)
		(layer "F.Cu")
		(net "P3V3")
	)
	(segment
		(start 12.360656 -330.08062)
		(end 12.784074 -330.08062)
		(width 0.508)
		(layer "F.Cu")
		(net "P3V3")
	)
	(segment
		(start 12.13358 -330.307696)
		(end 12.360656 -330.08062)
		(width 0.508)
		(layer "F.Cu")
		(net "P3V3")
	)
	(segment
		(start 20.660614 -332.917292)
		(end 20.660614 -331.694536)
		(width 0.508)
		(layer "F.Cu")
		(net "P3V3")
	)
	(segment
		(start 1.949958 -339.0392)
		(end 1.949958 -339.669882)
		(width 0.508)
		(layer "F.Cu")
		(net "P3V3")
	)
	(segment
		(start 8.1915 -338.712556)
		(end 7.170166 -337.691222)
		(width 0.508)
		(layer "F.Cu")
		(net "P3V3")
	)
	(segment
		(start 10.78992 -339.304122)
		(end 10.198354 -338.712556)
		(width 0.508)
		(layer "F.Cu")
		(net "P3V3")
	)
	(segment
		(start 15.461742 -328.585068)
		(end 17.621758 -328.585068)
		(width 0.508)
		(layer "F.Cu")
		(net "P3V3")
	)
	(segment
		(start 20.660614 -331.694536)
		(end 19.021298 -330.05522)
		(width 0.508)
		(layer "F.Cu")
		(net "P3V3")
	)
	(segment
		(start 13.241274 -328.585576)
		(end 14.357858 -328.585576)
		(width 0.508)
		(layer "F.Cu")
		(net "P3V3")
	)
	(segment
		(start 12.683744 -333.081122)
		(end 12.13358 -332.530958)
		(width 0.508)
		(layer "F.Cu")
		(net "P3V3")
	)
	(segment
		(start 19.021298 -330.05522)
		(end 18.264886 -330.05522)
		(width 0.508)
		(layer "F.Cu")
		(net "P3V3")
	)
	(segment
		(start 14.923008 -329.123802)
		(end 15.461742 -328.585068)
		(width 0.508)
		(layer "F.Cu")
		(net "P3V3")
	)
	(segment
		(start 12.13358 -332.530958)
		(end 12.13358 -330.307696)
		(width 0.508)
		(layer "F.Cu")
		(net "P3V3")
	)
	(segment
		(start 14.923008 -330.097384)
		(end 14.923008 -329.150726)
		(width 0.508)
		(layer "F.Cu")
		(net "P3V3")
	)
	(segment
		(start 20.660614 -337.927696)
		(end 20.660614 -332.917292)
		(width 0.508)
		(layer "F.Cu")
		(net "P3V3")
	)
	(segment
		(start 18.948908 -338.633562)
		(end 19.954748 -338.633562)
		(width 0.508)
		(layer "F.Cu")
		(net "P3V3")
	)
	(via
		(at 11.93292 -339.304122)
		(size 0.508)
		(drill 0.254)
		(layers "F.Cu" "B.Cu")
		(net "P3V3")
	)
	(via
		(at 20.660614 -332.917292)
		(size 0.762)
		(drill 0.381)
		(layers "F.Cu" "B.Cu")
		(net "P3V3")
	)
	(via
		(at 12.683744 -333.081122)
		(size 0.762)
		(drill 0.381)
		(layers "F.Cu" "B.Cu")
		(net "P3V3")
	)
	(segment
		(start 18.256758 -334.823562)
		(end 16.55572 -336.5246)
		(width 0.1524)
		(layer "F.Cu")
		(net "I2C_PDB_SDA")
	)
	(segment
		(start 13.173964 -342.301322)
		(end 11.93292 -341.060278)
		(width 0.1524)
		(layer "F.Cu")
		(net "I2C_PDB_SDA")
	)
	(segment
		(start 16.55572 -336.5246)
		(end 16.55572 -341.44712)
		(width 0.1524)
		(layer "F.Cu")
		(net "I2C_PDB_SDA")
	)
	(segment
		(start 15.701518 -342.301322)
		(end 13.173964 -342.301322)
		(width 0.1524)
		(layer "F.Cu")
		(net "I2C_PDB_SDA")
	)
	(segment
		(start 18.948908 -334.823562)
		(end 18.256758 -334.823562)
		(width 0.1524)
		(layer "F.Cu")
		(net "I2C_PDB_SDA")
	)
	(segment
		(start 16.55572 -341.44712)
		(end 15.701518 -342.301322)
		(width 0.1524)
		(layer "F.Cu")
		(net "I2C_PDB_SDA")
	)
	(segment
		(start 11.93292 -341.060278)
		(end 11.93292 -340.574122)
		(width 0.1524)
		(layer "F.Cu")
		(net "I2C_PDB_SDA")
	)
	(via
		(at 11.93292 -340.574122)
		(size 0.508)
		(drill 0.254)
		(layers "F.Cu" "B.Cu")
		(net "I2C_PDB_SDA")
	)
	(segment
		(start 10.802874 -341.704168)
		(end 11.93292 -340.574122)
		(width 0.127)
		(layer "In2.Cu")
		(net "I2C_PDB_SDA")
	)
	(segment
		(start 3.949954 -342.669876)
		(end 4.723638 -343.44356)
		(width 0.127)
		(layer "In2.Cu")
		(net "I2C_PDB_SDA")
	)
	(segment
		(start 8.843772 -341.704168)
		(end 10.802874 -341.704168)
		(width 0.127)
		(layer "In2.Cu")
		(net "I2C_PDB_SDA")
	)
	(segment
		(start 4.723638 -343.44356)
		(end 7.10438 -343.44356)
		(width 0.127)
		(layer "In2.Cu")
		(net "I2C_PDB_SDA")
	)
	(segment
		(start 7.10438 -343.44356)
		(end 8.843772 -341.704168)
		(width 0.127)
		(layer "In2.Cu")
		(net "I2C_PDB_SDA")
	)
	(segment
		(start 18.04543 -336.093562)
		(end 18.948908 -336.093562)
		(width 0.1524)
		(layer "F.Cu")
		(net "I2C_PDB_SCL")
	)
	(segment
		(start 17.108424 -341.627206)
		(end 17.108424 -337.030568)
		(width 0.1524)
		(layer "F.Cu")
		(net "I2C_PDB_SCL")
	)
	(segment
		(start 15.885668 -342.849962)
		(end 17.108424 -341.627206)
		(width 0.1524)
		(layer "F.Cu")
		(net "I2C_PDB_SCL")
	)
	(segment
		(start 13.147802 -342.849962)
		(end 15.885668 -342.849962)
		(width 0.1524)
		(layer "F.Cu")
		(net "I2C_PDB_SCL")
	)
	(segment
		(start 17.108424 -337.030568)
		(end 18.04543 -336.093562)
		(width 0.1524)
		(layer "F.Cu")
		(net "I2C_PDB_SCL")
	)
	(segment
		(start 11.93292 -341.844122)
		(end 12.141962 -341.844122)
		(width 0.1524)
		(layer "F.Cu")
		(net "I2C_PDB_SCL")
	)
	(segment
		(start 12.141962 -341.844122)
		(end 13.147802 -342.849962)
		(width 0.1524)
		(layer "F.Cu")
		(net "I2C_PDB_SCL")
	)
	(via
		(at 11.93292 -341.844122)
		(size 0.508)
		(drill 0.254)
		(layers "F.Cu" "B.Cu")
		(net "I2C_PDB_SCL")
	)
	(segment
		(start 1.949958 -343.669874)
		(end 3.437382 -343.669874)
		(width 0.127)
		(layer "In2.Cu")
		(net "I2C_PDB_SCL")
	)
	(segment
		(start 7.210552 -343.834212)
		(end 8.71474 -342.330024)
		(width 0.127)
		(layer "In2.Cu")
		(net "I2C_PDB_SCL")
	)
	(segment
		(start 3.437382 -343.669874)
		(end 3.60172 -343.834212)
		(width 0.127)
		(layer "In2.Cu")
		(net "I2C_PDB_SCL")
	)
	(segment
		(start 3.60172 -343.834212)
		(end 7.210552 -343.834212)
		(width 0.127)
		(layer "In2.Cu")
		(net "I2C_PDB_SCL")
	)
	(segment
		(start 8.71474 -342.330024)
		(end 11.447018 -342.330024)
		(width 0.127)
		(layer "In2.Cu")
		(net "I2C_PDB_SCL")
	)
	(segment
		(start 11.447018 -342.330024)
		(end 11.93292 -341.844122)
		(width 0.127)
		(layer "In2.Cu")
		(net "I2C_PDB_SCL")
	)
	(segment
		(start 39.167308 -12.20978)
		(end 40.019732 -13.062204)
		(width 0.1524)
		(layer "F.Cu")
		(net "PSU1_RETURN")
	)
	(segment
		(start 35.53968 -12.210034)
		(end 35.539934 -12.20978)
		(width 0.1524)
		(layer "F.Cu")
		(net "PSU1_RETURN")
	)
	(segment
		(start 39.757604 -14.412976)
		(end 39.757604 -13.781532)
		(width 0.1524)
		(layer "F.Cu")
		(net "PSU1_RETURN")
	)
	(segment
		(start 35.539934 -12.20978)
		(end 39.167308 -12.20978)
		(width 0.1524)
		(layer "F.Cu")
		(net "PSU1_RETURN")
	)
	(segment
		(start 39.757604 -13.781532)
		(end 40.019732 -13.519404)
		(width 0.1524)
		(layer "F.Cu")
		(net "PSU1_RETURN")
	)
	(segment
		(start 40.019732 -13.519404)
		(end 40.019732 -13.062204)
		(width 0.1524)
		(layer "F.Cu")
		(net "PSU1_RETURN")
	)
	(via
		(at 40.019732 -13.062204)
		(size 0.508)
		(drill 0.254)
		(layers "F.Cu" "B.Cu")
		(net "PSU1_RETURN")
	)
	(segment
		(start 37.555932 -17.28978)
		(end 37.571172 -17.30502)
		(width 0.1524)
		(layer "F.Cu")
		(net "PSU1_AD0")
	)
	(segment
		(start 37.571172 -17.30502)
		(end 39.449502 -17.30502)
		(width 0.1524)
		(layer "F.Cu")
		(net "PSU1_AD0")
	)
	(segment
		(start 36.539932 -17.290034)
		(end 37.555932 -17.28978)
		(width 0.1524)
		(layer "F.Cu")
		(net "PSU1_AD0")
	)
	(segment
		(start 35.53968 -17.290034)
		(end 36.539932 -17.290034)
		(width 0.1524)
		(layer "F.Cu")
		(net "PSU1_AD0")
	)
	(via
		(at 94.366842 -306.00015)
		(size 0.508)
		(drill 0.254)
		(layers "F.Cu" "B.Cu")
		(net "T8_BLAD2_TXD")
	)
	(segment
		(start 6.925818 -279.960578)
		(end 8.05053 -278.835866)
		(width 0.127)
		(layer "In5.Cu")
		(net "T8_BLAD2_TXD")
	)
	(segment
		(start 5.154168 -281.465528)
		(end 5.154168 -280.828242)
		(width 0.127)
		(layer "In5.Cu")
		(net "T8_BLAD2_TXD")
	)
	(segment
		(start 10.798556 -277.584916)
		(end 10.798556 -276.82571)
		(width 0.127)
		(layer "In5.Cu")
		(net "T8_BLAD2_TXD")
	)
	(segment
		(start 6.021832 -279.960578)
		(end 6.925818 -279.960578)
		(width 0.127)
		(layer "In5.Cu")
		(net "T8_BLAD2_TXD")
	)
	(segment
		(start 89.29116 -321.39382)
		(end 85.47608 -321.39382)
		(width 0.127)
		(layer "In5.Cu")
		(net "T8_BLAD2_TXD")
	)
	(segment
		(start 94.366842 -306.791614)
		(end 94.366842 -306.00015)
		(width 0.127)
		(layer "In5.Cu")
		(net "T8_BLAD2_TXD")
	)
	(segment
		(start 90.71991 -319.96507)
		(end 89.29116 -321.39382)
		(width 0.127)
		(layer "In5.Cu")
		(net "T8_BLAD2_TXD")
	)
	(segment
		(start 98.799904 -274.188682)
		(end 98.799904 -288.47796)
		(width 0.127)
		(layer "In5.Cu")
		(net "T8_BLAD2_TXD")
	)
	(segment
		(start 70.947026 -268.708886)
		(end 72.112886 -269.874746)
		(width 0.127)
		(layer "In5.Cu")
		(net "T8_BLAD2_TXD")
	)
	(segment
		(start 5.154168 -280.828242)
		(end 6.021832 -279.960578)
		(width 0.127)
		(layer "In5.Cu")
		(net "T8_BLAD2_TXD")
	)
	(segment
		(start 98.799904 -288.47796)
		(end 94.366842 -292.911022)
		(width 0.127)
		(layer "In5.Cu")
		(net "T8_BLAD2_TXD")
	)
	(segment
		(start 94.366842 -292.911022)
		(end 94.366842 -306.00015)
		(width 0.127)
		(layer "In5.Cu")
		(net "T8_BLAD2_TXD")
	)
	(segment
		(start 84.524088 -320.441828)
		(end 84.524088 -316.634368)
		(width 0.127)
		(layer "In5.Cu")
		(net "T8_BLAD2_TXD")
	)
	(segment
		(start 94.485968 -269.874746)
		(end 98.799904 -274.188682)
		(width 0.127)
		(layer "In5.Cu")
		(net "T8_BLAD2_TXD")
	)
	(segment
		(start 18.91538 -268.708886)
		(end 70.947026 -268.708886)
		(width 0.127)
		(layer "In5.Cu")
		(net "T8_BLAD2_TXD")
	)
	(segment
		(start 8.05053 -278.835866)
		(end 9.547606 -278.835866)
		(width 0.127)
		(layer "In5.Cu")
		(net "T8_BLAD2_TXD")
	)
	(segment
		(start 85.47608 -321.39382)
		(end 84.524088 -320.441828)
		(width 0.127)
		(layer "In5.Cu")
		(net "T8_BLAD2_TXD")
	)
	(segment
		(start 72.112886 -269.874746)
		(end 94.485968 -269.874746)
		(width 0.127)
		(layer "In5.Cu")
		(net "T8_BLAD2_TXD")
	)
	(segment
		(start 10.798556 -276.82571)
		(end 18.91538 -268.708886)
		(width 0.127)
		(layer "In5.Cu")
		(net "T8_BLAD2_TXD")
	)
	(segment
		(start 3.949954 -282.669742)
		(end 5.154168 -281.465528)
		(width 0.127)
		(layer "In5.Cu")
		(net "T8_BLAD2_TXD")
	)
	(segment
		(start 9.547606 -278.835866)
		(end 10.798556 -277.584916)
		(width 0.127)
		(layer "In5.Cu")
		(net "T8_BLAD2_TXD")
	)
	(segment
		(start 84.524088 -316.634368)
		(end 94.366842 -306.791614)
		(width 0.127)
		(layer "In5.Cu")
		(net "T8_BLAD2_TXD")
	)
	(segment
		(start 39.43858 -22.370034)
		(end 39.462964 -22.394418)
		(width 0.508)
		(layer "F.Cu")
		(net "PSU1_REMOTE_P")
	)
	(segment
		(start 35.53968 -22.370034)
		(end 39.43858 -22.370034)
		(width 0.508)
		(layer "F.Cu")
		(net "PSU1_REMOTE_P")
	)
	(via
		(at 83.723226 -326.140064)
		(size 0.508)
		(drill 0.254)
		(layers "F.Cu" "B.Cu")
		(net "T8_BLAD1_EN")
	)
	(segment
		(start 27.577796 -349.153226)
		(end 29.647896 -351.223326)
		(width 0.127)
		(layer "In2.Cu")
		(net "T8_BLAD1_EN")
	)
	(segment
		(start 2.97053 -288.3154)
		(end 3.316478 -287.969452)
		(width 0.127)
		(layer "In2.Cu")
		(net "T8_BLAD1_EN")
	)
	(segment
		(start 60.03925 -348.580202)
		(end 82.479388 -326.140064)
		(width 0.127)
		(layer "In2.Cu")
		(net "T8_BLAD1_EN")
	)
	(segment
		(start 44.709842 -351.223326)
		(end 47.352966 -348.580202)
		(width 0.127)
		(layer "In2.Cu")
		(net "T8_BLAD1_EN")
	)
	(segment
		(start 21.608542 -287.052766)
		(end 27.577796 -293.02202)
		(width 0.127)
		(layer "In2.Cu")
		(net "T8_BLAD1_EN")
	)
	(segment
		(start 6.217158 -285.89478)
		(end 7.090664 -285.89478)
		(width 0.127)
		(layer "In2.Cu")
		(net "T8_BLAD1_EN")
	)
	(segment
		(start 29.647896 -351.223326)
		(end 44.709842 -351.223326)
		(width 0.127)
		(layer "In2.Cu")
		(net "T8_BLAD1_EN")
	)
	(segment
		(start 3.949954 -290.66998)
		(end 2.97053 -289.690556)
		(width 0.127)
		(layer "In2.Cu")
		(net "T8_BLAD1_EN")
	)
	(segment
		(start 8.711184 -286.821626)
		(end 8.942324 -287.052766)
		(width 0.127)
		(layer "In2.Cu")
		(net "T8_BLAD1_EN")
	)
	(segment
		(start 4.142486 -287.969452)
		(end 6.217158 -285.89478)
		(width 0.127)
		(layer "In2.Cu")
		(net "T8_BLAD1_EN")
	)
	(segment
		(start 82.479388 -326.140064)
		(end 83.723226 -326.140064)
		(width 0.127)
		(layer "In2.Cu")
		(net "T8_BLAD1_EN")
	)
	(segment
		(start 8.942324 -287.052766)
		(end 21.608542 -287.052766)
		(width 0.127)
		(layer "In2.Cu")
		(net "T8_BLAD1_EN")
	)
	(segment
		(start 2.97053 -289.690556)
		(end 2.97053 -288.3154)
		(width 0.127)
		(layer "In2.Cu")
		(net "T8_BLAD1_EN")
	)
	(segment
		(start 7.090664 -285.89478)
		(end 8.01751 -286.821626)
		(width 0.127)
		(layer "In2.Cu")
		(net "T8_BLAD1_EN")
	)
	(segment
		(start 8.01751 -286.821626)
		(end 8.711184 -286.821626)
		(width 0.127)
		(layer "In2.Cu")
		(net "T8_BLAD1_EN")
	)
	(segment
		(start 47.352966 -348.580202)
		(end 60.03925 -348.580202)
		(width 0.127)
		(layer "In2.Cu")
		(net "T8_BLAD1_EN")
	)
	(segment
		(start 27.577796 -293.02202)
		(end 27.577796 -349.153226)
		(width 0.127)
		(layer "In2.Cu")
		(net "T8_BLAD1_EN")
	)
	(segment
		(start 88.17991 -319.96507)
		(end 88.17991 -321.68338)
		(width 0.127)
		(layer "In2.Cu")
		(net "T8_BLAD1_EN")
	)
	(segment
		(start 88.17991 -321.68338)
		(end 83.723226 -326.140064)
		(width 0.127)
		(layer "In2.Cu")
		(net "T8_BLAD1_EN")
	)
	(segment
		(start 3.316478 -287.969452)
		(end 4.142486 -287.969452)
		(width 0.127)
		(layer "In2.Cu")
		(net "T8_BLAD1_EN")
	)
	(via
		(at 98.251264 -299.679614)
		(size 0.508)
		(drill 0.254)
		(layers "F.Cu" "B.Cu")
		(net "T8_BLAD4_TXD")
	)
	(segment
		(start 8.00608 -274.380452)
		(end 10.561066 -274.380452)
		(width 0.127)
		(layer "In5.Cu")
		(net "T8_BLAD4_TXD")
	)
	(segment
		(start 83.093306 -266.60856)
		(end 83.36407 -266.879324)
		(width 0.127)
		(layer "In5.Cu")
		(net "T8_BLAD4_TXD")
	)
	(segment
		(start 6.894576 -275.491956)
		(end 8.00608 -274.380452)
		(width 0.127)
		(layer "In5.Cu")
		(net "T8_BLAD4_TXD")
	)
	(segment
		(start 4.89331 -276.602952)
		(end 6.004306 -275.491956)
		(width 0.127)
		(layer "In5.Cu")
		(net "T8_BLAD4_TXD")
	)
	(segment
		(start 94.037658 -266.879324)
		(end 100.450904 -273.29257)
		(width 0.127)
		(layer "In5.Cu")
		(net "T8_BLAD4_TXD")
	)
	(segment
		(start 83.36407 -266.879324)
		(end 94.037658 -266.879324)
		(width 0.127)
		(layer "In5.Cu")
		(net "T8_BLAD4_TXD")
	)
	(segment
		(start 100.450904 -273.29257)
		(end 100.450904 -289.623246)
		(width 0.127)
		(layer "In5.Cu")
		(net "T8_BLAD4_TXD")
	)
	(segment
		(start 4.89331 -276.864826)
		(end 4.89331 -276.602952)
		(width 0.127)
		(layer "In5.Cu")
		(net "T8_BLAD4_TXD")
	)
	(segment
		(start 4.088384 -277.669752)
		(end 4.89331 -276.864826)
		(width 0.127)
		(layer "In5.Cu")
		(net "T8_BLAD4_TXD")
	)
	(segment
		(start 92.207334 -317.42507)
		(end 98.251264 -311.38114)
		(width 0.127)
		(layer "In5.Cu")
		(net "T8_BLAD4_TXD")
	)
	(segment
		(start 6.004306 -275.491956)
		(end 6.894576 -275.491956)
		(width 0.127)
		(layer "In5.Cu")
		(net "T8_BLAD4_TXD")
	)
	(segment
		(start 18.062194 -266.879324)
		(end 80.826102 -266.879324)
		(width 0.127)
		(layer "In5.Cu")
		(net "T8_BLAD4_TXD")
	)
	(segment
		(start 100.450904 -289.623246)
		(end 98.251264 -291.822886)
		(width 0.127)
		(layer "In5.Cu")
		(net "T8_BLAD4_TXD")
	)
	(segment
		(start 90.71991 -317.42507)
		(end 92.207334 -317.42507)
		(width 0.127)
		(layer "In5.Cu")
		(net "T8_BLAD4_TXD")
	)
	(segment
		(start 1.949958 -277.669752)
		(end 4.088384 -277.669752)
		(width 0.127)
		(layer "In5.Cu")
		(net "T8_BLAD4_TXD")
	)
	(segment
		(start 98.251264 -291.822886)
		(end 98.251264 -299.679614)
		(width 0.127)
		(layer "In5.Cu")
		(net "T8_BLAD4_TXD")
	)
	(segment
		(start 81.096866 -266.60856)
		(end 83.093306 -266.60856)
		(width 0.127)
		(layer "In5.Cu")
		(net "T8_BLAD4_TXD")
	)
	(segment
		(start 98.251264 -311.38114)
		(end 98.251264 -299.679614)
		(width 0.127)
		(layer "In5.Cu")
		(net "T8_BLAD4_TXD")
	)
	(segment
		(start 10.561066 -274.380452)
		(end 18.062194 -266.879324)
		(width 0.127)
		(layer "In5.Cu")
		(net "T8_BLAD4_TXD")
	)
	(segment
		(start 80.826102 -266.879324)
		(end 81.096866 -266.60856)
		(width 0.127)
		(layer "In5.Cu")
		(net "T8_BLAD4_TXD")
	)
	(via
		(at 83.294728 -327.462134)
		(size 0.508)
		(drill 0.254)
		(layers "F.Cu" "B.Cu")
		(net "T8_BLAD3_EN")
	)
	(segment
		(start 7.248398 -287.588706)
		(end 6.045454 -287.588706)
		(width 0.127)
		(layer "In2.Cu")
		(net "T8_BLAD3_EN")
	)
	(segment
		(start 27.247596 -293.158926)
		(end 21.623782 -287.535112)
		(width 0.127)
		(layer "In2.Cu")
		(net "T8_BLAD3_EN")
	)
	(segment
		(start 27.247596 -349.290132)
		(end 27.247596 -293.158926)
		(width 0.127)
		(layer "In2.Cu")
		(net "T8_BLAD3_EN")
	)
	(segment
		(start 8.093964 -288.434272)
		(end 7.248398 -287.588706)
		(width 0.127)
		(layer "In2.Cu")
		(net "T8_BLAD3_EN")
	)
	(segment
		(start 4.964176 -288.669984)
		(end 3.949954 -288.669984)
		(width 0.127)
		(layer "In2.Cu")
		(net "T8_BLAD3_EN")
	)
	(segment
		(start 88.17991 -317.42507)
		(end 88.17991 -318.81826)
		(width 0.127)
		(layer "In2.Cu")
		(net "T8_BLAD3_EN")
	)
	(segment
		(start 89.013538 -321.743324)
		(end 83.294728 -327.462134)
		(width 0.127)
		(layer "In2.Cu")
		(net "T8_BLAD3_EN")
	)
	(segment
		(start 88.17991 -318.81826)
		(end 89.013538 -319.651888)
		(width 0.127)
		(layer "In2.Cu")
		(net "T8_BLAD3_EN")
	)
	(segment
		(start 89.013538 -319.651888)
		(end 89.013538 -321.743324)
		(width 0.127)
		(layer "In2.Cu")
		(net "T8_BLAD3_EN")
	)
	(segment
		(start 6.045454 -287.588706)
		(end 4.964176 -288.669984)
		(width 0.127)
		(layer "In2.Cu")
		(net "T8_BLAD3_EN")
	)
	(segment
		(start 81.624678 -327.462134)
		(end 60.114434 -348.972378)
		(width 0.127)
		(layer "In2.Cu")
		(net "T8_BLAD3_EN")
	)
	(segment
		(start 21.623782 -287.535112)
		(end 10.470388 -287.535112)
		(width 0.127)
		(layer "In2.Cu")
		(net "T8_BLAD3_EN")
	)
	(segment
		(start 44.846748 -351.553526)
		(end 29.51099 -351.553526)
		(width 0.127)
		(layer "In2.Cu")
		(net "T8_BLAD3_EN")
	)
	(segment
		(start 9.571228 -288.434272)
		(end 8.093964 -288.434272)
		(width 0.127)
		(layer "In2.Cu")
		(net "T8_BLAD3_EN")
	)
	(segment
		(start 10.470388 -287.535112)
		(end 9.571228 -288.434272)
		(width 0.127)
		(layer "In2.Cu")
		(net "T8_BLAD3_EN")
	)
	(segment
		(start 60.114434 -348.972378)
		(end 47.427896 -348.972378)
		(width 0.127)
		(layer "In2.Cu")
		(net "T8_BLAD3_EN")
	)
	(segment
		(start 47.427896 -348.972378)
		(end 44.846748 -351.553526)
		(width 0.127)
		(layer "In2.Cu")
		(net "T8_BLAD3_EN")
	)
	(segment
		(start 83.294728 -327.462134)
		(end 81.624678 -327.462134)
		(width 0.127)
		(layer "In2.Cu")
		(net "T8_BLAD3_EN")
	)
	(segment
		(start 29.51099 -351.553526)
		(end 27.247596 -349.290132)
		(width 0.127)
		(layer "In2.Cu")
		(net "T8_BLAD3_EN")
	)
	(via
		(at 81.782412 -325.649844)
		(size 0.508)
		(drill 0.254)
		(layers "F.Cu" "B.Cu")
		(net "T8_BLAD1_TXD")
	)
	(segment
		(start 28.594304 -348.365572)
		(end 28.594304 -292.600634)
		(width 0.127)
		(layer "In2.Cu")
		(net "T8_BLAD1_TXD")
	)
	(segment
		(start 44.548806 -349.98279)
		(end 30.211522 -349.98279)
		(width 0.127)
		(layer "In2.Cu")
		(net "T8_BLAD1_TXD")
	)
	(segment
		(start 20.998942 -285.005272)
		(end 9.894824 -285.005272)
		(width 0.127)
		(layer "In2.Cu")
		(net "T8_BLAD1_TXD")
	)
	(segment
		(start 59.512454 -347.919802)
		(end 46.611794 -347.919802)
		(width 0.127)
		(layer "In2.Cu")
		(net "T8_BLAD1_TXD")
	)
	(segment
		(start 81.782412 -325.649844)
		(end 59.512454 -347.919802)
		(width 0.127)
		(layer "In2.Cu")
		(net "T8_BLAD1_TXD")
	)
	(segment
		(start 5.09778 -283.522166)
		(end 3.949954 -284.669992)
		(width 0.127)
		(layer "In2.Cu")
		(net "T8_BLAD1_TXD")
	)
	(segment
		(start 9.894824 -285.005272)
		(end 9.393428 -284.503876)
		(width 0.127)
		(layer "In2.Cu")
		(net "T8_BLAD1_TXD")
	)
	(segment
		(start 7.270242 -283.522166)
		(end 5.09778 -283.522166)
		(width 0.127)
		(layer "In2.Cu")
		(net "T8_BLAD1_TXD")
	)
	(segment
		(start 28.594304 -292.600634)
		(end 20.998942 -285.005272)
		(width 0.127)
		(layer "In2.Cu")
		(net "T8_BLAD1_TXD")
	)
	(segment
		(start 46.611794 -347.919802)
		(end 44.548806 -349.98279)
		(width 0.127)
		(layer "In2.Cu")
		(net "T8_BLAD1_TXD")
	)
	(segment
		(start 85.63991 -319.96507)
		(end 85.63991 -321.792346)
		(width 0.127)
		(layer "In2.Cu")
		(net "T8_BLAD1_TXD")
	)
	(segment
		(start 9.393428 -284.503876)
		(end 8.251952 -284.503876)
		(width 0.127)
		(layer "In2.Cu")
		(net "T8_BLAD1_TXD")
	)
	(segment
		(start 30.211522 -349.98279)
		(end 28.594304 -348.365572)
		(width 0.127)
		(layer "In2.Cu")
		(net "T8_BLAD1_TXD")
	)
	(segment
		(start 85.63991 -321.792346)
		(end 81.782412 -325.649844)
		(width 0.127)
		(layer "In2.Cu")
		(net "T8_BLAD1_TXD")
	)
	(segment
		(start 8.251952 -284.503876)
		(end 7.270242 -283.522166)
		(width 0.127)
		(layer "In2.Cu")
		(net "T8_BLAD1_TXD")
	)
	(via
		(at 83.172808 -324.979538)
		(size 0.508)
		(drill 0.254)
		(layers "F.Cu" "B.Cu")
		(net "T8_BLAD1_RXD")
	)
	(segment
		(start 28.251658 -292.74262)
		(end 20.856956 -285.347918)
		(width 0.127)
		(layer "In2.Cu")
		(net "T8_BLAD1_RXD")
	)
	(segment
		(start 86.90991 -319.506854)
		(end 86.532212 -319.884552)
		(width 0.127)
		(layer "In2.Cu")
		(net "T8_BLAD1_RXD")
	)
	(segment
		(start 9.708642 -285.347918)
		(end 9.212326 -284.851602)
		(width 0.127)
		(layer "In2.Cu")
		(net "T8_BLAD1_RXD")
	)
	(segment
		(start 5.7658 -283.958792)
		(end 4.054856 -285.669736)
		(width 0.127)
		(layer "In2.Cu")
		(net "T8_BLAD1_RXD")
	)
	(segment
		(start 59.902344 -348.250002)
		(end 46.7487 -348.250002)
		(width 0.127)
		(layer "In2.Cu")
		(net "T8_BLAD1_RXD")
	)
	(segment
		(start 44.582334 -350.416368)
		(end 30.03169 -350.416368)
		(width 0.127)
		(layer "In2.Cu")
		(net "T8_BLAD1_RXD")
	)
	(segment
		(start 4.054856 -285.669736)
		(end 1.949958 -285.669736)
		(width 0.127)
		(layer "In2.Cu")
		(net "T8_BLAD1_RXD")
	)
	(segment
		(start 28.251658 -348.636336)
		(end 28.251658 -292.74262)
		(width 0.127)
		(layer "In2.Cu")
		(net "T8_BLAD1_RXD")
	)
	(segment
		(start 46.7487 -348.250002)
		(end 44.582334 -350.416368)
		(width 0.127)
		(layer "In2.Cu")
		(net "T8_BLAD1_RXD")
	)
	(segment
		(start 7.871714 -284.851602)
		(end 6.978904 -283.958792)
		(width 0.127)
		(layer "In2.Cu")
		(net "T8_BLAD1_RXD")
	)
	(segment
		(start 83.172808 -324.979538)
		(end 59.902344 -348.250002)
		(width 0.127)
		(layer "In2.Cu")
		(net "T8_BLAD1_RXD")
	)
	(segment
		(start 20.856956 -285.347918)
		(end 9.708642 -285.347918)
		(width 0.127)
		(layer "In2.Cu")
		(net "T8_BLAD1_RXD")
	)
	(segment
		(start 86.532212 -319.884552)
		(end 86.532212 -321.620134)
		(width 0.127)
		(layer "In2.Cu")
		(net "T8_BLAD1_RXD")
	)
	(segment
		(start 6.978904 -283.958792)
		(end 5.7658 -283.958792)
		(width 0.127)
		(layer "In2.Cu")
		(net "T8_BLAD1_RXD")
	)
	(segment
		(start 86.532212 -321.620134)
		(end 83.172808 -324.979538)
		(width 0.127)
		(layer "In2.Cu")
		(net "T8_BLAD1_RXD")
	)
	(segment
		(start 86.90991 -318.69507)
		(end 86.90991 -319.506854)
		(width 0.127)
		(layer "In2.Cu")
		(net "T8_BLAD1_RXD")
	)
	(segment
		(start 30.03169 -350.416368)
		(end 28.251658 -348.636336)
		(width 0.127)
		(layer "In2.Cu")
		(net "T8_BLAD1_RXD")
	)
	(segment
		(start 9.212326 -284.851602)
		(end 7.871714 -284.851602)
		(width 0.127)
		(layer "In2.Cu")
		(net "T8_BLAD1_RXD")
	)
	(via
		(at 97.352104 -300.770544)
		(size 0.508)
		(drill 0.254)
		(layers "F.Cu" "B.Cu")
		(net "T8_BLAD4_RXD")
	)
	(segment
		(start 6.141212 -275.822156)
		(end 7.031482 -275.822156)
		(width 0.127)
		(layer "In5.Cu")
		(net "T8_BLAD4_RXD")
	)
	(segment
		(start 18.29308 -267.21054)
		(end 76.105004 -267.21054)
		(width 0.127)
		(layer "In5.Cu")
		(net "T8_BLAD4_RXD")
	)
	(segment
		(start 76.914756 -268.020292)
		(end 94.629986 -268.020292)
		(width 0.127)
		(layer "In5.Cu")
		(net "T8_BLAD4_RXD")
	)
	(segment
		(start 11.679936 -273.823684)
		(end 18.29308 -267.21054)
		(width 0.127)
		(layer "In5.Cu")
		(net "T8_BLAD4_RXD")
	)
	(segment
		(start 10.704322 -274.796504)
		(end 11.679936 -273.823684)
		(width 0.127)
		(layer "In5.Cu")
		(net "T8_BLAD4_RXD")
	)
	(segment
		(start 7.031482 -275.822156)
		(end 8.057134 -274.796504)
		(width 0.127)
		(layer "In5.Cu")
		(net "T8_BLAD4_RXD")
	)
	(segment
		(start 76.105004 -267.21054)
		(end 76.914756 -268.020292)
		(width 0.127)
		(layer "In5.Cu")
		(net "T8_BLAD4_RXD")
	)
	(segment
		(start 5.22351 -277.396194)
		(end 5.22351 -276.739858)
		(width 0.127)
		(layer "In5.Cu")
		(net "T8_BLAD4_RXD")
	)
	(segment
		(start 8.057134 -274.796504)
		(end 10.704322 -274.796504)
		(width 0.127)
		(layer "In5.Cu")
		(net "T8_BLAD4_RXD")
	)
	(segment
		(start 100.120704 -289.404806)
		(end 96.799654 -292.725856)
		(width 0.127)
		(layer "In5.Cu")
		(net "T8_BLAD4_RXD")
	)
	(segment
		(start 94.629986 -268.020292)
		(end 100.120704 -273.51101)
		(width 0.127)
		(layer "In5.Cu")
		(net "T8_BLAD4_RXD")
	)
	(segment
		(start 3.949954 -278.66975)
		(end 5.22351 -277.396194)
		(width 0.127)
		(layer "In5.Cu")
		(net "T8_BLAD4_RXD")
	)
	(segment
		(start 100.120704 -273.51101)
		(end 100.120704 -289.404806)
		(width 0.127)
		(layer "In5.Cu")
		(net "T8_BLAD4_RXD")
	)
	(segment
		(start 91.98991 -316.15507)
		(end 97.352104 -310.792876)
		(width 0.127)
		(layer "In5.Cu")
		(net "T8_BLAD4_RXD")
	)
	(segment
		(start 5.22351 -276.739858)
		(end 6.141212 -275.822156)
		(width 0.127)
		(layer "In5.Cu")
		(net "T8_BLAD4_RXD")
	)
	(segment
		(start 96.799654 -300.218094)
		(end 97.352104 -300.770544)
		(width 0.127)
		(layer "In5.Cu")
		(net "T8_BLAD4_RXD")
	)
	(segment
		(start 97.352104 -310.792876)
		(end 97.352104 -300.770544)
		(width 0.127)
		(layer "In5.Cu")
		(net "T8_BLAD4_RXD")
	)
	(segment
		(start 96.799654 -292.725856)
		(end 96.799654 -300.218094)
		(width 0.127)
		(layer "In5.Cu")
		(net "T8_BLAD4_RXD")
	)
	(via
		(at 94.913196 -304.791618)
		(size 0.508)
		(drill 0.254)
		(layers "F.Cu" "B.Cu")
		(net "T8_BLAD2_RXD")
	)
	(segment
		(start 6.95452 -279.464262)
		(end 6.864604 -279.554178)
		(width 0.127)
		(layer "In5.Cu")
		(net "T8_BLAD2_RXD")
	)
	(segment
		(start 71.417688 -268.319504)
		(end 18.75409 -268.319504)
		(width 0.127)
		(layer "In5.Cu")
		(net "T8_BLAD2_RXD")
	)
	(segment
		(start 94.467426 -269.389098)
		(end 72.487282 -269.389098)
		(width 0.127)
		(layer "In5.Cu")
		(net "T8_BLAD2_RXD")
	)
	(segment
		(start 99.130104 -274.051776)
		(end 94.467426 -269.389098)
		(width 0.127)
		(layer "In5.Cu")
		(net "T8_BLAD2_RXD")
	)
	(segment
		(start 6.864604 -279.554178)
		(end 5.85343 -279.554178)
		(width 0.127)
		(layer "In5.Cu")
		(net "T8_BLAD2_RXD")
	)
	(segment
		(start 99.130104 -288.76244)
		(end 99.130104 -274.051776)
		(width 0.127)
		(layer "In5.Cu")
		(net "T8_BLAD2_RXD")
	)
	(segment
		(start 4.747768 -281.164284)
		(end 4.252722 -281.65933)
		(width 0.127)
		(layer "In5.Cu")
		(net "T8_BLAD2_RXD")
	)
	(segment
		(start 5.85343 -279.554178)
		(end 4.747768 -280.65984)
		(width 0.127)
		(layer "In5.Cu")
		(net "T8_BLAD2_RXD")
	)
	(segment
		(start 84.854288 -320.276728)
		(end 85.64118 -321.06362)
		(width 0.127)
		(layer "In5.Cu")
		(net "T8_BLAD2_RXD")
	)
	(segment
		(start 90.26271 -319.167002)
		(end 91.517978 -319.167002)
		(width 0.127)
		(layer "In5.Cu")
		(net "T8_BLAD2_RXD")
	)
	(segment
		(start 88.366092 -321.06362)
		(end 90.26271 -319.167002)
		(width 0.127)
		(layer "In5.Cu")
		(net "T8_BLAD2_RXD")
	)
	(segment
		(start 94.913196 -304.791618)
		(end 94.913196 -306.955444)
		(width 0.127)
		(layer "In5.Cu")
		(net "T8_BLAD2_RXD")
	)
	(segment
		(start 84.854288 -317.014352)
		(end 84.854288 -320.276728)
		(width 0.127)
		(layer "In5.Cu")
		(net "T8_BLAD2_RXD")
	)
	(segment
		(start 91.517978 -319.167002)
		(end 91.98991 -318.69507)
		(width 0.127)
		(layer "In5.Cu")
		(net "T8_BLAD2_RXD")
	)
	(segment
		(start 3.960368 -281.65933)
		(end 1.949958 -283.66974)
		(width 0.127)
		(layer "In5.Cu")
		(net "T8_BLAD2_RXD")
	)
	(segment
		(start 85.64118 -321.06362)
		(end 88.366092 -321.06362)
		(width 0.127)
		(layer "In5.Cu")
		(net "T8_BLAD2_RXD")
	)
	(segment
		(start 18.75409 -268.319504)
		(end 10.342372 -276.731222)
		(width 0.127)
		(layer "In5.Cu")
		(net "T8_BLAD2_RXD")
	)
	(segment
		(start 94.913196 -292.979348)
		(end 99.130104 -288.76244)
		(width 0.127)
		(layer "In5.Cu")
		(net "T8_BLAD2_RXD")
	)
	(segment
		(start 10.342372 -276.731222)
		(end 10.342372 -277.490428)
		(width 0.127)
		(layer "In5.Cu")
		(net "T8_BLAD2_RXD")
	)
	(segment
		(start 10.342372 -277.490428)
		(end 9.32815 -278.50465)
		(width 0.127)
		(layer "In5.Cu")
		(net "T8_BLAD2_RXD")
	)
	(segment
		(start 94.913196 -304.791618)
		(end 94.913196 -292.979348)
		(width 0.127)
		(layer "In5.Cu")
		(net "T8_BLAD2_RXD")
	)
	(segment
		(start 6.95452 -279.463246)
		(end 6.95452 -279.464262)
		(width 0.127)
		(layer "In5.Cu")
		(net "T8_BLAD2_RXD")
	)
	(segment
		(start 7.913116 -278.50465)
		(end 6.95452 -279.463246)
		(width 0.127)
		(layer "In5.Cu")
		(net "T8_BLAD2_RXD")
	)
	(segment
		(start 94.913196 -306.955444)
		(end 84.854288 -317.014352)
		(width 0.127)
		(layer "In5.Cu")
		(net "T8_BLAD2_RXD")
	)
	(segment
		(start 4.252722 -281.65933)
		(end 3.960368 -281.65933)
		(width 0.127)
		(layer "In5.Cu")
		(net "T8_BLAD2_RXD")
	)
	(segment
		(start 9.32815 -278.50465)
		(end 7.913116 -278.50465)
		(width 0.127)
		(layer "In5.Cu")
		(net "T8_BLAD2_RXD")
	)
	(segment
		(start 4.747768 -280.65984)
		(end 4.747768 -281.164284)
		(width 0.127)
		(layer "In5.Cu")
		(net "T8_BLAD2_RXD")
	)
	(segment
		(start 72.487282 -269.389098)
		(end 71.417688 -268.319504)
		(width 0.127)
		(layer "In5.Cu")
		(net "T8_BLAD2_RXD")
	)
	(segment
		(start 27.28087 -12.320778)
		(end 27.28087 -12.674092)
		(width 0.1524)
		(layer "F.Cu")
		(net "PSU1_PS_ON_N")
	)
	(segment
		(start 27.32278 -12.632182)
		(end 28.840684 -12.632182)
		(width 0.1524)
		(layer "F.Cu")
		(net "PSU1_PS_ON_N")
	)
	(segment
		(start 27.28087 -12.674092)
		(end 27.32278 -12.632182)
		(width 0.1524)
		(layer "F.Cu")
		(net "PSU1_PS_ON_N")
	)
	(segment
		(start 27.45486 -12.146788)
		(end 27.28087 -12.320778)
		(width 0.1524)
		(layer "F.Cu")
		(net "PSU1_PS_ON_N")
	)
	(segment
		(start 27.45486 -11.75639)
		(end 27.45486 -12.146788)
		(width 0.1524)
		(layer "F.Cu")
		(net "PSU1_PS_ON_N")
	)
	(segment
		(start 28.840684 -12.632182)
		(end 29.262832 -12.210034)
		(width 0.1524)
		(layer "F.Cu")
		(net "PSU1_PS_ON_N")
	)
	(segment
		(start 29.262832 -12.210034)
		(end 30.45968 -12.210034)
		(width 0.1524)
		(layer "F.Cu")
		(net "PSU1_PS_ON_N")
	)
	(via
		(at 27.28087 -12.674092)
		(size 0.508)
		(drill 0.254)
		(layers "F.Cu" "B.Cu")
		(net "PSU1_PS_ON_N")
	)
	(via
		(at 95.623888 -303.529746)
		(size 0.508)
		(drill 0.254)
		(layers "F.Cu" "B.Cu")
		(net "T8_BLAD3_RXD")
	)
	(segment
		(start 95.623888 -303.529746)
		(end 95.623888 -292.843204)
		(width 0.127)
		(layer "In5.Cu")
		(net "T8_BLAD3_RXD")
	)
	(segment
		(start 6.194552 -277.75154)
		(end 5.36829 -278.577802)
		(width 0.127)
		(layer "In5.Cu")
		(net "T8_BLAD3_RXD")
	)
	(segment
		(start 18.610072 -267.972032)
		(end 9.765792 -276.816312)
		(width 0.127)
		(layer "In5.Cu")
		(net "T8_BLAD3_RXD")
	)
	(segment
		(start 8.020304 -276.816312)
		(end 7.085076 -277.75154)
		(width 0.127)
		(layer "In5.Cu")
		(net "T8_BLAD3_RXD")
	)
	(segment
		(start 95.623888 -292.843204)
		(end 99.460304 -289.006788)
		(width 0.127)
		(layer "In5.Cu")
		(net "T8_BLAD3_RXD")
	)
	(segment
		(start 5.36829 -279.25141)
		(end 3.949954 -280.669746)
		(width 0.127)
		(layer "In5.Cu")
		(net "T8_BLAD3_RXD")
	)
	(segment
		(start 95.623888 -303.529746)
		(end 95.623888 -307.44414)
		(width 0.127)
		(layer "In5.Cu")
		(net "T8_BLAD3_RXD")
	)
	(segment
		(start 5.36829 -278.577802)
		(end 5.36829 -279.25141)
		(width 0.127)
		(layer "In5.Cu")
		(net "T8_BLAD3_RXD")
	)
	(segment
		(start 7.085076 -277.75154)
		(end 6.194552 -277.75154)
		(width 0.127)
		(layer "In5.Cu")
		(net "T8_BLAD3_RXD")
	)
	(segment
		(start 99.460304 -273.909028)
		(end 94.408498 -268.857222)
		(width 0.127)
		(layer "In5.Cu")
		(net "T8_BLAD3_RXD")
	)
	(segment
		(start 99.460304 -289.006788)
		(end 99.460304 -273.909028)
		(width 0.127)
		(layer "In5.Cu")
		(net "T8_BLAD3_RXD")
	)
	(segment
		(start 95.623888 -307.44414)
		(end 87.724488 -315.340492)
		(width 0.127)
		(layer "In5.Cu")
		(net "T8_BLAD3_RXD")
	)
	(segment
		(start 71.781416 -267.972032)
		(end 18.610072 -267.972032)
		(width 0.127)
		(layer "In5.Cu")
		(net "T8_BLAD3_RXD")
	)
	(segment
		(start 72.666606 -268.857222)
		(end 71.781416 -267.972032)
		(width 0.127)
		(layer "In5.Cu")
		(net "T8_BLAD3_RXD")
	)
	(segment
		(start 9.765792 -276.816312)
		(end 8.020304 -276.816312)
		(width 0.127)
		(layer "In5.Cu")
		(net "T8_BLAD3_RXD")
	)
	(segment
		(start 94.408498 -268.857222)
		(end 72.666606 -268.857222)
		(width 0.127)
		(layer "In5.Cu")
		(net "T8_BLAD3_RXD")
	)
	(segment
		(start 87.724488 -315.340492)
		(end 86.90991 -316.15507)
		(width 0.127)
		(layer "In5.Cu")
		(net "T8_BLAD3_RXD")
	)
	(via
		(at 96.35109 -302.203612)
		(size 0.508)
		(drill 0.254)
		(layers "F.Cu" "B.Cu")
		(net "T8_BLAD3_TXD")
	)
	(segment
		(start 7.879588 -276.476968)
		(end 6.94436 -277.412196)
		(width 0.127)
		(layer "In5.Cu")
		(net "T8_BLAD3_TXD")
	)
	(segment
		(start 6.94436 -277.412196)
		(end 6.053836 -277.412196)
		(width 0.127)
		(layer "In5.Cu")
		(net "T8_BLAD3_TXD")
	)
	(segment
		(start 73.115932 -267.558012)
		(end 18.438368 -267.558012)
		(width 0.127)
		(layer "In5.Cu")
		(net "T8_BLAD3_TXD")
	)
	(segment
		(start 99.790504 -273.772122)
		(end 94.487746 -268.469364)
		(width 0.127)
		(layer "In5.Cu")
		(net "T8_BLAD3_TXD")
	)
	(segment
		(start 86.871302 -317.42507)
		(end 96.35109 -307.945282)
		(width 0.127)
		(layer "In5.Cu")
		(net "T8_BLAD3_TXD")
	)
	(segment
		(start 6.053836 -277.412196)
		(end 5.028946 -278.437086)
		(width 0.127)
		(layer "In5.Cu")
		(net "T8_BLAD3_TXD")
	)
	(segment
		(start 96.35109 -292.583108)
		(end 99.790504 -289.143694)
		(width 0.127)
		(layer "In5.Cu")
		(net "T8_BLAD3_TXD")
	)
	(segment
		(start 94.487746 -268.469364)
		(end 74.027284 -268.469364)
		(width 0.127)
		(layer "In5.Cu")
		(net "T8_BLAD3_TXD")
	)
	(segment
		(start 96.35109 -302.203612)
		(end 96.35109 -292.583108)
		(width 0.127)
		(layer "In5.Cu")
		(net "T8_BLAD3_TXD")
	)
	(segment
		(start 18.438368 -267.558012)
		(end 9.519412 -276.476968)
		(width 0.127)
		(layer "In5.Cu")
		(net "T8_BLAD3_TXD")
	)
	(segment
		(start 85.63991 -317.42507)
		(end 86.871302 -317.42507)
		(width 0.127)
		(layer "In5.Cu")
		(net "T8_BLAD3_TXD")
	)
	(segment
		(start 4.136136 -279.669748)
		(end 1.949958 -279.669748)
		(width 0.127)
		(layer "In5.Cu")
		(net "T8_BLAD3_TXD")
	)
	(segment
		(start 5.028946 -278.437086)
		(end 5.028946 -278.776938)
		(width 0.127)
		(layer "In5.Cu")
		(net "T8_BLAD3_TXD")
	)
	(segment
		(start 74.027284 -268.469364)
		(end 73.115932 -267.558012)
		(width 0.127)
		(layer "In5.Cu")
		(net "T8_BLAD3_TXD")
	)
	(segment
		(start 96.35109 -307.945282)
		(end 96.35109 -302.203612)
		(width 0.127)
		(layer "In5.Cu")
		(net "T8_BLAD3_TXD")
	)
	(segment
		(start 9.519412 -276.476968)
		(end 7.879588 -276.476968)
		(width 0.127)
		(layer "In5.Cu")
		(net "T8_BLAD3_TXD")
	)
	(segment
		(start 99.790504 -289.143694)
		(end 99.790504 -273.772122)
		(width 0.127)
		(layer "In5.Cu")
		(net "T8_BLAD3_TXD")
	)
	(segment
		(start 5.028946 -278.776938)
		(end 4.136136 -279.669748)
		(width 0.127)
		(layer "In5.Cu")
		(net "T8_BLAD3_TXD")
	)
	(segment
		(start 35.53968 -459.289912)
		(end 36.674806 -459.289912)
		(width 0.1524)
		(layer "F.Cu")
		(net "PSU6_AD0")
	)
	(segment
		(start 39.474902 -461.195674)
		(end 39.474902 -461.170274)
		(width 0.1524)
		(layer "F.Cu")
		(net "PSU6_AD0")
	)
	(segment
		(start 37.555932 -459.289658)
		(end 38.051486 -459.289658)
		(width 0.1524)
		(layer "F.Cu")
		(net "PSU6_AD0")
	)
	(segment
		(start 39.474902 -460.713074)
		(end 39.474902 -461.170274)
		(width 0.1524)
		(layer "F.Cu")
		(net "PSU6_AD0")
	)
	(segment
		(start 38.051486 -459.289658)
		(end 39.474902 -460.713074)
		(width 0.1524)
		(layer "F.Cu")
		(net "PSU6_AD0")
	)
	(segment
		(start 36.674806 -459.289912)
		(end 37.555932 -459.289658)
		(width 0.1524)
		(layer "F.Cu")
		(net "PSU6_AD0")
	)
	(segment
		(start 40.273986 -462.37144)
		(end 40.273986 -461.994758)
		(width 0.1524)
		(layer "F.Cu")
		(net "PSU6_AD0")
	)
	(segment
		(start 40.273986 -461.994758)
		(end 39.474902 -461.195674)
		(width 0.1524)
		(layer "F.Cu")
		(net "PSU6_AD0")
	)
	(segment
		(start 40.401748 -282.696158)
		(end 40.40378 -282.69819)
		(width 0.1524)
		(layer "F.Cu")
		(net "PSU4_AD0")
	)
	(segment
		(start 37.555932 -282.489656)
		(end 37.762434 -282.696158)
		(width 0.1524)
		(layer "F.Cu")
		(net "PSU4_AD0")
	)
	(segment
		(start 36.997894 -282.48991)
		(end 37.555932 -282.489656)
		(width 0.1524)
		(layer "F.Cu")
		(net "PSU4_AD0")
	)
	(segment
		(start 39.653718 -282.696158)
		(end 40.401748 -282.696158)
		(width 0.1524)
		(layer "F.Cu")
		(net "PSU4_AD0")
	)
	(segment
		(start 37.762434 -282.696158)
		(end 39.653718 -282.696158)
		(width 0.1524)
		(layer "F.Cu")
		(net "PSU4_AD0")
	)
	(segment
		(start 40.40378 -282.69819)
		(end 40.86098 -282.69819)
		(width 0.1524)
		(layer "F.Cu")
		(net "PSU4_AD0")
	)
	(segment
		(start 35.53968 -282.48991)
		(end 36.997894 -282.48991)
		(width 0.1524)
		(layer "F.Cu")
		(net "PSU4_AD0")
	)
	(segment
		(start 28.038806 -19.83994)
		(end 28.019502 -19.859244)
		(width 0.508)
		(layer "F.Cu")
		(net "PSU1_REMOTE_N")
	)
	(segment
		(start 30.45968 -19.830034)
		(end 30.442662 -19.847052)
		(width 0.508)
		(layer "F.Cu")
		(net "PSU1_REMOTE_N")
	)
	(segment
		(start 30.442662 -19.847052)
		(end 28.045918 -19.847052)
		(width 0.508)
		(layer "F.Cu")
		(net "PSU1_REMOTE_N")
	)
	(segment
		(start 28.045918 -19.847052)
		(end 28.038806 -19.83994)
		(width 0.508)
		(layer "F.Cu")
		(net "PSU1_REMOTE_N")
	)
	(segment
		(start 28.019502 -19.859244)
		(end 27.250898 -19.859244)
		(width 0.508)
		(layer "F.Cu")
		(net "PSU1_REMOTE_N")
	)
	(via
		(at 80.668368 -267.4747)
		(size 0.508)
		(drill 0.254)
		(layers "F.Cu" "B.Cu")
		(net "T7_BLAD3_TXD")
	)
	(segment
		(start 85.63991 -272.446242)
		(end 80.668368 -267.4747)
		(width 0.127)
		(layer "In2.Cu")
		(net "T7_BLAD3_TXD")
	)
	(segment
		(start 21.333968 -266.9413)
		(end 80.134968 -266.9413)
		(width 0.127)
		(layer "In2.Cu")
		(net "T7_BLAD3_TXD")
	)
	(segment
		(start 85.63991 -272.97507)
		(end 85.63991 -272.446242)
		(width 0.127)
		(layer "In2.Cu")
		(net "T7_BLAD3_TXD")
	)
	(segment
		(start 8.449818 -275.669756)
		(end 12.605512 -275.669756)
		(width 0.127)
		(layer "In2.Cu")
		(net "T7_BLAD3_TXD")
	)
	(segment
		(start 12.605512 -275.669756)
		(end 21.333968 -266.9413)
		(width 0.127)
		(layer "In2.Cu")
		(net "T7_BLAD3_TXD")
	)
	(segment
		(start 80.134968 -266.9413)
		(end 80.668368 -267.4747)
		(width 0.127)
		(layer "In2.Cu")
		(net "T7_BLAD3_TXD")
	)
	(segment
		(start 28.087574 -454.209912)
		(end 27.23388 -455.063606)
		(width 0.1524)
		(layer "F.Cu")
		(net "PSU6_PS_ON_N")
	)
	(segment
		(start 27.069288 -455.063606)
		(end 26.65222 -454.646538)
		(width 0.1524)
		(layer "F.Cu")
		(net "PSU6_PS_ON_N")
	)
	(segment
		(start 30.45968 -454.209912)
		(end 28.087574 -454.209912)
		(width 0.1524)
		(layer "F.Cu")
		(net "PSU6_PS_ON_N")
	)
	(segment
		(start 27.23388 -455.063606)
		(end 27.069288 -455.063606)
		(width 0.1524)
		(layer "F.Cu")
		(net "PSU6_PS_ON_N")
	)
	(via
		(at 27.23388 -455.063606)
		(size 0.508)
		(drill 0.254)
		(layers "F.Cu" "B.Cu")
		(net "PSU6_PS_ON_N")
	)
	(via
		(at 87.401146 -281.126692)
		(size 0.508)
		(drill 0.254)
		(layers "F.Cu" "B.Cu")
		(net "T7_BLAD3_EN")
	)
	(segment
		(start 83.839812 -314.807854)
		(end 92.053664 -306.594002)
		(width 0.127)
		(layer "In5.Cu")
		(net "T7_BLAD3_EN")
	)
	(segment
		(start 88.17991 -274.25269)
		(end 88.17991 -272.97507)
		(width 0.127)
		(layer "In5.Cu")
		(net "T7_BLAD3_EN")
	)
	(segment
		(start 43.543474 -351.610676)
		(end 45.9994 -349.15475)
		(width 0.127)
		(layer "In5.Cu")
		(net "T7_BLAD3_EN")
	)
	(segment
		(start 29.968444 -351.610676)
		(end 43.543474 -351.610676)
		(width 0.127)
		(layer "In5.Cu")
		(net "T7_BLAD3_EN")
	)
	(segment
		(start 7.5057 -284.829504)
		(end 22.011386 -284.829504)
		(width 0.127)
		(layer "In5.Cu")
		(net "T7_BLAD3_EN")
	)
	(segment
		(start 7.346188 -284.669992)
		(end 7.5057 -284.829504)
		(width 0.127)
		(layer "In5.Cu")
		(net "T7_BLAD3_EN")
	)
	(segment
		(start 27.95524 -290.773358)
		(end 27.95524 -349.597472)
		(width 0.127)
		(layer "In5.Cu")
		(net "T7_BLAD3_EN")
	)
	(segment
		(start 45.9994 -349.15475)
		(end 61.66231 -349.15475)
		(width 0.127)
		(layer "In5.Cu")
		(net "T7_BLAD3_EN")
	)
	(segment
		(start 87.401146 -281.126692)
		(end 89.036906 -279.490932)
		(width 0.127)
		(layer "In5.Cu")
		(net "T7_BLAD3_EN")
	)
	(segment
		(start 80.931512 -329.885548)
		(end 80.931512 -323.652388)
		(width 0.127)
		(layer "In5.Cu")
		(net "T7_BLAD3_EN")
	)
	(segment
		(start 80.931512 -323.652388)
		(end 83.839812 -320.744088)
		(width 0.127)
		(layer "In5.Cu")
		(net "T7_BLAD3_EN")
	)
	(segment
		(start 83.839812 -320.744088)
		(end 83.839812 -314.807854)
		(width 0.127)
		(layer "In5.Cu")
		(net "T7_BLAD3_EN")
	)
	(segment
		(start 85.18652 -291.15893)
		(end 85.18652 -283.341318)
		(width 0.127)
		(layer "In5.Cu")
		(net "T7_BLAD3_EN")
	)
	(segment
		(start 22.011386 -284.829504)
		(end 27.95524 -290.773358)
		(width 0.127)
		(layer "In5.Cu")
		(net "T7_BLAD3_EN")
	)
	(segment
		(start 85.18652 -283.341318)
		(end 87.401146 -281.126692)
		(width 0.127)
		(layer "In5.Cu")
		(net "T7_BLAD3_EN")
	)
	(segment
		(start 61.66231 -349.15475)
		(end 80.931512 -329.885548)
		(width 0.127)
		(layer "In5.Cu")
		(net "T7_BLAD3_EN")
	)
	(segment
		(start 89.036906 -279.490932)
		(end 89.036906 -275.109686)
		(width 0.127)
		(layer "In5.Cu")
		(net "T7_BLAD3_EN")
	)
	(segment
		(start 6.449822 -284.669992)
		(end 7.346188 -284.669992)
		(width 0.127)
		(layer "In5.Cu")
		(net "T7_BLAD3_EN")
	)
	(segment
		(start 92.053664 -306.594002)
		(end 92.053664 -298.026074)
		(width 0.127)
		(layer "In5.Cu")
		(net "T7_BLAD3_EN")
	)
	(segment
		(start 92.053664 -298.026074)
		(end 85.18652 -291.15893)
		(width 0.127)
		(layer "In5.Cu")
		(net "T7_BLAD3_EN")
	)
	(segment
		(start 89.036906 -275.109686)
		(end 88.17991 -274.25269)
		(width 0.127)
		(layer "In5.Cu")
		(net "T7_BLAD3_EN")
	)
	(segment
		(start 27.95524 -349.597472)
		(end 29.968444 -351.610676)
		(width 0.127)
		(layer "In5.Cu")
		(net "T7_BLAD3_EN")
	)
	(via
		(at 21.021802 -269.252954)
		(size 0.508)
		(drill 0.254)
		(layers "F.Cu" "B.Cu")
		(net "T7_BLAD2_RXD")
	)
	(segment
		(start 89.800684 -277.718774)
		(end 91.98991 -275.529548)
		(width 0.127)
		(layer "In2.Cu")
		(net "T7_BLAD2_RXD")
	)
	(segment
		(start 22.18436 -268.090396)
		(end 79.922116 -268.090396)
		(width 0.127)
		(layer "In2.Cu")
		(net "T7_BLAD2_RXD")
	)
	(segment
		(start 84.169504 -276.745446)
		(end 85.142832 -277.718774)
		(width 0.127)
		(layer "In2.Cu")
		(net "T7_BLAD2_RXD")
	)
	(segment
		(start 84.169504 -272.337784)
		(end 84.169504 -276.745446)
		(width 0.127)
		(layer "In2.Cu")
		(net "T7_BLAD2_RXD")
	)
	(segment
		(start 11.119104 -277.000462)
		(end 13.274294 -277.000462)
		(width 0.127)
		(layer "In2.Cu")
		(net "T7_BLAD2_RXD")
	)
	(segment
		(start 13.274294 -277.000462)
		(end 21.021802 -269.252954)
		(width 0.127)
		(layer "In2.Cu")
		(net "T7_BLAD2_RXD")
	)
	(segment
		(start 21.021802 -269.252954)
		(end 22.18436 -268.090396)
		(width 0.127)
		(layer "In2.Cu")
		(net "T7_BLAD2_RXD")
	)
	(segment
		(start 91.98991 -275.529548)
		(end 91.98991 -274.24507)
		(width 0.127)
		(layer "In2.Cu")
		(net "T7_BLAD2_RXD")
	)
	(segment
		(start 8.449818 -279.669748)
		(end 11.119104 -277.000462)
		(width 0.127)
		(layer "In2.Cu")
		(net "T7_BLAD2_RXD")
	)
	(segment
		(start 79.922116 -268.090396)
		(end 84.169504 -272.337784)
		(width 0.127)
		(layer "In2.Cu")
		(net "T7_BLAD2_RXD")
	)
	(segment
		(start 85.142832 -277.718774)
		(end 89.800684 -277.718774)
		(width 0.127)
		(layer "In2.Cu")
		(net "T7_BLAD2_RXD")
	)
	(segment
		(start 10.946384 -320.828162)
		(end 9.353804 -322.420742)
		(width 0.1524)
		(layer "F.Cu")
		(net "FAN3_TACH")
	)
	(segment
		(start 4.752594 -321.867276)
		(end 3.949954 -322.669916)
		(width 0.1524)
		(layer "F.Cu")
		(net "FAN3_TACH")
	)
	(segment
		(start 7.063232 -321.867276)
		(end 4.752594 -321.867276)
		(width 0.1524)
		(layer "F.Cu")
		(net "FAN3_TACH")
	)
	(segment
		(start 9.353804 -322.420742)
		(end 7.616698 -322.420742)
		(width 0.1524)
		(layer "F.Cu")
		(net "FAN3_TACH")
	)
	(segment
		(start 12.96924 -320.828162)
		(end 10.946384 -320.828162)
		(width 0.1524)
		(layer "F.Cu")
		(net "FAN3_TACH")
	)
	(segment
		(start 7.616698 -322.420742)
		(end 7.063232 -321.867276)
		(width 0.1524)
		(layer "F.Cu")
		(net "FAN3_TACH")
	)
	(segment
		(start 11.444224 -436.49392)
		(end 23.134574 -424.80357)
		(width 0.127)
		(layer "In2.Cu")
		(net "FAN3_TACH")
	)
	(segment
		(start 10.55116 -322.766944)
		(end 7.875016 -322.766944)
		(width 0.127)
		(layer "In2.Cu")
		(net "FAN3_TACH")
	)
	(segment
		(start 4.674616 -321.945254)
		(end 3.949954 -322.669916)
		(width 0.127)
		(layer "In2.Cu")
		(net "FAN3_TACH")
	)
	(segment
		(start 7.875016 -322.766944)
		(end 7.053326 -321.945254)
		(width 0.127)
		(layer "In2.Cu")
		(net "FAN3_TACH")
	)
	(segment
		(start 12.484354 -324.700138)
		(end 10.55116 -322.766944)
		(width 0.127)
		(layer "In2.Cu")
		(net "FAN3_TACH")
	)
	(segment
		(start 23.134574 -424.80357)
		(end 23.134574 -380.795276)
		(width 0.127)
		(layer "In2.Cu")
		(net "FAN3_TACH")
	)
	(segment
		(start 12.484354 -370.145056)
		(end 12.484354 -324.700138)
		(width 0.127)
		(layer "In2.Cu")
		(net "FAN3_TACH")
	)
	(segment
		(start 7.053326 -321.945254)
		(end 4.674616 -321.945254)
		(width 0.127)
		(layer "In2.Cu")
		(net "FAN3_TACH")
	)
	(segment
		(start 23.134574 -380.795276)
		(end 12.484354 -370.145056)
		(width 0.127)
		(layer "In2.Cu")
		(net "FAN3_TACH")
	)
	(via
		(at 85.261958 -266.421616)
		(size 0.508)
		(drill 0.254)
		(layers "F.Cu" "B.Cu")
		(net "T7_BLAD4_RXD")
	)
	(segment
		(start 91.98991 -271.70507)
		(end 90.545666 -271.70507)
		(width 0.127)
		(layer "In2.Cu")
		(net "T7_BLAD4_RXD")
	)
	(segment
		(start 7.650226 -274.669758)
		(end 7.911084 -274.4089)
		(width 0.127)
		(layer "In2.Cu")
		(net "T7_BLAD4_RXD")
	)
	(segment
		(start 6.449822 -274.669758)
		(end 7.650226 -274.669758)
		(width 0.127)
		(layer "In2.Cu")
		(net "T7_BLAD4_RXD")
	)
	(segment
		(start 18.75155 -266.224512)
		(end 85.065108 -266.224512)
		(width 0.127)
		(layer "In2.Cu")
		(net "T7_BLAD4_RXD")
	)
	(segment
		(start 85.261958 -266.421362)
		(end 85.261958 -266.421616)
		(width 0.127)
		(layer "In2.Cu")
		(net "T7_BLAD4_RXD")
	)
	(segment
		(start 90.545666 -271.70507)
		(end 85.261958 -266.421362)
		(width 0.127)
		(layer "In2.Cu")
		(net "T7_BLAD4_RXD")
	)
	(segment
		(start 85.065108 -266.224512)
		(end 85.261958 -266.421362)
		(width 0.127)
		(layer "In2.Cu")
		(net "T7_BLAD4_RXD")
	)
	(segment
		(start 10.567162 -274.4089)
		(end 18.75155 -266.224512)
		(width 0.127)
		(layer "In2.Cu")
		(net "T7_BLAD4_RXD")
	)
	(segment
		(start 7.911084 -274.4089)
		(end 10.567162 -274.4089)
		(width 0.127)
		(layer "In2.Cu")
		(net "T7_BLAD4_RXD")
	)
	(segment
		(start 8.92556 -326.145652)
		(end 8.449818 -325.66991)
		(width 0.1524)
		(layer "F.Cu")
		(net "FAN4_TACH")
	)
	(segment
		(start 9.74979 -326.145652)
		(end 8.92556 -326.145652)
		(width 0.1524)
		(layer "F.Cu")
		(net "FAN4_TACH")
	)
	(segment
		(start 10.311638 -326.7075)
		(end 9.74979 -326.145652)
		(width 0.1524)
		(layer "F.Cu")
		(net "FAN4_TACH")
	)
	(segment
		(start 12.467336 -326.7075)
		(end 10.311638 -326.7075)
		(width 0.1524)
		(layer "F.Cu")
		(net "FAN4_TACH")
	)
	(segment
		(start 13.029184 -326.145652)
		(end 12.467336 -326.7075)
		(width 0.1524)
		(layer "F.Cu")
		(net "FAN4_TACH")
	)
	(segment
		(start 22.947884 -407.859992)
		(end 11.444224 -419.363652)
		(width 0.1524)
		(layer "B.Cu")
		(net "FAN4_TACH")
	)
	(segment
		(start 10.234422 -327.454514)
		(end 10.234422 -342.979248)
		(width 0.1524)
		(layer "B.Cu")
		(net "FAN4_TACH")
	)
	(segment
		(start 10.234422 -342.979248)
		(end 12.937998 -345.682824)
		(width 0.1524)
		(layer "B.Cu")
		(net "FAN4_TACH")
	)
	(segment
		(start 22.947884 -382.202436)
		(end 22.947884 -407.859992)
		(width 0.1524)
		(layer "B.Cu")
		(net "FAN4_TACH")
	)
	(segment
		(start 12.937998 -372.19255)
		(end 22.947884 -382.202436)
		(width 0.1524)
		(layer "B.Cu")
		(net "FAN4_TACH")
	)
	(segment
		(start 11.444224 -419.363652)
		(end 11.444224 -423.893996)
		(width 0.1524)
		(layer "B.Cu")
		(net "FAN4_TACH")
	)
	(segment
		(start 12.937998 -345.682824)
		(end 12.937998 -372.19255)
		(width 0.1524)
		(layer "B.Cu")
		(net "FAN4_TACH")
	)
	(segment
		(start 8.449818 -325.66991)
		(end 10.234422 -327.454514)
		(width 0.1524)
		(layer "B.Cu")
		(net "FAN4_TACH")
	)
	(via
		(at 85.727286 -281.837892)
		(size 0.508)
		(drill 0.254)
		(layers "F.Cu" "B.Cu")
		(net "T7_BLAD1_EN")
	)
	(segment
		(start 61.526674 -348.806516)
		(end 80.589374 -329.743816)
		(width 0.127)
		(layer "In5.Cu")
		(net "T7_BLAD1_EN")
	)
	(segment
		(start 84.85632 -282.708858)
		(end 85.727286 -281.837892)
		(width 0.127)
		(layer "In5.Cu")
		(net "T7_BLAD1_EN")
	)
	(segment
		(start 80.589374 -323.510656)
		(end 83.497674 -320.602356)
		(width 0.127)
		(layer "In5.Cu")
		(net "T7_BLAD1_EN")
	)
	(segment
		(start 43.286934 -351.268538)
		(end 45.748956 -348.806516)
		(width 0.127)
		(layer "In5.Cu")
		(net "T7_BLAD1_EN")
	)
	(segment
		(start 28.297378 -290.48964)
		(end 28.297378 -349.45574)
		(width 0.127)
		(layer "In5.Cu")
		(net "T7_BLAD1_EN")
	)
	(segment
		(start 6.449822 -286.669988)
		(end 5.37845 -285.598616)
		(width 0.127)
		(layer "In5.Cu")
		(net "T7_BLAD1_EN")
	)
	(segment
		(start 7.920228 -284.48254)
		(end 22.290278 -284.48254)
		(width 0.127)
		(layer "In5.Cu")
		(net "T7_BLAD1_EN")
	)
	(segment
		(start 45.748956 -348.806516)
		(end 61.526674 -348.806516)
		(width 0.127)
		(layer "In5.Cu")
		(net "T7_BLAD1_EN")
	)
	(segment
		(start 83.497674 -320.602356)
		(end 83.497674 -314.666122)
		(width 0.127)
		(layer "In5.Cu")
		(net "T7_BLAD1_EN")
	)
	(segment
		(start 80.589374 -329.743816)
		(end 80.589374 -323.510656)
		(width 0.127)
		(layer "In5.Cu")
		(net "T7_BLAD1_EN")
	)
	(segment
		(start 7.2517 -283.814012)
		(end 7.920228 -284.48254)
		(width 0.127)
		(layer "In5.Cu")
		(net "T7_BLAD1_EN")
	)
	(segment
		(start 91.711526 -298.167806)
		(end 84.85632 -291.3126)
		(width 0.127)
		(layer "In5.Cu")
		(net "T7_BLAD1_EN")
	)
	(segment
		(start 22.290278 -284.48254)
		(end 28.297378 -290.48964)
		(width 0.127)
		(layer "In5.Cu")
		(net "T7_BLAD1_EN")
	)
	(segment
		(start 91.711526 -306.45227)
		(end 91.711526 -298.167806)
		(width 0.127)
		(layer "In5.Cu")
		(net "T7_BLAD1_EN")
	)
	(segment
		(start 83.497674 -314.666122)
		(end 91.711526 -306.45227)
		(width 0.127)
		(layer "In5.Cu")
		(net "T7_BLAD1_EN")
	)
	(segment
		(start 5.37845 -284.376876)
		(end 5.941314 -283.814012)
		(width 0.127)
		(layer "In5.Cu")
		(net "T7_BLAD1_EN")
	)
	(segment
		(start 30.110176 -351.268538)
		(end 43.286934 -351.268538)
		(width 0.127)
		(layer "In5.Cu")
		(net "T7_BLAD1_EN")
	)
	(segment
		(start 88.17991 -279.385268)
		(end 88.17991 -275.51507)
		(width 0.127)
		(layer "In5.Cu")
		(net "T7_BLAD1_EN")
	)
	(segment
		(start 5.941314 -283.814012)
		(end 7.2517 -283.814012)
		(width 0.127)
		(layer "In5.Cu")
		(net "T7_BLAD1_EN")
	)
	(segment
		(start 84.85632 -291.3126)
		(end 84.85632 -282.708858)
		(width 0.127)
		(layer "In5.Cu")
		(net "T7_BLAD1_EN")
	)
	(segment
		(start 28.297378 -349.45574)
		(end 30.110176 -351.268538)
		(width 0.127)
		(layer "In5.Cu")
		(net "T7_BLAD1_EN")
	)
	(segment
		(start 5.37845 -285.598616)
		(end 5.37845 -284.376876)
		(width 0.127)
		(layer "In5.Cu")
		(net "T7_BLAD1_EN")
	)
	(segment
		(start 85.727286 -281.837892)
		(end 88.17991 -279.385268)
		(width 0.127)
		(layer "In5.Cu")
		(net "T7_BLAD1_EN")
	)
	(via
		(at 87.776812 -266.152376)
		(size 0.508)
		(drill 0.254)
		(layers "F.Cu" "B.Cu")
		(net "T7_BLAD4_TXD")
	)
	(segment
		(start 92.86113 -271.236694)
		(end 87.776812 -266.152376)
		(width 0.127)
		(layer "In2.Cu")
		(net "T7_BLAD4_TXD")
	)
	(segment
		(start 87.515446 -265.89101)
		(end 87.776812 -266.152376)
		(width 0.127)
		(layer "In2.Cu")
		(net "T7_BLAD4_TXD")
	)
	(segment
		(start 92.08135 -272.97507)
		(end 92.86113 -272.19529)
		(width 0.127)
		(layer "In2.Cu")
		(net "T7_BLAD4_TXD")
	)
	(segment
		(start 18.613374 -265.89101)
		(end 87.515446 -265.89101)
		(width 0.127)
		(layer "In2.Cu")
		(net "T7_BLAD4_TXD")
	)
	(segment
		(start 8.449818 -273.66976)
		(end 10.834624 -273.66976)
		(width 0.127)
		(layer "In2.Cu")
		(net "T7_BLAD4_TXD")
	)
	(segment
		(start 90.71991 -272.97507)
		(end 92.08135 -272.97507)
		(width 0.127)
		(layer "In2.Cu")
		(net "T7_BLAD4_TXD")
	)
	(segment
		(start 92.86113 -272.19529)
		(end 92.86113 -271.236694)
		(width 0.127)
		(layer "In2.Cu")
		(net "T7_BLAD4_TXD")
	)
	(segment
		(start 10.834624 -273.66976)
		(end 18.613374 -265.89101)
		(width 0.127)
		(layer "In2.Cu")
		(net "T7_BLAD4_TXD")
	)
	(via
		(at 82.358484 -267.153644)
		(size 0.508)
		(drill 0.254)
		(layers "F.Cu" "B.Cu")
		(net "T7_BLAD3_RXD")
	)
	(segment
		(start 18.85188 -266.6111)
		(end 81.81594 -266.6111)
		(width 0.127)
		(layer "In2.Cu")
		(net "T7_BLAD3_RXD")
	)
	(segment
		(start 6.449822 -276.669754)
		(end 8.303006 -274.81657)
		(width 0.127)
		(layer "In2.Cu")
		(net "T7_BLAD3_RXD")
	)
	(segment
		(start 8.303006 -274.81657)
		(end 10.64641 -274.81657)
		(width 0.127)
		(layer "In2.Cu")
		(net "T7_BLAD3_RXD")
	)
	(segment
		(start 81.81594 -266.6111)
		(end 82.358484 -267.153644)
		(width 0.127)
		(layer "In2.Cu")
		(net "T7_BLAD3_RXD")
	)
	(segment
		(start 82.358484 -267.153644)
		(end 86.90991 -271.70507)
		(width 0.127)
		(layer "In2.Cu")
		(net "T7_BLAD3_RXD")
	)
	(segment
		(start 10.64641 -274.81657)
		(end 18.85188 -266.6111)
		(width 0.127)
		(layer "In2.Cu")
		(net "T7_BLAD3_RXD")
	)
	(segment
		(start 27.117802 -366.928146)
		(end 26.274522 -367.771426)
		(width 0.1524)
		(layer "F.Cu")
		(net "PSU5_PS_ON_N")
	)
	(segment
		(start 30.45968 -365.810038)
		(end 28.23591 -365.810038)
		(width 0.1524)
		(layer "F.Cu")
		(net "PSU5_PS_ON_N")
	)
	(segment
		(start 28.23591 -365.810038)
		(end 27.117802 -366.928146)
		(width 0.1524)
		(layer "F.Cu")
		(net "PSU5_PS_ON_N")
	)
	(via
		(at 27.117802 -366.928146)
		(size 0.508)
		(drill 0.254)
		(layers "F.Cu" "B.Cu")
		(net "PSU5_PS_ON_N")
	)
	(via
		(at 82.945732 -286.097472)
		(size 0.508)
		(drill 0.254)
		(layers "F.Cu" "B.Cu")
		(net "T7_BLAD1_TXD")
	)
	(segment
		(start 82.945732 -282.10637)
		(end 82.945732 -286.097472)
		(width 0.127)
		(layer "In5.Cu")
		(net "T7_BLAD1_TXD")
	)
	(segment
		(start 60.668662 -348.083124)
		(end 45.251116 -348.083124)
		(width 0.127)
		(layer "In5.Cu")
		(net "T7_BLAD1_TXD")
	)
	(segment
		(start 80.91932 -316.181994)
		(end 80.91932 -321.599306)
		(width 0.127)
		(layer "In5.Cu")
		(net "T7_BLAD1_TXD")
	)
	(segment
		(start 85.63991 -279.412192)
		(end 82.945732 -282.10637)
		(width 0.127)
		(layer "In5.Cu")
		(net "T7_BLAD1_TXD")
	)
	(segment
		(start 29.415232 -290.00069)
		(end 22.707346 -283.292804)
		(width 0.127)
		(layer "In5.Cu")
		(net "T7_BLAD1_TXD")
	)
	(segment
		(start 79.47152 -329.280266)
		(end 60.668662 -348.083124)
		(width 0.127)
		(layer "In5.Cu")
		(net "T7_BLAD1_TXD")
	)
	(segment
		(start 22.707346 -283.292804)
		(end 11.10742 -283.292804)
		(width 0.127)
		(layer "In5.Cu")
		(net "T7_BLAD1_TXD")
	)
	(segment
		(start 82.945732 -291.337492)
		(end 90.343228 -298.734988)
		(width 0.127)
		(layer "In5.Cu")
		(net "T7_BLAD1_TXD")
	)
	(segment
		(start 82.945732 -286.097472)
		(end 82.945732 -291.337492)
		(width 0.127)
		(layer "In5.Cu")
		(net "T7_BLAD1_TXD")
	)
	(segment
		(start 30.516576 -350.150684)
		(end 29.415232 -349.04934)
		(width 0.127)
		(layer "In5.Cu")
		(net "T7_BLAD1_TXD")
	)
	(segment
		(start 90.343228 -298.734988)
		(end 90.343228 -306.758086)
		(width 0.127)
		(layer "In5.Cu")
		(net "T7_BLAD1_TXD")
	)
	(segment
		(start 29.415232 -349.04934)
		(end 29.415232 -290.00069)
		(width 0.127)
		(layer "In5.Cu")
		(net "T7_BLAD1_TXD")
	)
	(segment
		(start 79.47152 -323.047106)
		(end 79.47152 -329.280266)
		(width 0.127)
		(layer "In5.Cu")
		(net "T7_BLAD1_TXD")
	)
	(segment
		(start 11.10742 -283.292804)
		(end 8.484362 -280.669746)
		(width 0.127)
		(layer "In5.Cu")
		(net "T7_BLAD1_TXD")
	)
	(segment
		(start 8.484362 -280.669746)
		(end 6.449822 -280.669746)
		(width 0.127)
		(layer "In5.Cu")
		(net "T7_BLAD1_TXD")
	)
	(segment
		(start 85.63991 -275.51507)
		(end 85.63991 -279.412192)
		(width 0.127)
		(layer "In5.Cu")
		(net "T7_BLAD1_TXD")
	)
	(segment
		(start 45.251116 -348.083124)
		(end 43.183556 -350.150684)
		(width 0.127)
		(layer "In5.Cu")
		(net "T7_BLAD1_TXD")
	)
	(segment
		(start 80.91932 -321.599306)
		(end 79.47152 -323.047106)
		(width 0.127)
		(layer "In5.Cu")
		(net "T7_BLAD1_TXD")
	)
	(segment
		(start 90.343228 -306.758086)
		(end 80.91932 -316.181994)
		(width 0.127)
		(layer "In5.Cu")
		(net "T7_BLAD1_TXD")
	)
	(segment
		(start 43.183556 -350.150684)
		(end 30.516576 -350.150684)
		(width 0.127)
		(layer "In5.Cu")
		(net "T7_BLAD1_TXD")
	)
	(via
		(at 83.563206 -284.75686)
		(size 0.508)
		(drill 0.254)
		(layers "F.Cu" "B.Cu")
		(net "T7_BLAD1_RXD")
	)
	(segment
		(start 83.563206 -291.389054)
		(end 90.743278 -298.569126)
		(width 0.127)
		(layer "In5.Cu")
		(net "T7_BLAD1_RXD")
	)
	(segment
		(start 83.563206 -282.344368)
		(end 86.90991 -278.997664)
		(width 0.127)
		(layer "In5.Cu")
		(net "T7_BLAD1_RXD")
	)
	(segment
		(start 79.87157 -323.212968)
		(end 79.87157 -329.446128)
		(width 0.127)
		(layer "In5.Cu")
		(net "T7_BLAD1_RXD")
	)
	(segment
		(start 10.45591 -283.675836)
		(end 8.449818 -281.669744)
		(width 0.127)
		(layer "In5.Cu")
		(net "T7_BLAD1_RXD")
	)
	(segment
		(start 81.31937 -321.765168)
		(end 79.87157 -323.212968)
		(width 0.127)
		(layer "In5.Cu")
		(net "T7_BLAD1_RXD")
	)
	(segment
		(start 86.90991 -278.997664)
		(end 86.90991 -274.24507)
		(width 0.127)
		(layer "In5.Cu")
		(net "T7_BLAD1_RXD")
	)
	(segment
		(start 45.474382 -348.436946)
		(end 43.360594 -350.550734)
		(width 0.127)
		(layer "In5.Cu")
		(net "T7_BLAD1_RXD")
	)
	(segment
		(start 22.564344 -283.675836)
		(end 10.45591 -283.675836)
		(width 0.127)
		(layer "In5.Cu")
		(net "T7_BLAD1_RXD")
	)
	(segment
		(start 83.563206 -284.75686)
		(end 83.563206 -282.344368)
		(width 0.127)
		(layer "In5.Cu")
		(net "T7_BLAD1_RXD")
	)
	(segment
		(start 79.87157 -329.446128)
		(end 60.880752 -348.436946)
		(width 0.127)
		(layer "In5.Cu")
		(net "T7_BLAD1_RXD")
	)
	(segment
		(start 29.015182 -349.135192)
		(end 29.015182 -290.12642)
		(width 0.127)
		(layer "In5.Cu")
		(net "T7_BLAD1_RXD")
	)
	(segment
		(start 81.31937 -316.347856)
		(end 81.31937 -321.765168)
		(width 0.127)
		(layer "In5.Cu")
		(net "T7_BLAD1_RXD")
	)
	(segment
		(start 43.360594 -350.550734)
		(end 30.430724 -350.550734)
		(width 0.127)
		(layer "In5.Cu")
		(net "T7_BLAD1_RXD")
	)
	(segment
		(start 83.563206 -284.75686)
		(end 83.563206 -291.389054)
		(width 0.127)
		(layer "In5.Cu")
		(net "T7_BLAD1_RXD")
	)
	(segment
		(start 60.880752 -348.436946)
		(end 45.474382 -348.436946)
		(width 0.127)
		(layer "In5.Cu")
		(net "T7_BLAD1_RXD")
	)
	(segment
		(start 90.743278 -298.569126)
		(end 90.743278 -306.923948)
		(width 0.127)
		(layer "In5.Cu")
		(net "T7_BLAD1_RXD")
	)
	(segment
		(start 29.015182 -290.12642)
		(end 22.564344 -283.675836)
		(width 0.127)
		(layer "In5.Cu")
		(net "T7_BLAD1_RXD")
	)
	(segment
		(start 30.430724 -350.550734)
		(end 29.015182 -349.135192)
		(width 0.127)
		(layer "In5.Cu")
		(net "T7_BLAD1_RXD")
	)
	(segment
		(start 90.743278 -306.923948)
		(end 81.31937 -316.347856)
		(width 0.127)
		(layer "In5.Cu")
		(net "T7_BLAD1_RXD")
	)
	(via
		(at 78.658212 -267.528548)
		(size 0.508)
		(drill 0.254)
		(layers "F.Cu" "B.Cu")
		(net "T7_BLAD2_TXD")
	)
	(segment
		(start 84.57946 -276.57552)
		(end 85.2424 -277.23846)
		(width 0.127)
		(layer "In2.Cu")
		(net "T7_BLAD2_TXD")
	)
	(segment
		(start 88.99652 -277.23846)
		(end 90.71991 -275.51507)
		(width 0.127)
		(layer "In2.Cu")
		(net "T7_BLAD2_TXD")
	)
	(segment
		(start 84.57946 -272.259044)
		(end 84.57946 -276.57552)
		(width 0.127)
		(layer "In2.Cu")
		(net "T7_BLAD2_TXD")
	)
	(segment
		(start 8.72109 -276.398482)
		(end 12.420346 -276.398482)
		(width 0.127)
		(layer "In2.Cu")
		(net "T7_BLAD2_TXD")
	)
	(segment
		(start 12.420346 -276.398482)
		(end 21.29028 -267.528548)
		(width 0.127)
		(layer "In2.Cu")
		(net "T7_BLAD2_TXD")
	)
	(segment
		(start 78.658212 -267.528548)
		(end 79.848964 -267.528548)
		(width 0.127)
		(layer "In2.Cu")
		(net "T7_BLAD2_TXD")
	)
	(segment
		(start 21.29028 -267.528548)
		(end 78.658212 -267.528548)
		(width 0.127)
		(layer "In2.Cu")
		(net "T7_BLAD2_TXD")
	)
	(segment
		(start 79.848964 -267.528548)
		(end 84.57946 -272.259044)
		(width 0.127)
		(layer "In2.Cu")
		(net "T7_BLAD2_TXD")
	)
	(segment
		(start 6.449822 -278.66975)
		(end 8.72109 -276.398482)
		(width 0.127)
		(layer "In2.Cu")
		(net "T7_BLAD2_TXD")
	)
	(segment
		(start 85.2424 -277.23846)
		(end 88.99652 -277.23846)
		(width 0.127)
		(layer "In2.Cu")
		(net "T7_BLAD2_TXD")
	)
	(segment
		(start 27.60218 -277.40991)
		(end 30.45968 -277.40991)
		(width 0.1524)
		(layer "F.Cu")
		(net "PSU4_PS_ON_N")
	)
	(segment
		(start 26.525728 -278.486362)
		(end 27.267154 -277.744936)
		(width 0.1524)
		(layer "F.Cu")
		(net "PSU4_PS_ON_N")
	)
	(segment
		(start 27.267154 -277.744936)
		(end 27.60218 -277.40991)
		(width 0.1524)
		(layer "F.Cu")
		(net "PSU4_PS_ON_N")
	)
	(via
		(at 27.267154 -277.744936)
		(size 0.508)
		(drill 0.254)
		(layers "F.Cu" "B.Cu")
		(net "PSU4_PS_ON_N")
	)
	(segment
		(start 30.45968 -189.010036)
		(end 29.167836 -189.010036)
		(width 0.1524)
		(layer "F.Cu")
		(net "PSU3_PS_ON_N")
	)
	(segment
		(start 28.912566 -189.265306)
		(end 27.16149 -189.265306)
		(width 0.1524)
		(layer "F.Cu")
		(net "PSU3_PS_ON_N")
	)
	(segment
		(start 29.167836 -189.010036)
		(end 28.912566 -189.265306)
		(width 0.1524)
		(layer "F.Cu")
		(net "PSU3_PS_ON_N")
	)
	(segment
		(start 27.16149 -189.265306)
		(end 26.503884 -189.265306)
		(width 0.1524)
		(layer "F.Cu")
		(net "PSU3_PS_ON_N")
	)
	(via
		(at 27.16149 -189.265306)
		(size 0.508)
		(drill 0.254)
		(layers "F.Cu" "B.Cu")
		(net "PSU3_PS_ON_N")
	)
	(segment
		(start 13.719556 -230.500174)
		(end 13.719556 -229.665784)
		(width 0.1524)
		(layer "F.Cu")
		(net "PSU_ALERT_N")
	)
	(segment
		(start 23.667466 -310.080914)
		(end 23.667466 -334.58658)
		(width 0.1524)
		(layer "F.Cu")
		(net "PSU_ALERT_N")
	)
	(segment
		(start 23.667466 -334.58658)
		(end 25.582626 -336.50174)
		(width 0.1524)
		(layer "F.Cu")
		(net "PSU_ALERT_N")
	)
	(segment
		(start 11.781028 -271.669764)
		(end 8.449818 -271.669764)
		(width 0.1524)
		(layer "F.Cu")
		(net "PSU_ALERT_N")
	)
	(segment
		(start 23.188676 -235.445554)
		(end 23.091394 -235.542836)
		(width 0.1524)
		(layer "F.Cu")
		(net "PSU_ALERT_N")
	)
	(segment
		(start 23.09368 -287.432242)
		(end 26.174954 -290.513516)
		(width 0.1524)
		(layer "F.Cu")
		(net "PSU_ALERT_N")
	)
	(segment
		(start 16.083026 -267.367766)
		(end 11.781028 -271.669764)
		(width 0.1524)
		(layer "F.Cu")
		(net "PSU_ALERT_N")
	)
	(segment
		(start 23.09368 -271.003522)
		(end 23.09368 -287.432242)
		(width 0.1524)
		(layer "F.Cu")
		(net "PSU_ALERT_N")
	)
	(segment
		(start 28.037536 -267.367766)
		(end 16.083026 -267.367766)
		(width 0.1524)
		(layer "F.Cu")
		(net "PSU_ALERT_N")
	)
	(segment
		(start 29.957776 -270.291814)
		(end 23.805388 -270.291814)
		(width 0.1524)
		(layer "F.Cu")
		(net "PSU_ALERT_N")
	)
	(segment
		(start 23.091394 -235.542836)
		(end 18.762218 -235.542836)
		(width 0.1524)
		(layer "F.Cu")
		(net "PSU_ALERT_N")
	)
	(segment
		(start 26.174954 -290.513516)
		(end 26.174954 -307.573426)
		(width 0.1524)
		(layer "F.Cu")
		(net "PSU_ALERT_N")
	)
	(segment
		(start 30.45968 -269.78991)
		(end 28.037536 -267.367766)
		(width 0.1524)
		(layer "F.Cu")
		(net "PSU_ALERT_N")
	)
	(segment
		(start 30.45968 -269.78991)
		(end 29.957776 -270.291814)
		(width 0.1524)
		(layer "F.Cu")
		(net "PSU_ALERT_N")
	)
	(segment
		(start 23.805388 -270.291814)
		(end 23.09368 -271.003522)
		(width 0.1524)
		(layer "F.Cu")
		(net "PSU_ALERT_N")
	)
	(segment
		(start 18.762218 -235.542836)
		(end 13.719556 -230.500174)
		(width 0.1524)
		(layer "F.Cu")
		(net "PSU_ALERT_N")
	)
	(segment
		(start 26.174954 -307.573426)
		(end 23.667466 -310.080914)
		(width 0.1524)
		(layer "F.Cu")
		(net "PSU_ALERT_N")
	)
	(via
		(at 25.582626 -336.50174)
		(size 0.508)
		(drill 0.254)
		(layers "F.Cu" "B.Cu")
		(net "PSU_ALERT_N")
	)
	(via
		(at 23.188676 -235.445554)
		(size 0.508)
		(drill 0.254)
		(layers "F.Cu" "B.Cu")
		(net "PSU_ALERT_N")
	)
	(via
		(at 92.007944 -82.545682)
		(size 0.508)
		(drill 0.254)
		(layers "F.Cu" "B.Cu")
		(net "PSU_ALERT_N")
	)
	(via
		(at 93.041724 -482.565456)
		(size 0.508)
		(drill 0.254)
		(layers "F.Cu" "B.Cu")
		(net "PSU_ALERT_N")
	)
	(via
		(at 90.565986 -171.492418)
		(size 0.508)
		(drill 0.254)
		(layers "F.Cu" "B.Cu")
		(net "PSU_ALERT_N")
	)
	(via
		(at 95.168974 -346.86748)
		(size 0.508)
		(drill 0.254)
		(layers "F.Cu" "B.Cu")
		(net "PSU_ALERT_N")
	)
	(segment
		(start 21.998432 -261.328662)
		(end 30.45968 -269.78991)
		(width 0.1524)
		(layer "B.Cu")
		(net "PSU_ALERT_N")
	)
	(segment
		(start 90.75928 -171.299124)
		(end 90.565986 -171.492418)
		(width 0.1524)
		(layer "B.Cu")
		(net "PSU_ALERT_N")
	)
	(segment
		(start 93.339158 -82.545682)
		(end 92.007944 -82.545682)
		(width 0.1524)
		(layer "B.Cu")
		(net "PSU_ALERT_N")
	)
	(segment
		(start 91.499944 -480.689158)
		(end 91.815412 -480.37369)
		(width 0.1524)
		(layer "B.Cu")
		(net "PSU_ALERT_N")
	)
	(segment
		(start 30.45968 -180.23967)
		(end 23.561548 -173.341538)
		(width 0.1524)
		(layer "B.Cu")
		(net "PSU_ALERT_N")
	)
	(segment
		(start 93.95206 -79.43088)
		(end 95.007176 -79.43088)
		(width 0.1524)
		(layer "B.Cu")
		(net "PSU_ALERT_N")
	)
	(segment
		(start 24.511254 -337.573112)
		(end 24.511254 -352.241612)
		(width 0.1524)
		(layer "B.Cu")
		(net "PSU_ALERT_N")
	)
	(segment
		(start 95.257874 -79.180182)
		(end 95.257874 -77.950314)
		(width 0.1524)
		(layer "B.Cu")
		(net "PSU_ALERT_N")
	)
	(segment
		(start 93.04147 -479.4631)
		(end 91.815412 -479.4631)
		(width 0.1524)
		(layer "B.Cu")
		(net "PSU_ALERT_N")
	)
	(segment
		(start 31.676086 -94.206314)
		(end 30.45968 -92.989908)
		(width 0.1524)
		(layer "B.Cu")
		(net "PSU_ALERT_N")
	)
	(segment
		(start 23.188676 -235.445554)
		(end 23.188676 -235.973366)
		(width 0.1524)
		(layer "B.Cu")
		(net "PSU_ALERT_N")
	)
	(segment
		(start 92.81033 -79.43088)
		(end 92.65793 -79.27848)
		(width 0.1524)
		(layer "B.Cu")
		(net "PSU_ALERT_N")
	)
	(segment
		(start 91.865958 -171.316396)
		(end 91.88323 -171.299124)
		(width 0.1524)
		(layer "B.Cu")
		(net "PSU_ALERT_N")
	)
	(segment
		(start 32.00781 -359.738168)
		(end 30.45968 -358.190038)
		(width 0.1524)
		(layer "B.Cu")
		(net "PSU_ALERT_N")
	)
	(segment
		(start 93.957902 -77.950314)
		(end 93.957902 -79.425038)
		(width 0.1524)
		(layer "B.Cu")
		(net "PSU_ALERT_N")
	)
	(segment
		(start 97.118932 -342.20277)
		(end 97.118932 -343.635584)
		(width 0.1524)
		(layer "B.Cu")
		(net "PSU_ALERT_N")
	)
	(segment
		(start 94.607888 -82.777838)
		(end 94.375732 -82.545682)
		(width 0.1524)
		(layer "B.Cu")
		(net "PSU_ALERT_N")
	)
	(segment
		(start 23.561548 -173.341538)
		(end 23.561548 -110.75289)
		(width 0.1524)
		(layer "B.Cu")
		(net "PSU_ALERT_N")
	)
	(segment
		(start 23.561548 -110.75289)
		(end 25.24379 -109.070648)
		(width 0.1524)
		(layer "B.Cu")
		(net "PSU_ALERT_N")
	)
	(segment
		(start 21.702522 -232.05567)
		(end 21.702522 -222.063818)
		(width 0.1524)
		(layer "B.Cu")
		(net "PSU_ALERT_N")
	)
	(segment
		(start 97.17024 -343.686892)
		(end 96.092772 -343.686892)
		(width 0.1524)
		(layer "B.Cu")
		(net "PSU_ALERT_N")
	)
	(segment
		(start 30.816804 -190.08979)
		(end 31.55696 -189.349634)
		(width 0.1524)
		(layer "B.Cu")
		(net "PSU_ALERT_N")
	)
	(segment
		(start 30.45968 -446.589912)
		(end 28.260548 -444.39078)
		(width 0.1524)
		(layer "B.Cu")
		(net "PSU_ALERT_N")
	)
	(segment
		(start 93.003624 -171.299124)
		(end 91.88323 -171.299124)
		(width 0.1524)
		(layer "B.Cu")
		(net "PSU_ALERT_N")
	)
	(segment
		(start 30.859984 -371.926612)
		(end 32.00781 -370.778786)
		(width 0.1524)
		(layer "B.Cu")
		(net "PSU_ALERT_N")
	)
	(segment
		(start 92.653612 -483.223062)
		(end 92.653612 -483.871524)
		(width 0.1524)
		(layer "B.Cu")
		(net "PSU_ALERT_N")
	)
	(segment
		(start 25.582626 -336.50174)
		(end 24.511254 -337.573112)
		(width 0.1524)
		(layer "B.Cu")
		(net "PSU_ALERT_N")
	)
	(segment
		(start 28.18257 -6.867144)
		(end 28.18257 -10.27049)
		(width 0.1524)
		(layer "B.Cu")
		(net "PSU_ALERT_N")
	)
	(segment
		(start 31.55696 -182.487316)
		(end 30.45968 -181.390036)
		(width 0.1524)
		(layer "B.Cu")
		(net "PSU_ALERT_N")
	)
	(segment
		(start 22.10308 -194.613784)
		(end 26.627074 -190.08979)
		(width 0.1524)
		(layer "B.Cu")
		(net "PSU_ALERT_N")
	)
	(segment
		(start 26.046684 -439.57494)
		(end 26.046684 -375.521982)
		(width 0.1524)
		(layer "B.Cu")
		(net "PSU_ALERT_N")
	)
	(segment
		(start 23.910798 -87.03437)
		(end 29.866336 -92.989908)
		(width 0.1524)
		(layer "B.Cu")
		(net "PSU_ALERT_N")
	)
	(segment
		(start 92.003626 -478.029524)
		(end 92.003626 -478.764092)
		(width 0.1524)
		(layer "B.Cu")
		(net "PSU_ALERT_N")
	)
	(segment
		(start 92.003626 -478.764092)
		(end 91.815412 -478.952306)
		(width 0.1524)
		(layer "B.Cu")
		(net "PSU_ALERT_N")
	)
	(segment
		(start 91.35364 -483.871524)
		(end 91.35364 -483.083616)
		(width 0.1524)
		(layer "B.Cu")
		(net "PSU_ALERT_N")
	)
	(segment
		(start 21.702522 -222.063818)
		(end 22.10308 -221.66326)
		(width 0.1524)
		(layer "B.Cu")
		(net "PSU_ALERT_N")
	)
	(segment
		(start 90.314526 -482.565456)
		(end 91.499944 -482.565456)
		(width 0.1524)
		(layer "B.Cu")
		(net "PSU_ALERT_N")
	)
	(segment
		(start 23.188676 -233.541824)
		(end 21.702522 -232.05567)
		(width 0.1524)
		(layer "B.Cu")
		(net "PSU_ALERT_N")
	)
	(segment
		(start 95.81896 -343.41308)
		(end 95.81896 -342.20277)
		(width 0.1524)
		(layer "B.Cu")
		(net "PSU_ALERT_N")
	)
	(segment
		(start 93.815916 -166.874444)
		(end 93.815916 -167.932608)
		(width 0.1524)
		(layer "B.Cu")
		(net "PSU_ALERT_N")
	)
	(segment
		(start 94.375732 -82.545682)
		(end 93.339158 -82.545682)
		(width 0.1524)
		(layer "B.Cu")
		(net "PSU_ALERT_N")
	)
	(segment
		(start 30.45968 -181.390036)
		(end 30.45968 -180.23967)
		(width 0.1524)
		(layer "B.Cu")
		(net "PSU_ALERT_N")
	)
	(segment
		(start 25.907746 -11.585194)
		(end 23.910798 -13.582142)
		(width 0.1524)
		(layer "B.Cu")
		(net "PSU_ALERT_N")
	)
	(segment
		(start 93.16593 -171.46143)
		(end 93.003624 -171.299124)
		(width 0.1524)
		(layer "B.Cu")
		(net "PSU_ALERT_N")
	)
	(segment
		(start 93.303598 -478.029524)
		(end 93.303598 -479.200972)
		(width 0.1524)
		(layer "B.Cu")
		(net "PSU_ALERT_N")
	)
	(segment
		(start 32.00781 -370.778786)
		(end 32.00781 -359.738168)
		(width 0.1524)
		(layer "B.Cu")
		(net "PSU_ALERT_N")
	)
	(segment
		(start 97.132648 -346.621862)
		(end 96.47047 -346.621862)
		(width 0.1524)
		(layer "B.Cu")
		(net "PSU_ALERT_N")
	)
	(segment
		(start 25.24379 -109.070648)
		(end 25.24379 -104.140508)
		(width 0.1524)
		(layer "B.Cu")
		(net "PSU_ALERT_N")
	)
	(segment
		(start 91.88323 -171.299124)
		(end 90.75928 -171.299124)
		(width 0.1524)
		(layer "B.Cu")
		(net "PSU_ALERT_N")
	)
	(segment
		(start 26.627074 -190.08979)
		(end 30.816804 -190.08979)
		(width 0.1524)
		(layer "B.Cu")
		(net "PSU_ALERT_N")
	)
	(segment
		(start 98.418904 -342.20277)
		(end 98.418904 -343.264998)
		(width 0.1524)
		(layer "B.Cu")
		(net "PSU_ALERT_N")
	)
	(segment
		(start 91.88323 -168.198292)
		(end 91.88323 -171.299124)
		(width 0.1524)
		(layer "B.Cu")
		(net "PSU_ALERT_N")
	)
	(segment
		(start 91.499944 -482.565456)
		(end 91.499944 -480.689158)
		(width 0.1524)
		(layer "B.Cu")
		(net "PSU_ALERT_N")
	)
	(segment
		(start 91.815412 -480.37369)
		(end 91.815412 -479.4631)
		(width 0.1524)
		(layer "B.Cu")
		(net "PSU_ALERT_N")
	)
	(segment
		(start 31.073344 -101.656896)
		(end 31.676086 -101.054154)
		(width 0.1524)
		(layer "B.Cu")
		(net "PSU_ALERT_N")
	)
	(segment
		(start 95.414592 -346.621862)
		(end 96.47047 -346.621862)
		(width 0.1524)
		(layer "B.Cu")
		(net "PSU_ALERT_N")
	)
	(segment
		(start 93.357446 -79.43088)
		(end 93.95206 -79.43088)
		(width 0.1524)
		(layer "B.Cu")
		(net "PSU_ALERT_N")
	)
	(segment
		(start 91.862148 -168.17721)
		(end 91.88323 -168.198292)
		(width 0.1524)
		(layer "B.Cu")
		(net "PSU_ALERT_N")
	)
	(segment
		(start 91.865958 -172.716444)
		(end 91.865958 -171.316396)
		(width 0.1524)
		(layer "B.Cu")
		(net "PSU_ALERT_N")
	)
	(segment
		(start 94.903544 -84.751672)
		(end 94.607888 -84.456016)
		(width 0.1524)
		(layer "B.Cu")
		(net "PSU_ALERT_N")
	)
	(segment
		(start 93.303598 -479.200972)
		(end 93.04147 -479.4631)
		(width 0.1524)
		(layer "B.Cu")
		(net "PSU_ALERT_N")
	)
	(segment
		(start 31.55696 -189.349634)
		(end 31.55696 -182.487316)
		(width 0.1524)
		(layer "B.Cu")
		(net "PSU_ALERT_N")
	)
	(segment
		(start 28.260548 -441.788804)
		(end 26.046684 -439.57494)
		(width 0.1524)
		(layer "B.Cu")
		(net "PSU_ALERT_N")
	)
	(segment
		(start 91.815412 -478.952306)
		(end 91.815412 -479.4631)
		(width 0.1524)
		(layer "B.Cu")
		(net "PSU_ALERT_N")
	)
	(segment
		(start 93.357446 -79.43088)
		(end 92.81033 -79.43088)
		(width 0.1524)
		(layer "B.Cu")
		(net "PSU_ALERT_N")
	)
	(segment
		(start 93.957902 -79.425038)
		(end 93.95206 -79.43088)
		(width 0.1524)
		(layer "B.Cu")
		(net "PSU_ALERT_N")
	)
	(segment
		(start 93.307916 -83.792314)
		(end 93.307916 -82.576924)
		(width 0.1524)
		(layer "B.Cu")
		(net "PSU_ALERT_N")
	)
	(segment
		(start 93.16593 -172.716444)
		(end 93.16593 -171.46143)
		(width 0.1524)
		(layer "B.Cu")
		(net "PSU_ALERT_N")
	)
	(segment
		(start 90.053668 -483.871524)
		(end 90.053668 -482.826314)
		(width 0.1524)
		(layer "B.Cu")
		(net "PSU_ALERT_N")
	)
	(segment
		(start 92.007944 -82.545682)
		(end 92.007944 -83.792314)
		(width 0.1524)
		(layer "B.Cu")
		(net "PSU_ALERT_N")
	)
	(segment
		(start 26.046684 -375.521982)
		(end 29.642054 -371.926612)
		(width 0.1524)
		(layer "B.Cu")
		(net "PSU_ALERT_N")
	)
	(segment
		(start 93.815916 -167.932608)
		(end 93.571314 -168.17721)
		(width 0.1524)
		(layer "B.Cu")
		(net "PSU_ALERT_N")
	)
	(segment
		(start 97.768918 -346.858336)
		(end 97.532444 -346.621862)
		(width 0.1524)
		(layer "B.Cu")
		(net "PSU_ALERT_N")
	)
	(segment
		(start 98.418904 -343.264998)
		(end 97.99701 -343.686892)
		(width 0.1524)
		(layer "B.Cu")
		(net "PSU_ALERT_N")
	)
	(segment
		(start 90.703654 -479.242882)
		(end 90.703654 -478.029524)
		(width 0.1524)
		(layer "B.Cu")
		(net "PSU_ALERT_N")
	)
	(segment
		(start 94.607888 -83.792314)
		(end 94.607888 -82.777838)
		(width 0.1524)
		(layer "B.Cu")
		(net "PSU_ALERT_N")
	)
	(segment
		(start 97.17024 -343.686892)
		(end 97.17024 -346.58427)
		(width 0.1524)
		(layer "B.Cu")
		(net "PSU_ALERT_N")
	)
	(segment
		(start 92.515944 -168.145714)
		(end 92.484448 -168.17721)
		(width 0.1524)
		(layer "B.Cu")
		(net "PSU_ALERT_N")
	)
	(segment
		(start 92.65793 -79.27848)
		(end 92.65793 -77.950314)
		(width 0.1524)
		(layer "B.Cu")
		(net "PSU_ALERT_N")
	)
	(segment
		(start 27.727402 -101.656896)
		(end 31.073344 -101.656896)
		(width 0.1524)
		(layer "B.Cu")
		(net "PSU_ALERT_N")
	)
	(segment
		(start 97.118932 -343.635584)
		(end 97.17024 -343.686892)
		(width 0.1524)
		(layer "B.Cu")
		(net "PSU_ALERT_N")
	)
	(segment
		(start 91.40698 -168.17721)
		(end 91.862148 -168.17721)
		(width 0.1524)
		(layer "B.Cu")
		(net "PSU_ALERT_N")
	)
	(segment
		(start 23.188676 -235.445554)
		(end 23.188676 -233.541824)
		(width 0.1524)
		(layer "B.Cu")
		(net "PSU_ALERT_N")
	)
	(segment
		(start 21.998432 -237.16361)
		(end 21.998432 -261.328662)
		(width 0.1524)
		(layer "B.Cu")
		(net "PSU_ALERT_N")
	)
	(segment
		(start 91.215972 -166.874444)
		(end 91.215972 -167.986202)
		(width 0.1524)
		(layer "B.Cu")
		(net "PSU_ALERT_N")
	)
	(segment
		(start 96.468946 -348.04477)
		(end 96.468946 -346.623386)
		(width 0.1524)
		(layer "B.Cu")
		(net "PSU_ALERT_N")
	)
	(segment
		(start 23.188676 -235.973366)
		(end 21.998432 -237.16361)
		(width 0.1524)
		(layer "B.Cu")
		(net "PSU_ALERT_N")
	)
	(segment
		(start 93.041724 -482.83495)
		(end 92.653612 -483.223062)
		(width 0.1524)
		(layer "B.Cu")
		(net "PSU_ALERT_N")
	)
	(segment
		(start 97.768918 -348.04477)
		(end 97.768918 -346.858336)
		(width 0.1524)
		(layer "B.Cu")
		(net "PSU_ALERT_N")
	)
	(segment
		(start 31.676086 -101.054154)
		(end 31.676086 -94.206314)
		(width 0.1524)
		(layer "B.Cu")
		(net "PSU_ALERT_N")
	)
	(segment
		(start 93.041724 -482.565456)
		(end 91.499944 -482.565456)
		(width 0.1524)
		(layer "B.Cu")
		(net "PSU_ALERT_N")
	)
	(segment
		(start 23.910798 -13.582142)
		(end 23.910798 -87.03437)
		(width 0.1524)
		(layer "B.Cu")
		(net "PSU_ALERT_N")
	)
	(segment
		(start 28.18257 -10.27049)
		(end 26.867866 -11.585194)
		(width 0.1524)
		(layer "B.Cu")
		(net "PSU_ALERT_N")
	)
	(segment
		(start 93.571314 -168.17721)
		(end 92.484448 -168.17721)
		(width 0.1524)
		(layer "B.Cu")
		(net "PSU_ALERT_N")
	)
	(segment
		(start 96.468946 -346.623386)
		(end 96.47047 -346.621862)
		(width 0.1524)
		(layer "B.Cu")
		(net "PSU_ALERT_N")
	)
	(segment
		(start 91.815412 -479.4631)
		(end 90.923872 -479.4631)
		(width 0.1524)
		(layer "B.Cu")
		(net "PSU_ALERT_N")
	)
	(segment
		(start 90.923872 -479.4631)
		(end 90.703654 -479.242882)
		(width 0.1524)
		(layer "B.Cu")
		(net "PSU_ALERT_N")
	)
	(segment
		(start 28.260548 -444.39078)
		(end 28.260548 -441.788804)
		(width 0.1524)
		(layer "B.Cu")
		(net "PSU_ALERT_N")
	)
	(segment
		(start 25.24379 -104.140508)
		(end 27.727402 -101.656896)
		(width 0.1524)
		(layer "B.Cu")
		(net "PSU_ALERT_N")
	)
	(segment
		(start 90.565986 -171.492418)
		(end 90.565986 -172.716444)
		(width 0.1524)
		(layer "B.Cu")
		(net "PSU_ALERT_N")
	)
	(segment
		(start 91.215972 -167.986202)
		(end 91.40698 -168.17721)
		(width 0.1524)
		(layer "B.Cu")
		(net "PSU_ALERT_N")
	)
	(segment
		(start 93.041724 -482.565456)
		(end 93.041724 -482.83495)
		(width 0.1524)
		(layer "B.Cu")
		(net "PSU_ALERT_N")
	)
	(segment
		(start 30.45968 -4.590034)
		(end 28.18257 -6.867144)
		(width 0.1524)
		(layer "B.Cu")
		(net "PSU_ALERT_N")
	)
	(segment
		(start 29.642054 -371.926612)
		(end 30.859984 -371.926612)
		(width 0.1524)
		(layer "B.Cu")
		(net "PSU_ALERT_N")
	)
	(segment
		(start 26.867866 -11.585194)
		(end 25.907746 -11.585194)
		(width 0.1524)
		(layer "B.Cu")
		(net "PSU_ALERT_N")
	)
	(segment
		(start 90.053668 -482.826314)
		(end 90.314526 -482.565456)
		(width 0.1524)
		(layer "B.Cu")
		(net "PSU_ALERT_N")
	)
	(segment
		(start 97.532444 -346.621862)
		(end 97.132648 -346.621862)
		(width 0.1524)
		(layer "B.Cu")
		(net "PSU_ALERT_N")
	)
	(segment
		(start 29.866336 -92.989908)
		(end 30.45968 -92.989908)
		(width 0.1524)
		(layer "B.Cu")
		(net "PSU_ALERT_N")
	)
	(segment
		(start 94.607888 -84.456016)
		(end 94.607888 -83.792314)
		(width 0.1524)
		(layer "B.Cu")
		(net "PSU_ALERT_N")
	)
	(segment
		(start 24.511254 -352.241612)
		(end 30.45968 -358.190038)
		(width 0.1524)
		(layer "B.Cu")
		(net "PSU_ALERT_N")
	)
	(segment
		(start 92.484448 -168.17721)
		(end 91.862148 -168.17721)
		(width 0.1524)
		(layer "B.Cu")
		(net "PSU_ALERT_N")
	)
	(segment
		(start 95.007176 -79.43088)
		(end 95.257874 -79.180182)
		(width 0.1524)
		(layer "B.Cu")
		(net "PSU_ALERT_N")
	)
	(segment
		(start 22.10308 -221.66326)
		(end 22.10308 -194.613784)
		(width 0.1524)
		(layer "B.Cu")
		(net "PSU_ALERT_N")
	)
	(segment
		(start 92.515944 -166.874444)
		(end 92.515944 -168.145714)
		(width 0.1524)
		(layer "B.Cu")
		(net "PSU_ALERT_N")
	)
	(segment
		(start 91.35364 -483.083616)
		(end 91.499944 -482.937312)
		(width 0.1524)
		(layer "B.Cu")
		(net "PSU_ALERT_N")
	)
	(segment
		(start 95.168974 -348.04477)
		(end 95.168974 -346.86748)
		(width 0.1524)
		(layer "B.Cu")
		(net "PSU_ALERT_N")
	)
	(segment
		(start 95.168974 -346.86748)
		(end 95.414592 -346.621862)
		(width 0.1524)
		(layer "B.Cu")
		(net "PSU_ALERT_N")
	)
	(segment
		(start 96.092772 -343.686892)
		(end 95.81896 -343.41308)
		(width 0.1524)
		(layer "B.Cu")
		(net "PSU_ALERT_N")
	)
	(segment
		(start 93.307916 -82.576924)
		(end 93.339158 -82.545682)
		(width 0.1524)
		(layer "B.Cu")
		(net "PSU_ALERT_N")
	)
	(segment
		(start 96.75241 -84.751672)
		(end 94.903544 -84.751672)
		(width 0.1524)
		(layer "B.Cu")
		(net "PSU_ALERT_N")
	)
	(segment
		(start 93.339158 -79.449168)
		(end 93.357446 -79.43088)
		(width 0.1524)
		(layer "B.Cu")
		(net "PSU_ALERT_N")
	)
	(segment
		(start 91.499944 -482.937312)
		(end 91.499944 -482.565456)
		(width 0.1524)
		(layer "B.Cu")
		(net "PSU_ALERT_N")
	)
	(segment
		(start 93.339158 -82.545682)
		(end 93.339158 -79.449168)
		(width 0.1524)
		(layer "B.Cu")
		(net "PSU_ALERT_N")
	)
	(segment
		(start 97.17024 -346.58427)
		(end 97.132648 -346.621862)
		(width 0.1524)
		(layer "B.Cu")
		(net "PSU_ALERT_N")
	)
	(segment
		(start 97.99701 -343.686892)
		(end 97.17024 -343.686892)
		(width 0.1524)
		(layer "B.Cu")
		(net "PSU_ALERT_N")
	)
	(segment
		(start 26.538682 -349.7072)
		(end 29.252672 -352.42119)
		(width 0.127)
		(layer "In2.Cu")
		(net "PSU_ALERT_N")
	)
	(segment
		(start 94.845378 -349.96755)
		(end 94.845378 -347.191076)
		(width 0.127)
		(layer "In2.Cu")
		(net "PSU_ALERT_N")
	)
	(segment
		(start 26.538682 -337.457796)
		(end 26.538682 -349.7072)
		(width 0.127)
		(layer "In2.Cu")
		(net "PSU_ALERT_N")
	)
	(segment
		(start 91.053666 -85.27796)
		(end 91.053666 -87.091774)
		(width 0.127)
		(layer "In2.Cu")
		(net "PSU_ALERT_N")
	)
	(segment
		(start 92.007944 -84.323682)
		(end 91.053666 -85.27796)
		(width 0.127)
		(layer "In2.Cu")
		(net "PSU_ALERT_N")
	)
	(segment
		(start 91.053666 -87.091774)
		(end 88.192864 -89.952576)
		(width 0.127)
		(layer "In2.Cu")
		(net "PSU_ALERT_N")
	)
	(segment
		(start 76.896976 -91.290648)
		(end 31.495746 -91.290648)
		(width 0.127)
		(layer "In2.Cu")
		(net "PSU_ALERT_N")
	)
	(segment
		(start 46.330108 -354.847906)
		(end 89.965022 -354.847906)
		(width 0.127)
		(layer "In2.Cu")
		(net "PSU_ALERT_N")
	)
	(segment
		(start 89.965022 -354.847906)
		(end 94.845378 -349.96755)
		(width 0.127)
		(layer "In2.Cu")
		(net "PSU_ALERT_N")
	)
	(segment
		(start 78.235048 -89.952576)
		(end 76.896976 -91.290648)
		(width 0.127)
		(layer "In2.Cu")
		(net "PSU_ALERT_N")
	)
	(segment
		(start 25.582626 -336.50174)
		(end 26.538682 -337.457796)
		(width 0.127)
		(layer "In2.Cu")
		(net "PSU_ALERT_N")
	)
	(segment
		(start 94.845378 -347.191076)
		(end 95.168974 -346.86748)
		(width 0.127)
		(layer "In2.Cu")
		(net "PSU_ALERT_N")
	)
	(segment
		(start 30.45968 -92.326714)
		(end 30.45968 -92.989908)
		(width 0.127)
		(layer "In2.Cu")
		(net "PSU_ALERT_N")
	)
	(segment
		(start 43.903392 -352.42119)
		(end 46.330108 -354.847906)
		(width 0.127)
		(layer "In2.Cu")
		(net "PSU_ALERT_N")
	)
	(segment
		(start 31.495746 -91.290648)
		(end 30.45968 -92.326714)
		(width 0.127)
		(layer "In2.Cu")
		(net "PSU_ALERT_N")
	)
	(segment
		(start 29.252672 -352.42119)
		(end 43.903392 -352.42119)
		(width 0.127)
		(layer "In2.Cu")
		(net "PSU_ALERT_N")
	)
	(segment
		(start 88.192864 -89.952576)
		(end 78.235048 -89.952576)
		(width 0.127)
		(layer "In2.Cu")
		(net "PSU_ALERT_N")
	)
	(segment
		(start 92.007944 -82.545682)
		(end 92.007944 -84.323682)
		(width 0.127)
		(layer "In2.Cu")
		(net "PSU_ALERT_N")
	)
	(segment
		(start 40.431466 -445.46647)
		(end 31.583122 -445.46647)
		(width 0.127)
		(layer "In5.Cu")
		(net "PSU_ALERT_N")
	)
	(segment
		(start 96.969326 -479.482912)
		(end 96.969326 -457.955142)
		(width 0.127)
		(layer "In5.Cu")
		(net "PSU_ALERT_N")
	)
	(segment
		(start 85.032088 -455.990198)
		(end 83.225894 -454.184004)
		(width 0.127)
		(layer "In5.Cu")
		(net "PSU_ALERT_N")
	)
	(segment
		(start 95.004382 -455.990198)
		(end 85.032088 -455.990198)
		(width 0.127)
		(layer "In5.Cu")
		(net "PSU_ALERT_N")
	)
	(segment
		(start 31.583122 -445.46647)
		(end 30.45968 -446.589912)
		(width 0.127)
		(layer "In5.Cu")
		(net "PSU_ALERT_N")
	)
	(segment
		(start 96.969326 -457.955142)
		(end 95.004382 -455.990198)
		(width 0.127)
		(layer "In5.Cu")
		(net "PSU_ALERT_N")
	)
	(segment
		(start 80.588612 -446.39357)
		(end 41.358566 -446.39357)
		(width 0.127)
		(layer "In5.Cu")
		(net "PSU_ALERT_N")
	)
	(segment
		(start 84.478622 -179.611782)
		(end 31.379668 -179.611782)
		(width 0.127)
		(layer "In5.Cu")
		(net "PSU_ALERT_N")
	)
	(segment
		(start 41.358566 -446.39357)
		(end 40.431466 -445.46647)
		(width 0.127)
		(layer "In5.Cu")
		(net "PSU_ALERT_N")
	)
	(segment
		(start 93.886782 -482.565456)
		(end 96.969326 -479.482912)
		(width 0.127)
		(layer "In5.Cu")
		(net "PSU_ALERT_N")
	)
	(segment
		(start 93.041724 -482.565456)
		(end 93.886782 -482.565456)
		(width 0.127)
		(layer "In5.Cu")
		(net "PSU_ALERT_N")
	)
	(segment
		(start 31.379668 -179.611782)
		(end 30.45968 -180.53177)
		(width 0.127)
		(layer "In5.Cu")
		(net "PSU_ALERT_N")
	)
	(segment
		(start 83.225894 -449.030852)
		(end 80.588612 -446.39357)
		(width 0.127)
		(layer "In5.Cu")
		(net "PSU_ALERT_N")
	)
	(segment
		(start 90.565986 -171.492418)
		(end 90.565986 -173.524418)
		(width 0.127)
		(layer "In5.Cu")
		(net "PSU_ALERT_N")
	)
	(segment
		(start 30.45968 -180.53177)
		(end 30.45968 -181.390036)
		(width 0.127)
		(layer "In5.Cu")
		(net "PSU_ALERT_N")
	)
	(segment
		(start 90.565986 -173.524418)
		(end 84.478622 -179.611782)
		(width 0.127)
		(layer "In5.Cu")
		(net "PSU_ALERT_N")
	)
	(segment
		(start 83.225894 -454.184004)
		(end 83.225894 -449.030852)
		(width 0.127)
		(layer "In5.Cu")
		(net "PSU_ALERT_N")
	)
	(segment
		(start 29.109162 -100.609908)
		(end 29.082492 -100.636578)
		(width 0.1524)
		(layer "F.Cu")
		(net "PSU2_PS_ON_N")
	)
	(segment
		(start 30.45968 -100.609908)
		(end 29.109162 -100.609908)
		(width 0.1524)
		(layer "F.Cu")
		(net "PSU2_PS_ON_N")
	)
	(segment
		(start 26.652728 -10.617962)
		(end 25.76322 -10.617962)
		(width 0.1524)
		(layer "F.Cu")
		(net "PSU2_PS_ON_N")
	)
	(via
		(at 29.082492 -100.636578)
		(size 0.508)
		(drill 0.254)
		(layers "F.Cu" "B.Cu")
		(net "PSU2_PS_ON_N")
	)
	(via
		(at 17.99971 -228.0285)
		(size 0.508)
		(drill 0.254)
		(layers "F.Cu" "B.Cu")
		(net "PSU2_PS_ON_N")
	)
	(via
		(at 25.76322 -10.617962)
		(size 0.508)
		(drill 0.254)
		(layers "F.Cu" "B.Cu")
		(net "PSU2_PS_ON_N")
	)
	(segment
		(start 29.082492 -94.170246)
		(end 23.531576 -88.61933)
		(width 0.1524)
		(layer "B.Cu")
		(net "PSU2_PS_ON_N")
	)
	(segment
		(start 23.531576 -88.61933)
		(end 23.531576 -12.849606)
		(width 0.1524)
		(layer "B.Cu")
		(net "PSU2_PS_ON_N")
	)
	(segment
		(start 23.531576 -12.849606)
		(end 25.76322 -10.617962)
		(width 0.1524)
		(layer "B.Cu")
		(net "PSU2_PS_ON_N")
	)
	(segment
		(start 29.082492 -100.636578)
		(end 29.082492 -94.170246)
		(width 0.1524)
		(layer "B.Cu")
		(net "PSU2_PS_ON_N")
	)
	(segment
		(start 23.783036 -221.075758)
		(end 19.089624 -225.76917)
		(width 0.127)
		(layer "In2.Cu")
		(net "PSU2_PS_ON_N")
	)
	(segment
		(start 19.089624 -225.76917)
		(end 19.089624 -226.938586)
		(width 0.127)
		(layer "In2.Cu")
		(net "PSU2_PS_ON_N")
	)
	(segment
		(start 29.082492 -174.368714)
		(end 20.036028 -183.415178)
		(width 0.127)
		(layer "In2.Cu")
		(net "PSU2_PS_ON_N")
	)
	(segment
		(start 20.036028 -197.21449)
		(end 23.783036 -200.961498)
		(width 0.127)
		(layer "In2.Cu")
		(net "PSU2_PS_ON_N")
	)
	(segment
		(start 23.783036 -200.961498)
		(end 23.783036 -221.075758)
		(width 0.127)
		(layer "In2.Cu")
		(net "PSU2_PS_ON_N")
	)
	(segment
		(start 20.036028 -183.415178)
		(end 20.036028 -197.21449)
		(width 0.127)
		(layer "In2.Cu")
		(net "PSU2_PS_ON_N")
	)
	(segment
		(start 29.082492 -100.636578)
		(end 29.082492 -174.368714)
		(width 0.127)
		(layer "In2.Cu")
		(net "PSU2_PS_ON_N")
	)
	(segment
		(start 19.089624 -226.938586)
		(end 17.99971 -228.0285)
		(width 0.127)
		(layer "In2.Cu")
		(net "PSU2_PS_ON_N")
	)
	(via
		(at 83.460082 -237.048548)
		(size 0.508)
		(drill 0.254)
		(layers "F.Cu" "B.Cu")
		(net "T6_BLAD1_EN")
	)
	(segment
		(start 6.946138 -271.856708)
		(end 7.963154 -270.839692)
		(width 0.127)
		(layer "In2.Cu")
		(net "T6_BLAD1_EN")
	)
	(segment
		(start 84.257134 -241.449606)
		(end 84.257134 -240.62055)
		(width 0.127)
		(layer "In2.Cu")
		(net "T6_BLAD1_EN")
	)
	(segment
		(start 3.646678 -271.856708)
		(end 6.946138 -271.856708)
		(width 0.127)
		(layer "In2.Cu")
		(net "T6_BLAD1_EN")
	)
	(segment
		(start 83.460082 -242.246658)
		(end 84.257134 -241.449606)
		(width 0.127)
		(layer "In2.Cu")
		(net "T6_BLAD1_EN")
	)
	(segment
		(start 83.460082 -239.823498)
		(end 83.460082 -237.048548)
		(width 0.127)
		(layer "In2.Cu")
		(net "T6_BLAD1_EN")
	)
	(segment
		(start 83.460082 -237.048548)
		(end 83.460082 -235.784898)
		(width 0.127)
		(layer "In2.Cu")
		(net "T6_BLAD1_EN")
	)
	(segment
		(start 84.257134 -240.62055)
		(end 83.460082 -239.823498)
		(width 0.127)
		(layer "In2.Cu")
		(net "T6_BLAD1_EN")
	)
	(segment
		(start 83.460082 -245.37289)
		(end 83.460082 -242.246658)
		(width 0.127)
		(layer "In2.Cu")
		(net "T6_BLAD1_EN")
	)
	(segment
		(start 3.058414 -274.5613)
		(end 3.058414 -272.444972)
		(width 0.127)
		(layer "In2.Cu")
		(net "T6_BLAD1_EN")
	)
	(segment
		(start 64.105028 -264.727944)
		(end 83.460082 -245.37289)
		(width 0.127)
		(layer "In2.Cu")
		(net "T6_BLAD1_EN")
	)
	(segment
		(start 7.963154 -270.839692)
		(end 12.019534 -270.839692)
		(width 0.127)
		(layer "In2.Cu")
		(net "T6_BLAD1_EN")
	)
	(segment
		(start 12.019534 -270.839692)
		(end 18.131282 -264.727944)
		(width 0.127)
		(layer "In2.Cu")
		(net "T6_BLAD1_EN")
	)
	(segment
		(start 3.058414 -272.444972)
		(end 3.646678 -271.856708)
		(width 0.127)
		(layer "In2.Cu")
		(net "T6_BLAD1_EN")
	)
	(segment
		(start 18.131282 -264.727944)
		(end 64.105028 -264.727944)
		(width 0.127)
		(layer "In2.Cu")
		(net "T6_BLAD1_EN")
	)
	(segment
		(start 83.460082 -235.784898)
		(end 88.17991 -231.06507)
		(width 0.127)
		(layer "In2.Cu")
		(net "T6_BLAD1_EN")
	)
	(segment
		(start 1.949958 -275.669756)
		(end 3.058414 -274.5613)
		(width 0.127)
		(layer "In2.Cu")
		(net "T6_BLAD1_EN")
	)
	(via
		(at 87.288624 -237.16615)
		(size 0.508)
		(drill 0.254)
		(layers "F.Cu" "B.Cu")
		(net "T6_BLAD2_RXD")
	)
	(segment
		(start 4.089654 -260.670548)
		(end 5.193538 -259.566664)
		(width 0.127)
		(layer "In5.Cu")
		(net "T6_BLAD2_RXD")
	)
	(segment
		(start 85.323934 -239.13084)
		(end 87.288624 -237.16615)
		(width 0.127)
		(layer "In5.Cu")
		(net "T6_BLAD2_RXD")
	)
	(segment
		(start 5.193538 -257.716782)
		(end 5.99313 -256.91719)
		(width 0.127)
		(layer "In5.Cu")
		(net "T6_BLAD2_RXD")
	)
	(segment
		(start 87.288624 -237.16615)
		(end 91.98991 -232.464864)
		(width 0.127)
		(layer "In5.Cu")
		(net "T6_BLAD2_RXD")
	)
	(segment
		(start 91.98991 -232.464864)
		(end 91.98991 -229.79507)
		(width 0.127)
		(layer "In5.Cu")
		(net "T6_BLAD2_RXD")
	)
	(segment
		(start 62.425834 -264.417302)
		(end 85.323934 -241.518694)
		(width 0.127)
		(layer "In5.Cu")
		(net "T6_BLAD2_RXD")
	)
	(segment
		(start 85.323934 -241.518694)
		(end 85.323934 -239.13084)
		(width 0.127)
		(layer "In5.Cu")
		(net "T6_BLAD2_RXD")
	)
	(segment
		(start 5.99313 -256.91719)
		(end 6.934708 -256.91719)
		(width 0.127)
		(layer "In5.Cu")
		(net "T6_BLAD2_RXD")
	)
	(segment
		(start 5.193538 -259.566664)
		(end 5.193538 -257.716782)
		(width 0.127)
		(layer "In5.Cu")
		(net "T6_BLAD2_RXD")
	)
	(segment
		(start 1.948942 -260.670548)
		(end 4.089654 -260.670548)
		(width 0.127)
		(layer "In5.Cu")
		(net "T6_BLAD2_RXD")
	)
	(segment
		(start 7.901686 -255.950212)
		(end 9.123934 -255.950212)
		(width 0.127)
		(layer "In5.Cu")
		(net "T6_BLAD2_RXD")
	)
	(segment
		(start 6.934708 -256.91719)
		(end 7.901686 -255.950212)
		(width 0.127)
		(layer "In5.Cu")
		(net "T6_BLAD2_RXD")
	)
	(segment
		(start 9.123934 -255.950212)
		(end 17.591024 -264.417302)
		(width 0.127)
		(layer "In5.Cu")
		(net "T6_BLAD2_RXD")
	)
	(segment
		(start 17.591024 -264.417302)
		(end 62.425834 -264.417302)
		(width 0.127)
		(layer "In5.Cu")
		(net "T6_BLAD2_RXD")
	)
	(via
		(at 85.38464 -238.064548)
		(size 0.508)
		(drill 0.254)
		(layers "F.Cu" "B.Cu")
		(net "T6_BLAD2_TXD")
	)
	(segment
		(start 5.843778 -256.556764)
		(end 4.833112 -257.56743)
		(width 0.127)
		(layer "In5.Cu")
		(net "T6_BLAD2_TXD")
	)
	(segment
		(start 84.9757 -238.473488)
		(end 84.9757 -241.399568)
		(width 0.127)
		(layer "In5.Cu")
		(net "T6_BLAD2_TXD")
	)
	(segment
		(start 7.75589 -255.58623)
		(end 6.785356 -256.556764)
		(width 0.127)
		(layer "In5.Cu")
		(net "T6_BLAD2_TXD")
	)
	(segment
		(start 17.742408 -264.052304)
		(end 9.276334 -255.58623)
		(width 0.127)
		(layer "In5.Cu")
		(net "T6_BLAD2_TXD")
	)
	(segment
		(start 84.9757 -241.399568)
		(end 62.322964 -264.052304)
		(width 0.127)
		(layer "In5.Cu")
		(net "T6_BLAD2_TXD")
	)
	(segment
		(start 6.785356 -256.556764)
		(end 5.843778 -256.556764)
		(width 0.127)
		(layer "In5.Cu")
		(net "T6_BLAD2_TXD")
	)
	(segment
		(start 4.833112 -258.786376)
		(end 3.948938 -259.67055)
		(width 0.127)
		(layer "In5.Cu")
		(net "T6_BLAD2_TXD")
	)
	(segment
		(start 9.276334 -255.58623)
		(end 7.75589 -255.58623)
		(width 0.127)
		(layer "In5.Cu")
		(net "T6_BLAD2_TXD")
	)
	(segment
		(start 90.71991 -232.729278)
		(end 85.38464 -238.064548)
		(width 0.127)
		(layer "In5.Cu")
		(net "T6_BLAD2_TXD")
	)
	(segment
		(start 85.38464 -238.064548)
		(end 84.9757 -238.473488)
		(width 0.127)
		(layer "In5.Cu")
		(net "T6_BLAD2_TXD")
	)
	(segment
		(start 4.833112 -257.56743)
		(end 4.833112 -258.786376)
		(width 0.127)
		(layer "In5.Cu")
		(net "T6_BLAD2_TXD")
	)
	(segment
		(start 90.71991 -231.06507)
		(end 90.71991 -232.729278)
		(width 0.127)
		(layer "In5.Cu")
		(net "T6_BLAD2_TXD")
	)
	(segment
		(start 62.322964 -264.052304)
		(end 17.742408 -264.052304)
		(width 0.127)
		(layer "In5.Cu")
		(net "T6_BLAD2_TXD")
	)
	(segment
		(start 22.87397 -367.82756)
		(end 24.189944 -369.143534)
		(width 0.1524)
		(layer "F.Cu")
		(net "PSU_CSAHRE")
	)
	(segment
		(start 25.78608 -190.641986)
		(end 26.692098 -191.548004)
		(width 0.1524)
		(layer "F.Cu")
		(net "PSU_CSAHRE")
	)
	(segment
		(start 24.953214 -332.824328)
		(end 25.582626 -333.45374)
		(width 0.1524)
		(layer "F.Cu")
		(net "PSU_CSAHRE")
	)
	(segment
		(start 26.767282 -455.79284)
		(end 26.332434 -456.227688)
		(width 0.1524)
		(layer "F.Cu")
		(net "PSU_CSAHRE")
	)
	(segment
		(start 27.277314 -455.79284)
		(end 26.767282 -455.79284)
		(width 0.1524)
		(layer "F.Cu")
		(net "PSU_CSAHRE")
	)
	(segment
		(start 24.953214 -310.49976)
		(end 24.953214 -332.824328)
		(width 0.1524)
		(layer "F.Cu")
		(net "PSU_CSAHRE")
	)
	(segment
		(start 24.189944 -369.143534)
		(end 24.238204 -369.095274)
		(width 0.1524)
		(layer "F.Cu")
		(net "PSU_CSAHRE")
	)
	(segment
		(start 24.238204 -369.095274)
		(end 25.404826 -369.095274)
		(width 0.1524)
		(layer "F.Cu")
		(net "PSU_CSAHRE")
	)
	(segment
		(start 27.123644 -289.710622)
		(end 27.123644 -308.32933)
		(width 0.1524)
		(layer "F.Cu")
		(net "PSU_CSAHRE")
	)
	(segment
		(start 26.092658 -15.41018)
		(end 26.5049 -15.822422)
		(width 0.4572)
		(layer "F.Cu")
		(net "PSU_CSAHRE")
	)
	(segment
		(start 25.582626 -351.870772)
		(end 22.87397 -354.579428)
		(width 0.1524)
		(layer "F.Cu")
		(net "PSU_CSAHRE")
	)
	(segment
		(start 27.123644 -308.32933)
		(end 24.953214 -310.49976)
		(width 0.1524)
		(layer "F.Cu")
		(net "PSU_CSAHRE")
	)
	(segment
		(start 26.89352 -280.04389)
		(end 26.89352 -280.126694)
		(width 0.1524)
		(layer "F.Cu")
		(net "PSU_CSAHRE")
	)
	(segment
		(start 27.629866 -280.86304)
		(end 25.008586 -283.48432)
		(width 0.1524)
		(layer "F.Cu")
		(net "PSU_CSAHRE")
	)
	(segment
		(start 25.008586 -283.48432)
		(end 25.008586 -287.595564)
		(width 0.1524)
		(layer "F.Cu")
		(net "PSU_CSAHRE")
	)
	(segment
		(start 26.89352 -280.126694)
		(end 27.629866 -280.86304)
		(width 0.1524)
		(layer "F.Cu")
		(net "PSU_CSAHRE")
	)
	(segment
		(start 22.87397 -354.579428)
		(end 22.87397 -367.82756)
		(width 0.1524)
		(layer "F.Cu")
		(net "PSU_CSAHRE")
	)
	(segment
		(start 26.332434 -456.227688)
		(end 26.332434 -456.748896)
		(width 0.1524)
		(layer "F.Cu")
		(net "PSU_CSAHRE")
	)
	(segment
		(start 26.092658 -14.7955)
		(end 26.092658 -15.41018)
		(width 0.4572)
		(layer "F.Cu")
		(net "PSU_CSAHRE")
	)
	(segment
		(start 25.601676 -101.689408)
		(end 25.601676 -102.143052)
		(width 0.1524)
		(layer "F.Cu")
		(net "PSU_CSAHRE")
	)
	(segment
		(start 25.78608 -190.368174)
		(end 25.78608 -190.641986)
		(width 0.1524)
		(layer "F.Cu")
		(net "PSU_CSAHRE")
	)
	(segment
		(start 25.601676 -102.143052)
		(end 26.784554 -103.32593)
		(width 0.1524)
		(layer "F.Cu")
		(net "PSU_CSAHRE")
	)
	(segment
		(start 25.008586 -287.595564)
		(end 27.123644 -289.710622)
		(width 0.1524)
		(layer "F.Cu")
		(net "PSU_CSAHRE")
	)
	(segment
		(start 25.582626 -341.90051)
		(end 25.582626 -351.870772)
		(width 0.1524)
		(layer "F.Cu")
		(net "PSU_CSAHRE")
	)
	(via
		(at 27.277314 -455.79284)
		(size 0.508)
		(drill 0.254)
		(layers "F.Cu" "B.Cu")
		(net "PSU_CSAHRE")
	)
	(via
		(at 26.784554 -103.32593)
		(size 0.508)
		(drill 0.254)
		(layers "F.Cu" "B.Cu")
		(net "PSU_CSAHRE")
	)
	(via
		(at 24.189944 -369.143534)
		(size 0.508)
		(drill 0.254)
		(layers "F.Cu" "B.Cu")
		(net "PSU_CSAHRE")
	)
	(via
		(at 25.582626 -333.45374)
		(size 0.508)
		(drill 0.254)
		(layers "F.Cu" "B.Cu")
		(net "PSU_CSAHRE")
	)
	(via
		(at 25.582626 -341.90051)
		(size 0.508)
		(drill 0.254)
		(layers "F.Cu" "B.Cu")
		(net "PSU_CSAHRE")
	)
	(via
		(at 26.692098 -191.548004)
		(size 0.508)
		(drill 0.254)
		(layers "F.Cu" "B.Cu")
		(net "PSU_CSAHRE")
	)
	(via
		(at 27.629866 -280.86304)
		(size 0.508)
		(drill 0.254)
		(layers "F.Cu" "B.Cu")
		(net "PSU_CSAHRE")
	)
	(via
		(at 26.5049 -15.822422)
		(size 0.508)
		(drill 0.254)
		(layers "F.Cu" "B.Cu")
		(net "PSU_CSAHRE")
	)
	(segment
		(start 31.110174 -102.122986)
		(end 27.987752 -102.122986)
		(width 0.1524)
		(layer "B.Cu")
		(net "PSU_CSAHRE")
	)
	(segment
		(start 31.246064 -190.523368)
		(end 31.999174 -189.770258)
		(width 0.1524)
		(layer "B.Cu")
		(net "PSU_CSAHRE")
	)
	(segment
		(start 26.692098 -191.548004)
		(end 27.62377 -191.548004)
		(width 0.1524)
		(layer "B.Cu")
		(net "PSU_CSAHRE")
	)
	(segment
		(start 24.398478 -17.928844)
		(end 24.398478 -84.977224)
		(width 0.1524)
		(layer "B.Cu")
		(net "PSU_CSAHRE")
	)
	(segment
		(start 23.984204 -173.261274)
		(end 23.984204 -111.332772)
		(width 0.1524)
		(layer "B.Cu")
		(net "PSU_CSAHRE")
	)
	(segment
		(start 27.851862 -455.218292)
		(end 27.851862 -442.091318)
		(width 0.1524)
		(layer "B.Cu")
		(net "PSU_CSAHRE")
	)
	(segment
		(start 23.773892 -236.469682)
		(end 22.505924 -237.73765)
		(width 0.1524)
		(layer "B.Cu")
		(net "PSU_CSAHRE")
	)
	(segment
		(start 27.851862 -442.091318)
		(end 25.691084 -439.93054)
		(width 0.1524)
		(layer "B.Cu")
		(net "PSU_CSAHRE")
	)
	(segment
		(start 22.505924 -237.73765)
		(end 22.505924 -258.182872)
		(width 0.1524)
		(layer "B.Cu")
		(net "PSU_CSAHRE")
	)
	(segment
		(start 32.489902 -268.16685)
		(end 32.489902 -277.247604)
		(width 0.1524)
		(layer "B.Cu")
		(net "PSU_CSAHRE")
	)
	(segment
		(start 30.987746 -278.74976)
		(end 29.239464 -278.74976)
		(width 0.1524)
		(layer "B.Cu")
		(net "PSU_CSAHRE")
	)
	(segment
		(start 22.058122 -222.387414)
		(end 22.058122 -231.31399)
		(width 0.1524)
		(layer "B.Cu")
		(net "PSU_CSAHRE")
	)
	(segment
		(start 25.691084 -370.644674)
		(end 24.189944 -369.143534)
		(width 0.1524)
		(layer "B.Cu")
		(net "PSU_CSAHRE")
	)
	(segment
		(start 27.10815 -103.002588)
		(end 27.107896 -103.002588)
		(width 0.1524)
		(layer "B.Cu")
		(net "PSU_CSAHRE")
	)
	(segment
		(start 27.629866 -280.359358)
		(end 27.629866 -280.86304)
		(width 0.1524)
		(layer "B.Cu")
		(net "PSU_CSAHRE")
	)
	(segment
		(start 31.999174 -181.276244)
		(end 23.984204 -173.261274)
		(width 0.1524)
		(layer "B.Cu")
		(net "PSU_CSAHRE")
	)
	(segment
		(start 27.62377 -191.548004)
		(end 28.648406 -190.523368)
		(width 0.1524)
		(layer "B.Cu")
		(net "PSU_CSAHRE")
	)
	(segment
		(start 32.253682 -92.832428)
		(end 32.253682 -100.979478)
		(width 0.1524)
		(layer "B.Cu")
		(net "PSU_CSAHRE")
	)
	(segment
		(start 23.984204 -111.332772)
		(end 26.784554 -108.532422)
		(width 0.1524)
		(layer "B.Cu")
		(net "PSU_CSAHRE")
	)
	(segment
		(start 29.239464 -278.74976)
		(end 27.629866 -280.359358)
		(width 0.1524)
		(layer "B.Cu")
		(net "PSU_CSAHRE")
	)
	(segment
		(start 25.691084 -439.93054)
		(end 25.691084 -370.644674)
		(width 0.1524)
		(layer "B.Cu")
		(net "PSU_CSAHRE")
	)
	(segment
		(start 32.489902 -277.247604)
		(end 30.987746 -278.74976)
		(width 0.1524)
		(layer "B.Cu")
		(net "PSU_CSAHRE")
	)
	(segment
		(start 27.987752 -102.122986)
		(end 27.10815 -103.002588)
		(width 0.1524)
		(layer "B.Cu")
		(net "PSU_CSAHRE")
	)
	(segment
		(start 27.107896 -103.002588)
		(end 26.784554 -103.32593)
		(width 0.1524)
		(layer "B.Cu")
		(net "PSU_CSAHRE")
	)
	(segment
		(start 23.773892 -233.02976)
		(end 23.773892 -236.469682)
		(width 0.1524)
		(layer "B.Cu")
		(net "PSU_CSAHRE")
	)
	(segment
		(start 32.253682 -100.979478)
		(end 31.110174 -102.122986)
		(width 0.1524)
		(layer "B.Cu")
		(net "PSU_CSAHRE")
	)
	(segment
		(start 22.058122 -231.31399)
		(end 23.773892 -233.02976)
		(width 0.1524)
		(layer "B.Cu")
		(net "PSU_CSAHRE")
	)
	(segment
		(start 26.784554 -108.532422)
		(end 26.784554 -103.32593)
		(width 0.1524)
		(layer "B.Cu")
		(net "PSU_CSAHRE")
	)
	(segment
		(start 26.692098 -191.548004)
		(end 22.45868 -195.781422)
		(width 0.1524)
		(layer "B.Cu")
		(net "PSU_CSAHRE")
	)
	(segment
		(start 24.398478 -84.977224)
		(end 32.253682 -92.832428)
		(width 0.1524)
		(layer "B.Cu")
		(net "PSU_CSAHRE")
	)
	(segment
		(start 27.277314 -455.79284)
		(end 27.851862 -455.218292)
		(width 0.1524)
		(layer "B.Cu")
		(net "PSU_CSAHRE")
	)
	(segment
		(start 22.505924 -258.182872)
		(end 32.489902 -268.16685)
		(width 0.1524)
		(layer "B.Cu")
		(net "PSU_CSAHRE")
	)
	(segment
		(start 26.5049 -15.822422)
		(end 24.398478 -17.928844)
		(width 0.1524)
		(layer "B.Cu")
		(net "PSU_CSAHRE")
	)
	(segment
		(start 22.45868 -221.986856)
		(end 22.058122 -222.387414)
		(width 0.1524)
		(layer "B.Cu")
		(net "PSU_CSAHRE")
	)
	(segment
		(start 28.648406 -190.523368)
		(end 31.246064 -190.523368)
		(width 0.1524)
		(layer "B.Cu")
		(net "PSU_CSAHRE")
	)
	(segment
		(start 31.999174 -189.770258)
		(end 31.999174 -181.276244)
		(width 0.1524)
		(layer "B.Cu")
		(net "PSU_CSAHRE")
	)
	(segment
		(start 22.45868 -195.781422)
		(end 22.45868 -221.986856)
		(width 0.1524)
		(layer "B.Cu")
		(net "PSU_CSAHRE")
	)
	(segment
		(start 25.08377 -341.401654)
		(end 25.08377 -333.952596)
		(width 0.127)
		(layer "In2.Cu")
		(net "PSU_CSAHRE")
	)
	(segment
		(start 25.582626 -341.90051)
		(end 25.08377 -341.401654)
		(width 0.127)
		(layer "In2.Cu")
		(net "PSU_CSAHRE")
	)
	(segment
		(start 25.08377 -333.952596)
		(end 25.582626 -333.45374)
		(width 0.127)
		(layer "In2.Cu")
		(net "PSU_CSAHRE")
	)
	(via
		(at 82.968084 -238.706152)
		(size 0.508)
		(drill 0.254)
		(layers "F.Cu" "B.Cu")
		(net "T6_BLAD3_EN")
	)
	(segment
		(start 2.650998 -272.96872)
		(end 1.949958 -273.66976)
		(width 0.127)
		(layer "In2.Cu")
		(net "T6_BLAD3_EN")
	)
	(segment
		(start 87.313008 -230.747824)
		(end 87.313008 -231.2924)
		(width 0.127)
		(layer "In2.Cu")
		(net "T6_BLAD3_EN")
	)
	(segment
		(start 88.17991 -228.52507)
		(end 88.17102 -228.53396)
		(width 0.127)
		(layer "In2.Cu")
		(net "T6_BLAD3_EN")
	)
	(segment
		(start 88.17102 -229.889812)
		(end 87.313008 -230.747824)
		(width 0.127)
		(layer "In2.Cu")
		(net "T6_BLAD3_EN")
	)
	(segment
		(start 3.485642 -271.468342)
		(end 2.650998 -272.302986)
		(width 0.127)
		(layer "In2.Cu")
		(net "T6_BLAD3_EN")
	)
	(segment
		(start 82.968084 -235.637324)
		(end 82.968084 -238.706152)
		(width 0.127)
		(layer "In2.Cu")
		(net "T6_BLAD3_EN")
	)
	(segment
		(start 11.940794 -270.451326)
		(end 7.802118 -270.451326)
		(width 0.127)
		(layer "In2.Cu")
		(net "T6_BLAD3_EN")
	)
	(segment
		(start 82.968084 -245.395242)
		(end 63.965582 -264.397744)
		(width 0.127)
		(layer "In2.Cu")
		(net "T6_BLAD3_EN")
	)
	(segment
		(start 6.785102 -271.468342)
		(end 3.485642 -271.468342)
		(width 0.127)
		(layer "In2.Cu")
		(net "T6_BLAD3_EN")
	)
	(segment
		(start 7.802118 -270.451326)
		(end 6.785102 -271.468342)
		(width 0.127)
		(layer "In2.Cu")
		(net "T6_BLAD3_EN")
	)
	(segment
		(start 82.968084 -238.706152)
		(end 82.968084 -245.395242)
		(width 0.127)
		(layer "In2.Cu")
		(net "T6_BLAD3_EN")
	)
	(segment
		(start 2.650998 -272.302986)
		(end 2.650998 -272.96872)
		(width 0.127)
		(layer "In2.Cu")
		(net "T6_BLAD3_EN")
	)
	(segment
		(start 88.17102 -228.53396)
		(end 88.17102 -229.889812)
		(width 0.127)
		(layer "In2.Cu")
		(net "T6_BLAD3_EN")
	)
	(segment
		(start 17.994376 -264.397744)
		(end 11.940794 -270.451326)
		(width 0.127)
		(layer "In2.Cu")
		(net "T6_BLAD3_EN")
	)
	(segment
		(start 87.313008 -231.2924)
		(end 82.968084 -235.637324)
		(width 0.127)
		(layer "In2.Cu")
		(net "T6_BLAD3_EN")
	)
	(segment
		(start 63.965582 -264.397744)
		(end 17.994376 -264.397744)
		(width 0.127)
		(layer "In2.Cu")
		(net "T6_BLAD3_EN")
	)
	(via
		(at 82.262472 -236.214412)
		(size 0.508)
		(drill 0.254)
		(layers "F.Cu" "B.Cu")
		(net "T6_BLAD4_RXD")
	)
	(segment
		(start 82.807556 -242.16614)
		(end 64.095376 -260.87832)
		(width 0.127)
		(layer "In5.Cu")
		(net "T6_BLAD4_RXD")
	)
	(segment
		(start 5.27304 -254.346456)
		(end 3.948938 -255.670558)
		(width 0.127)
		(layer "In5.Cu")
		(net "T6_BLAD4_RXD")
	)
	(segment
		(start 64.095376 -260.87832)
		(end 48.518064 -260.87832)
		(width 0.127)
		(layer "In5.Cu")
		(net "T6_BLAD4_RXD")
	)
	(segment
		(start 82.807556 -239.98936)
		(end 82.807556 -242.16614)
		(width 0.127)
		(layer "In5.Cu")
		(net "T6_BLAD4_RXD")
	)
	(segment
		(start 5.76453 -252.880114)
		(end 5.27304 -253.371604)
		(width 0.127)
		(layer "In5.Cu")
		(net "T6_BLAD4_RXD")
	)
	(segment
		(start 16.862552 -261.550658)
		(end 10.641076 -255.329182)
		(width 0.127)
		(layer "In5.Cu")
		(net "T6_BLAD4_RXD")
	)
	(segment
		(start 82.262472 -239.444276)
		(end 82.807556 -239.98936)
		(width 0.127)
		(layer "In5.Cu")
		(net "T6_BLAD4_RXD")
	)
	(segment
		(start 10.641076 -255.329182)
		(end 10.641076 -253.550928)
		(width 0.127)
		(layer "In5.Cu")
		(net "T6_BLAD4_RXD")
	)
	(segment
		(start 83.53298 -229.238048)
		(end 86.536784 -226.234244)
		(width 0.127)
		(layer "In5.Cu")
		(net "T6_BLAD4_RXD")
	)
	(segment
		(start 90.969084 -226.234244)
		(end 91.98991 -227.25507)
		(width 0.127)
		(layer "In5.Cu")
		(net "T6_BLAD4_RXD")
	)
	(segment
		(start 82.262472 -236.214412)
		(end 82.262472 -239.444276)
		(width 0.127)
		(layer "In5.Cu")
		(net "T6_BLAD4_RXD")
	)
	(segment
		(start 86.536784 -226.234244)
		(end 90.969084 -226.234244)
		(width 0.127)
		(layer "In5.Cu")
		(net "T6_BLAD4_RXD")
	)
	(segment
		(start 47.845726 -261.550658)
		(end 16.862552 -261.550658)
		(width 0.127)
		(layer "In5.Cu")
		(net "T6_BLAD4_RXD")
	)
	(segment
		(start 10.641076 -253.550928)
		(end 8.893048 -251.8029)
		(width 0.127)
		(layer "In5.Cu")
		(net "T6_BLAD4_RXD")
	)
	(segment
		(start 6.967982 -252.880114)
		(end 5.76453 -252.880114)
		(width 0.127)
		(layer "In5.Cu")
		(net "T6_BLAD4_RXD")
	)
	(segment
		(start 8.045196 -251.8029)
		(end 6.967982 -252.880114)
		(width 0.127)
		(layer "In5.Cu")
		(net "T6_BLAD4_RXD")
	)
	(segment
		(start 82.262472 -235.645198)
		(end 83.53298 -234.37469)
		(width 0.127)
		(layer "In5.Cu")
		(net "T6_BLAD4_RXD")
	)
	(segment
		(start 48.518064 -260.87832)
		(end 47.845726 -261.550658)
		(width 0.127)
		(layer "In5.Cu")
		(net "T6_BLAD4_RXD")
	)
	(segment
		(start 82.262472 -236.214412)
		(end 82.262472 -235.645198)
		(width 0.127)
		(layer "In5.Cu")
		(net "T6_BLAD4_RXD")
	)
	(segment
		(start 83.53298 -234.37469)
		(end 83.53298 -229.238048)
		(width 0.127)
		(layer "In5.Cu")
		(net "T6_BLAD4_RXD")
	)
	(segment
		(start 8.893048 -251.8029)
		(end 8.045196 -251.8029)
		(width 0.127)
		(layer "In5.Cu")
		(net "T6_BLAD4_RXD")
	)
	(segment
		(start 5.27304 -253.371604)
		(end 5.27304 -254.346456)
		(width 0.127)
		(layer "In5.Cu")
		(net "T6_BLAD4_RXD")
	)
	(via
		(at 80.913478 -239.059212)
		(size 0.508)
		(drill 0.254)
		(layers "F.Cu" "B.Cu")
		(net "T6_BLAD4_TXD")
	)
	(segment
		(start 82.964782 -233.957622)
		(end 82.964782 -229.238556)
		(width 0.127)
		(layer "In5.Cu")
		(net "T6_BLAD4_TXD")
	)
	(segment
		(start 11.010138 -255.147064)
		(end 11.010138 -253.395734)
		(width 0.127)
		(layer "In5.Cu")
		(net "T6_BLAD4_TXD")
	)
	(segment
		(start 64.002158 -260.504432)
		(end 48.354996 -260.504432)
		(width 0.127)
		(layer "In5.Cu")
		(net "T6_BLAD4_TXD")
	)
	(segment
		(start 6.814312 -252.509528)
		(end 5.61086 -252.509528)
		(width 0.127)
		(layer "In5.Cu")
		(net "T6_BLAD4_TXD")
	)
	(segment
		(start 48.354996 -260.504432)
		(end 47.658528 -261.2009)
		(width 0.127)
		(layer "In5.Cu")
		(net "T6_BLAD4_TXD")
	)
	(segment
		(start 82.964782 -229.238556)
		(end 86.370414 -225.832924)
		(width 0.127)
		(layer "In5.Cu")
		(net "T6_BLAD4_TXD")
	)
	(segment
		(start 80.913478 -236.008926)
		(end 82.964782 -233.957622)
		(width 0.127)
		(layer "In5.Cu")
		(net "T6_BLAD4_TXD")
	)
	(segment
		(start 80.913478 -243.593112)
		(end 64.002158 -260.504432)
		(width 0.127)
		(layer "In5.Cu")
		(net "T6_BLAD4_TXD")
	)
	(segment
		(start 47.658528 -261.2009)
		(end 17.063974 -261.2009)
		(width 0.127)
		(layer "In5.Cu")
		(net "T6_BLAD4_TXD")
	)
	(segment
		(start 5.61086 -252.509528)
		(end 4.902454 -253.217934)
		(width 0.127)
		(layer "In5.Cu")
		(net "T6_BLAD4_TXD")
	)
	(segment
		(start 4.902454 -253.863094)
		(end 4.094988 -254.67056)
		(width 0.127)
		(layer "In5.Cu")
		(net "T6_BLAD4_TXD")
	)
	(segment
		(start 4.094988 -254.67056)
		(end 1.948942 -254.67056)
		(width 0.127)
		(layer "In5.Cu")
		(net "T6_BLAD4_TXD")
	)
	(segment
		(start 91.100402 -228.144578)
		(end 90.71991 -228.52507)
		(width 0.127)
		(layer "In5.Cu")
		(net "T6_BLAD4_TXD")
	)
	(segment
		(start 80.913478 -239.059212)
		(end 80.913478 -243.593112)
		(width 0.127)
		(layer "In5.Cu")
		(net "T6_BLAD4_TXD")
	)
	(segment
		(start 17.063974 -261.2009)
		(end 11.010138 -255.147064)
		(width 0.127)
		(layer "In5.Cu")
		(net "T6_BLAD4_TXD")
	)
	(segment
		(start 92.495116 -228.144578)
		(end 91.100402 -228.144578)
		(width 0.127)
		(layer "In5.Cu")
		(net "T6_BLAD4_TXD")
	)
	(segment
		(start 92.871544 -226.89058)
		(end 92.871544 -227.76815)
		(width 0.127)
		(layer "In5.Cu")
		(net "T6_BLAD4_TXD")
	)
	(segment
		(start 11.010138 -253.395734)
		(end 9.046718 -251.432314)
		(width 0.127)
		(layer "In5.Cu")
		(net "T6_BLAD4_TXD")
	)
	(segment
		(start 80.913478 -239.059212)
		(end 80.913478 -236.008926)
		(width 0.127)
		(layer "In5.Cu")
		(net "T6_BLAD4_TXD")
	)
	(segment
		(start 86.370414 -225.832924)
		(end 91.813888 -225.832924)
		(width 0.127)
		(layer "In5.Cu")
		(net "T6_BLAD4_TXD")
	)
	(segment
		(start 92.871544 -227.76815)
		(end 92.495116 -228.144578)
		(width 0.127)
		(layer "In5.Cu")
		(net "T6_BLAD4_TXD")
	)
	(segment
		(start 91.813888 -225.832924)
		(end 92.871544 -226.89058)
		(width 0.127)
		(layer "In5.Cu")
		(net "T6_BLAD4_TXD")
	)
	(segment
		(start 4.902454 -253.217934)
		(end 4.902454 -253.863094)
		(width 0.127)
		(layer "In5.Cu")
		(net "T6_BLAD4_TXD")
	)
	(segment
		(start 9.046718 -251.432314)
		(end 7.891526 -251.432314)
		(width 0.127)
		(layer "In5.Cu")
		(net "T6_BLAD4_TXD")
	)
	(segment
		(start 7.891526 -251.432314)
		(end 6.814312 -252.509528)
		(width 0.127)
		(layer "In5.Cu")
		(net "T6_BLAD4_TXD")
	)
	(via
		(at 82.320892 -240.310416)
		(size 0.508)
		(drill 0.254)
		(layers "F.Cu" "B.Cu")
		(net "T6_BLAD1_RXD")
	)
	(segment
		(start 6.164072 -269.925038)
		(end 5.419344 -270.669766)
		(width 0.127)
		(layer "In2.Cu")
		(net "T6_BLAD1_RXD")
	)
	(segment
		(start 81.759552 -237.75416)
		(end 81.759552 -236.054138)
		(width 0.127)
		(layer "In2.Cu")
		(net "T6_BLAD1_RXD")
	)
	(segment
		(start 6.61035 -269.925038)
		(end 6.164072 -269.925038)
		(width 0.127)
		(layer "In2.Cu")
		(net "T6_BLAD1_RXD")
	)
	(segment
		(start 17.67332 -263.998456)
		(end 12.794996 -268.87678)
		(width 0.127)
		(layer "In2.Cu")
		(net "T6_BLAD1_RXD")
	)
	(segment
		(start 12.794996 -268.87678)
		(end 7.658608 -268.87678)
		(width 0.127)
		(layer "In2.Cu")
		(net "T6_BLAD1_RXD")
	)
	(segment
		(start 7.658608 -268.87678)
		(end 6.61035 -269.925038)
		(width 0.127)
		(layer "In2.Cu")
		(net "T6_BLAD1_RXD")
	)
	(segment
		(start 86.90102 -229.80396)
		(end 86.90991 -229.79507)
		(width 0.127)
		(layer "In2.Cu")
		(net "T6_BLAD1_RXD")
	)
	(segment
		(start 82.320892 -238.3155)
		(end 81.759552 -237.75416)
		(width 0.127)
		(layer "In2.Cu")
		(net "T6_BLAD1_RXD")
	)
	(segment
		(start 82.320892 -240.310416)
		(end 82.320892 -238.3155)
		(width 0.127)
		(layer "In2.Cu")
		(net "T6_BLAD1_RXD")
	)
	(segment
		(start 81.759552 -236.054138)
		(end 86.90102 -230.91267)
		(width 0.127)
		(layer "In2.Cu")
		(net "T6_BLAD1_RXD")
	)
	(segment
		(start 86.90102 -230.91267)
		(end 86.90102 -229.80396)
		(width 0.127)
		(layer "In2.Cu")
		(net "T6_BLAD1_RXD")
	)
	(segment
		(start 82.320892 -240.310416)
		(end 82.320892 -245.575074)
		(width 0.127)
		(layer "In2.Cu")
		(net "T6_BLAD1_RXD")
	)
	(segment
		(start 82.320892 -245.575074)
		(end 63.89751 -263.998456)
		(width 0.127)
		(layer "In2.Cu")
		(net "T6_BLAD1_RXD")
	)
	(segment
		(start 63.89751 -263.998456)
		(end 17.67332 -263.998456)
		(width 0.127)
		(layer "In2.Cu")
		(net "T6_BLAD1_RXD")
	)
	(segment
		(start 5.419344 -270.669766)
		(end 3.949954 -270.669766)
		(width 0.127)
		(layer "In2.Cu")
		(net "T6_BLAD1_RXD")
	)
	(via
		(at 81.64195 -241.700558)
		(size 0.508)
		(drill 0.254)
		(layers "F.Cu" "B.Cu")
		(net "T6_BLAD1_TXD")
	)
	(segment
		(start 81.374488 -241.433096)
		(end 81.374488 -235.956602)
		(width 0.127)
		(layer "In2.Cu")
		(net "T6_BLAD1_TXD")
	)
	(segment
		(start 5.737352 -269.594838)
		(end 5.662422 -269.669768)
		(width 0.127)
		(layer "In2.Cu")
		(net "T6_BLAD1_TXD")
	)
	(segment
		(start 5.662422 -269.669768)
		(end 1.949958 -269.669768)
		(width 0.127)
		(layer "In2.Cu")
		(net "T6_BLAD1_TXD")
	)
	(segment
		(start 7.521702 -268.54658)
		(end 6.473444 -269.594838)
		(width 0.127)
		(layer "In2.Cu")
		(net "T6_BLAD1_TXD")
	)
	(segment
		(start 12.623292 -268.54658)
		(end 7.521702 -268.54658)
		(width 0.127)
		(layer "In2.Cu")
		(net "T6_BLAD1_TXD")
	)
	(segment
		(start 81.64195 -245.78691)
		(end 63.785242 -263.643618)
		(width 0.127)
		(layer "In2.Cu")
		(net "T6_BLAD1_TXD")
	)
	(segment
		(start 81.64195 -241.700558)
		(end 81.64195 -245.78691)
		(width 0.127)
		(layer "In2.Cu")
		(net "T6_BLAD1_TXD")
	)
	(segment
		(start 6.473444 -269.594838)
		(end 5.737352 -269.594838)
		(width 0.127)
		(layer "In2.Cu")
		(net "T6_BLAD1_TXD")
	)
	(segment
		(start 17.526254 -263.643618)
		(end 12.623292 -268.54658)
		(width 0.127)
		(layer "In2.Cu")
		(net "T6_BLAD1_TXD")
	)
	(segment
		(start 85.63991 -231.69118)
		(end 85.63991 -231.06507)
		(width 0.127)
		(layer "In2.Cu")
		(net "T6_BLAD1_TXD")
	)
	(segment
		(start 81.64195 -241.700558)
		(end 81.374488 -241.433096)
		(width 0.127)
		(layer "In2.Cu")
		(net "T6_BLAD1_TXD")
	)
	(segment
		(start 63.785242 -263.643618)
		(end 17.526254 -263.643618)
		(width 0.127)
		(layer "In2.Cu")
		(net "T6_BLAD1_TXD")
	)
	(segment
		(start 81.374488 -235.956602)
		(end 85.63991 -231.69118)
		(width 0.127)
		(layer "In2.Cu")
		(net "T6_BLAD1_TXD")
	)
	(via
		(at 84.461858 -239.711484)
		(size 0.508)
		(drill 0.254)
		(layers "F.Cu" "B.Cu")
		(net "T6_BLAD3_RXD")
	)
	(segment
		(start 9.64311 -255.296162)
		(end 9.64311 -254.576072)
		(width 0.127)
		(layer "In5.Cu")
		(net "T6_BLAD3_RXD")
	)
	(segment
		(start 9.64311 -254.576072)
		(end 8.910066 -253.843028)
		(width 0.127)
		(layer "In5.Cu")
		(net "T6_BLAD3_RXD")
	)
	(segment
		(start 62.220856 -263.687052)
		(end 18.034 -263.687052)
		(width 0.127)
		(layer "In5.Cu")
		(net "T6_BLAD3_RXD")
	)
	(segment
		(start 85.278214 -234.759754)
		(end 84.775294 -234.256834)
		(width 0.127)
		(layer "In5.Cu")
		(net "T6_BLAD3_RXD")
	)
	(segment
		(start 8.910066 -253.843028)
		(end 8.007858 -253.843028)
		(width 0.127)
		(layer "In5.Cu")
		(net "T6_BLAD3_RXD")
	)
	(segment
		(start 8.007858 -253.843028)
		(end 6.920484 -254.930402)
		(width 0.127)
		(layer "In5.Cu")
		(net "T6_BLAD3_RXD")
	)
	(segment
		(start 6.920484 -254.930402)
		(end 5.809742 -254.930402)
		(width 0.127)
		(layer "In5.Cu")
		(net "T6_BLAD3_RXD")
	)
	(segment
		(start 84.461858 -239.711484)
		(end 84.461858 -241.44605)
		(width 0.127)
		(layer "In5.Cu")
		(net "T6_BLAD3_RXD")
	)
	(segment
		(start 85.278214 -237.048294)
		(end 85.278214 -234.759754)
		(width 0.127)
		(layer "In5.Cu")
		(net "T6_BLAD3_RXD")
	)
	(segment
		(start 84.461858 -237.86465)
		(end 85.278214 -237.048294)
		(width 0.127)
		(layer "In5.Cu")
		(net "T6_BLAD3_RXD")
	)
	(segment
		(start 84.461858 -241.44605)
		(end 62.220856 -263.687052)
		(width 0.127)
		(layer "In5.Cu")
		(net "T6_BLAD3_RXD")
	)
	(segment
		(start 84.775294 -234.256834)
		(end 84.775294 -230.550212)
		(width 0.127)
		(layer "In5.Cu")
		(net "T6_BLAD3_RXD")
	)
	(segment
		(start 84.775294 -230.550212)
		(end 86.90991 -228.415596)
		(width 0.127)
		(layer "In5.Cu")
		(net "T6_BLAD3_RXD")
	)
	(segment
		(start 5.566664 -255.17348)
		(end 5.566664 -256.052828)
		(width 0.127)
		(layer "In5.Cu")
		(net "T6_BLAD3_RXD")
	)
	(segment
		(start 84.461858 -239.711484)
		(end 84.461858 -237.86465)
		(width 0.127)
		(layer "In5.Cu")
		(net "T6_BLAD3_RXD")
	)
	(segment
		(start 86.90991 -228.415596)
		(end 86.90991 -227.25507)
		(width 0.127)
		(layer "In5.Cu")
		(net "T6_BLAD3_RXD")
	)
	(segment
		(start 5.566664 -256.052828)
		(end 3.948938 -257.670554)
		(width 0.127)
		(layer "In5.Cu")
		(net "T6_BLAD3_RXD")
	)
	(segment
		(start 18.034 -263.687052)
		(end 9.64311 -255.296162)
		(width 0.127)
		(layer "In5.Cu")
		(net "T6_BLAD3_RXD")
	)
	(segment
		(start 5.809742 -254.930402)
		(end 5.566664 -255.17348)
		(width 0.127)
		(layer "In5.Cu")
		(net "T6_BLAD3_RXD")
	)
	(via
		(at 83.804252 -240.984024)
		(size 0.508)
		(drill 0.254)
		(layers "F.Cu" "B.Cu")
		(net "T6_BLAD3_TXD")
	)
	(segment
		(start 83.804252 -240.984024)
		(end 83.804252 -241.63655)
		(width 0.127)
		(layer "In5.Cu")
		(net "T6_BLAD3_TXD")
	)
	(segment
		(start 83.804252 -240.984024)
		(end 83.804252 -238.258604)
		(width 0.127)
		(layer "In5.Cu")
		(net "T6_BLAD3_TXD")
	)
	(segment
		(start 18.17116 -263.356344)
		(end 10.108946 -255.29413)
		(width 0.127)
		(layer "In5.Cu")
		(net "T6_BLAD3_TXD")
	)
	(segment
		(start 5.20319 -255.022858)
		(end 5.20319 -255.509014)
		(width 0.127)
		(layer "In5.Cu")
		(net "T6_BLAD3_TXD")
	)
	(segment
		(start 83.804252 -241.63655)
		(end 62.084458 -263.356344)
		(width 0.127)
		(layer "In5.Cu")
		(net "T6_BLAD3_TXD")
	)
	(segment
		(start 9.060688 -253.479554)
		(end 7.857236 -253.479554)
		(width 0.127)
		(layer "In5.Cu")
		(net "T6_BLAD3_TXD")
	)
	(segment
		(start 82.98942 -235.914692)
		(end 84.115402 -234.78871)
		(width 0.127)
		(layer "In5.Cu")
		(net "T6_BLAD3_TXD")
	)
	(segment
		(start 82.98942 -237.443772)
		(end 82.98942 -235.914692)
		(width 0.127)
		(layer "In5.Cu")
		(net "T6_BLAD3_TXD")
	)
	(segment
		(start 83.804252 -238.258604)
		(end 82.98942 -237.443772)
		(width 0.127)
		(layer "In5.Cu")
		(net "T6_BLAD3_TXD")
	)
	(segment
		(start 5.20319 -255.509014)
		(end 4.041648 -256.670556)
		(width 0.127)
		(layer "In5.Cu")
		(net "T6_BLAD3_TXD")
	)
	(segment
		(start 6.745986 -254.590804)
		(end 5.635244 -254.590804)
		(width 0.127)
		(layer "In5.Cu")
		(net "T6_BLAD3_TXD")
	)
	(segment
		(start 84.115402 -230.049578)
		(end 85.63991 -228.52507)
		(width 0.127)
		(layer "In5.Cu")
		(net "T6_BLAD3_TXD")
	)
	(segment
		(start 5.635244 -254.590804)
		(end 5.20319 -255.022858)
		(width 0.127)
		(layer "In5.Cu")
		(net "T6_BLAD3_TXD")
	)
	(segment
		(start 10.108946 -255.29413)
		(end 10.108946 -254.527812)
		(width 0.127)
		(layer "In5.Cu")
		(net "T6_BLAD3_TXD")
	)
	(segment
		(start 84.115402 -234.78871)
		(end 84.115402 -230.049578)
		(width 0.127)
		(layer "In5.Cu")
		(net "T6_BLAD3_TXD")
	)
	(segment
		(start 7.857236 -253.479554)
		(end 6.745986 -254.590804)
		(width 0.127)
		(layer "In5.Cu")
		(net "T6_BLAD3_TXD")
	)
	(segment
		(start 4.041648 -256.670556)
		(end 1.948942 -256.670556)
		(width 0.127)
		(layer "In5.Cu")
		(net "T6_BLAD3_TXD")
	)
	(segment
		(start 10.108946 -254.527812)
		(end 9.060688 -253.479554)
		(width 0.127)
		(layer "In5.Cu")
		(net "T6_BLAD3_TXD")
	)
	(segment
		(start 62.084458 -263.356344)
		(end 18.17116 -263.356344)
		(width 0.127)
		(layer "In5.Cu")
		(net "T6_BLAD3_TXD")
	)
	(via
		(at 83.191096 -192.53708)
		(size 0.508)
		(drill 0.254)
		(layers "F.Cu" "B.Cu")
		(net "T5_BLAD4_RXD")
	)
	(segment
		(start 42.472356 -261.178548)
		(end 42.857674 -260.79323)
		(width 0.127)
		(layer "In2.Cu")
		(net "T5_BLAD4_RXD")
	)
	(segment
		(start 83.191096 -183.722264)
		(end 83.191096 -192.53708)
		(width 0.127)
		(layer "In2.Cu")
		(net "T5_BLAD4_RXD")
	)
	(segment
		(start 8.448802 -250.881388)
		(end 12.665964 -255.09855)
		(width 0.127)
		(layer "In2.Cu")
		(net "T5_BLAD4_RXD")
	)
	(segment
		(start 82.935572 -231.096566)
		(end 82.935572 -216.372948)
		(width 0.127)
		(layer "In2.Cu")
		(net "T5_BLAD4_RXD")
	)
	(segment
		(start 45.440854 -260.79323)
		(end 46.474126 -259.759958)
		(width 0.127)
		(layer "In2.Cu")
		(net "T5_BLAD4_RXD")
	)
	(segment
		(start 84.282026 -215.026494)
		(end 84.282026 -202.596496)
		(width 0.127)
		(layer "In2.Cu")
		(net "T5_BLAD4_RXD")
	)
	(segment
		(start 8.448802 -248.670572)
		(end 8.448802 -250.881388)
		(width 0.127)
		(layer "In2.Cu")
		(net "T5_BLAD4_RXD")
	)
	(segment
		(start 12.665964 -255.09855)
		(end 12.665964 -256.778506)
		(width 0.127)
		(layer "In2.Cu")
		(net "T5_BLAD4_RXD")
	)
	(segment
		(start 12.665964 -256.778506)
		(end 17.066006 -261.178548)
		(width 0.127)
		(layer "In2.Cu")
		(net "T5_BLAD4_RXD")
	)
	(segment
		(start 90.650822 -181.465728)
		(end 85.447632 -181.465728)
		(width 0.127)
		(layer "In2.Cu")
		(net "T5_BLAD4_RXD")
	)
	(segment
		(start 83.191096 -201.505566)
		(end 83.191096 -192.53708)
		(width 0.127)
		(layer "In2.Cu")
		(net "T5_BLAD4_RXD")
	)
	(segment
		(start 78.310994 -235.721144)
		(end 82.935572 -231.096566)
		(width 0.127)
		(layer "In2.Cu")
		(net "T5_BLAD4_RXD")
	)
	(segment
		(start 46.474126 -259.759958)
		(end 64.798448 -259.759958)
		(width 0.127)
		(layer "In2.Cu")
		(net "T5_BLAD4_RXD")
	)
	(segment
		(start 84.282026 -202.596496)
		(end 83.191096 -201.505566)
		(width 0.127)
		(layer "In2.Cu")
		(net "T5_BLAD4_RXD")
	)
	(segment
		(start 64.798448 -259.759958)
		(end 78.310994 -246.247158)
		(width 0.127)
		(layer "In2.Cu")
		(net "T5_BLAD4_RXD")
	)
	(segment
		(start 17.066006 -261.178548)
		(end 42.472356 -261.178548)
		(width 0.127)
		(layer "In2.Cu")
		(net "T5_BLAD4_RXD")
	)
	(segment
		(start 82.935572 -216.372948)
		(end 84.282026 -215.026494)
		(width 0.127)
		(layer "In2.Cu")
		(net "T5_BLAD4_RXD")
	)
	(segment
		(start 42.857674 -260.79323)
		(end 45.440854 -260.79323)
		(width 0.127)
		(layer "In2.Cu")
		(net "T5_BLAD4_RXD")
	)
	(segment
		(start 78.310994 -246.247158)
		(end 78.310994 -235.721144)
		(width 0.127)
		(layer "In2.Cu")
		(net "T5_BLAD4_RXD")
	)
	(segment
		(start 85.447632 -181.465728)
		(end 83.191096 -183.722264)
		(width 0.127)
		(layer "In2.Cu")
		(net "T5_BLAD4_RXD")
	)
	(segment
		(start 91.990164 -182.80507)
		(end 90.650822 -181.465728)
		(width 0.127)
		(layer "In2.Cu")
		(net "T5_BLAD4_RXD")
	)
	(via
		(at 95.670116 -191.705992)
		(size 0.508)
		(drill 0.254)
		(layers "F.Cu" "B.Cu")
		(net "T5_BLAD1_EN")
	)
	(segment
		(start 6.449822 -269.669768)
		(end 9.92124 -266.19835)
		(width 0.127)
		(layer "In5.Cu")
		(net "T5_BLAD1_EN")
	)
	(segment
		(start 9.92124 -266.19835)
		(end 62.513464 -266.19835)
		(width 0.127)
		(layer "In5.Cu")
		(net "T5_BLAD1_EN")
	)
	(segment
		(start 101.097588 -197.133464)
		(end 95.670116 -191.705992)
		(width 0.127)
		(layer "In5.Cu")
		(net "T5_BLAD1_EN")
	)
	(segment
		(start 93.88094 -248.963688)
		(end 101.097588 -241.74704)
		(width 0.127)
		(layer "In5.Cu")
		(net "T5_BLAD1_EN")
	)
	(segment
		(start 62.513464 -266.19835)
		(end 79.748126 -248.963688)
		(width 0.127)
		(layer "In5.Cu")
		(net "T5_BLAD1_EN")
	)
	(segment
		(start 101.097588 -241.74704)
		(end 101.097588 -197.133464)
		(width 0.127)
		(layer "In5.Cu")
		(net "T5_BLAD1_EN")
	)
	(segment
		(start 6.449822 -270.669766)
		(end 6.449822 -269.669768)
		(width 0.127)
		(layer "In5.Cu")
		(net "T5_BLAD1_EN")
	)
	(segment
		(start 79.748126 -248.963688)
		(end 93.88094 -248.963688)
		(width 0.127)
		(layer "In5.Cu")
		(net "T5_BLAD1_EN")
	)
	(segment
		(start 88.180164 -186.61507)
		(end 90.19413 -188.629036)
		(width 0.127)
		(layer "In5.Cu")
		(net "T5_BLAD1_EN")
	)
	(segment
		(start 90.19413 -188.629036)
		(end 92.59316 -188.629036)
		(width 0.127)
		(layer "In5.Cu")
		(net "T5_BLAD1_EN")
	)
	(segment
		(start 92.59316 -188.629036)
		(end 95.670116 -191.705992)
		(width 0.127)
		(layer "In5.Cu")
		(net "T5_BLAD1_EN")
	)
	(via
		(at 84.83854 -192.681352)
		(size 0.508)
		(drill 0.254)
		(layers "F.Cu" "B.Cu")
		(net "T5_BLAD3_TXD")
	)
	(segment
		(start 85.640164 -184.07507)
		(end 84.83854 -184.876694)
		(width 0.127)
		(layer "In2.Cu")
		(net "T5_BLAD3_TXD")
	)
	(segment
		(start 85.485732 -201.740008)
		(end 84.83854 -201.092816)
		(width 0.127)
		(layer "In2.Cu")
		(net "T5_BLAD3_TXD")
	)
	(segment
		(start 85.485732 -215.503252)
		(end 85.485732 -201.740008)
		(width 0.127)
		(layer "In2.Cu")
		(net "T5_BLAD3_TXD")
	)
	(segment
		(start 79.572866 -236.283754)
		(end 84.125308 -231.731312)
		(width 0.127)
		(layer "In2.Cu")
		(net "T5_BLAD3_TXD")
	)
	(segment
		(start 46.75378 -262.550402)
		(end 48.472598 -260.831584)
		(width 0.127)
		(layer "In2.Cu")
		(net "T5_BLAD3_TXD")
	)
	(segment
		(start 11.404092 -256.918714)
		(end 17.03578 -262.550402)
		(width 0.127)
		(layer "In2.Cu")
		(net "T5_BLAD3_TXD")
	)
	(segment
		(start 8.050276 -253.440184)
		(end 8.871458 -253.440184)
		(width 0.127)
		(layer "In2.Cu")
		(net "T5_BLAD3_TXD")
	)
	(segment
		(start 17.03578 -262.550402)
		(end 46.75378 -262.550402)
		(width 0.127)
		(layer "In2.Cu")
		(net "T5_BLAD3_TXD")
	)
	(segment
		(start 7.551674 -252.773434)
		(end 7.551674 -252.941582)
		(width 0.127)
		(layer "In2.Cu")
		(net "T5_BLAD3_TXD")
	)
	(segment
		(start 8.871458 -253.440184)
		(end 11.404092 -255.972818)
		(width 0.127)
		(layer "In2.Cu")
		(net "T5_BLAD3_TXD")
	)
	(segment
		(start 84.83854 -184.876694)
		(end 84.83854 -192.681352)
		(width 0.127)
		(layer "In2.Cu")
		(net "T5_BLAD3_TXD")
	)
	(segment
		(start 11.404092 -255.972818)
		(end 11.404092 -256.918714)
		(width 0.127)
		(layer "In2.Cu")
		(net "T5_BLAD3_TXD")
	)
	(segment
		(start 48.472598 -260.831584)
		(end 65.12814 -260.831584)
		(width 0.127)
		(layer "In2.Cu")
		(net "T5_BLAD3_TXD")
	)
	(segment
		(start 7.551674 -252.941582)
		(end 8.050276 -253.440184)
		(width 0.127)
		(layer "In2.Cu")
		(net "T5_BLAD3_TXD")
	)
	(segment
		(start 84.83854 -201.092816)
		(end 84.83854 -192.681352)
		(width 0.127)
		(layer "In2.Cu")
		(net "T5_BLAD3_TXD")
	)
	(segment
		(start 84.125308 -231.731312)
		(end 84.125308 -216.863676)
		(width 0.127)
		(layer "In2.Cu")
		(net "T5_BLAD3_TXD")
	)
	(segment
		(start 84.125308 -216.863676)
		(end 85.485732 -215.503252)
		(width 0.127)
		(layer "In2.Cu")
		(net "T5_BLAD3_TXD")
	)
	(segment
		(start 6.448806 -251.670566)
		(end 7.551674 -252.773434)
		(width 0.127)
		(layer "In2.Cu")
		(net "T5_BLAD3_TXD")
	)
	(segment
		(start 65.12814 -260.831584)
		(end 79.572866 -246.386858)
		(width 0.127)
		(layer "In2.Cu")
		(net "T5_BLAD3_TXD")
	)
	(segment
		(start 79.572866 -246.386858)
		(end 79.572866 -236.283754)
		(width 0.127)
		(layer "In2.Cu")
		(net "T5_BLAD3_TXD")
	)
	(via
		(at 98.24466 -196.681852)
		(size 0.508)
		(drill 0.254)
		(layers "F.Cu" "B.Cu")
		(net "T5_BLAD3_EN")
	)
	(segment
		(start 86.027768 -185.868564)
		(end 86.52256 -186.363356)
		(width 0.127)
		(layer "In5.Cu")
		(net "T5_BLAD3_EN")
	)
	(segment
		(start 79.478886 -248.298462)
		(end 62.659006 -265.118342)
		(width 0.127)
		(layer "In5.Cu")
		(net "T5_BLAD3_EN")
	)
	(segment
		(start 62.659006 -265.118342)
		(end 12.896596 -265.118342)
		(width 0.127)
		(layer "In5.Cu")
		(net "T5_BLAD3_EN")
	)
	(segment
		(start 91.585796 -190.022988)
		(end 98.24466 -196.681852)
		(width 0.127)
		(layer "In5.Cu")
		(net "T5_BLAD3_EN")
	)
	(segment
		(start 93.506036 -248.298462)
		(end 79.478886 -248.298462)
		(width 0.127)
		(layer "In5.Cu")
		(net "T5_BLAD3_EN")
	)
	(segment
		(start 86.027768 -184.89803)
		(end 86.027768 -185.868564)
		(width 0.127)
		(layer "In5.Cu")
		(net "T5_BLAD3_EN")
	)
	(segment
		(start 86.52256 -187.386976)
		(end 89.158572 -190.022988)
		(width 0.127)
		(layer "In5.Cu")
		(net "T5_BLAD3_EN")
	)
	(segment
		(start 12.896596 -265.118342)
		(end 8.448802 -260.670548)
		(width 0.127)
		(layer "In5.Cu")
		(net "T5_BLAD3_EN")
	)
	(segment
		(start 88.180164 -184.07507)
		(end 88.162892 -184.092342)
		(width 0.127)
		(layer "In5.Cu")
		(net "T5_BLAD3_EN")
	)
	(segment
		(start 86.52256 -186.363356)
		(end 86.52256 -187.386976)
		(width 0.127)
		(layer "In5.Cu")
		(net "T5_BLAD3_EN")
	)
	(segment
		(start 88.162892 -184.092342)
		(end 86.833456 -184.092342)
		(width 0.127)
		(layer "In5.Cu")
		(net "T5_BLAD3_EN")
	)
	(segment
		(start 98.24466 -196.681852)
		(end 99.828858 -198.26605)
		(width 0.127)
		(layer "In5.Cu")
		(net "T5_BLAD3_EN")
	)
	(segment
		(start 99.828858 -198.26605)
		(end 99.828858 -241.97564)
		(width 0.127)
		(layer "In5.Cu")
		(net "T5_BLAD3_EN")
	)
	(segment
		(start 99.828858 -241.97564)
		(end 93.506036 -248.298462)
		(width 0.127)
		(layer "In5.Cu")
		(net "T5_BLAD3_EN")
	)
	(segment
		(start 89.158572 -190.022988)
		(end 91.585796 -190.022988)
		(width 0.127)
		(layer "In5.Cu")
		(net "T5_BLAD3_EN")
	)
	(segment
		(start 86.833456 -184.092342)
		(end 86.027768 -184.89803)
		(width 0.127)
		(layer "In5.Cu")
		(net "T5_BLAD3_EN")
	)
	(via
		(at 97.254568 -194.99834)
		(size 0.508)
		(drill 0.254)
		(layers "F.Cu" "B.Cu")
		(net "T5_BLAD1_RXD")
	)
	(segment
		(start 86.910164 -187.134246)
		(end 86.910164 -185.34507)
		(width 0.127)
		(layer "In5.Cu")
		(net "T5_BLAD1_RXD")
	)
	(segment
		(start 6.448806 -257.670554)
		(end 7.513066 -258.734814)
		(width 0.127)
		(layer "In5.Cu")
		(net "T5_BLAD1_RXD")
	)
	(segment
		(start 89.342722 -189.566804)
		(end 86.910164 -187.134246)
		(width 0.127)
		(layer "In5.Cu")
		(net "T5_BLAD1_RXD")
	)
	(segment
		(start 62.77483 -265.469878)
		(end 79.616046 -248.628662)
		(width 0.127)
		(layer "In5.Cu")
		(net "T5_BLAD1_RXD")
	)
	(segment
		(start 93.74886 -248.628662)
		(end 100.18141 -242.196112)
		(width 0.127)
		(layer "In5.Cu")
		(net "T5_BLAD1_RXD")
	)
	(segment
		(start 91.823032 -189.566804)
		(end 89.342722 -189.566804)
		(width 0.127)
		(layer "In5.Cu")
		(net "T5_BLAD1_RXD")
	)
	(segment
		(start 79.616046 -248.628662)
		(end 93.74886 -248.628662)
		(width 0.127)
		(layer "In5.Cu")
		(net "T5_BLAD1_RXD")
	)
	(segment
		(start 12.190984 -265.469878)
		(end 62.77483 -265.469878)
		(width 0.127)
		(layer "In5.Cu")
		(net "T5_BLAD1_RXD")
	)
	(segment
		(start 100.18141 -197.925182)
		(end 97.254568 -194.99834)
		(width 0.127)
		(layer "In5.Cu")
		(net "T5_BLAD1_RXD")
	)
	(segment
		(start 7.513066 -260.79196)
		(end 12.190984 -265.469878)
		(width 0.127)
		(layer "In5.Cu")
		(net "T5_BLAD1_RXD")
	)
	(segment
		(start 7.513066 -258.734814)
		(end 7.513066 -260.79196)
		(width 0.127)
		(layer "In5.Cu")
		(net "T5_BLAD1_RXD")
	)
	(segment
		(start 97.254568 -194.99834)
		(end 91.823032 -189.566804)
		(width 0.127)
		(layer "In5.Cu")
		(net "T5_BLAD1_RXD")
	)
	(segment
		(start 100.18141 -242.196112)
		(end 100.18141 -197.925182)
		(width 0.127)
		(layer "In5.Cu")
		(net "T5_BLAD1_RXD")
	)
	(via
		(at 86.109048 -191.226186)
		(size 0.508)
		(drill 0.254)
		(layers "F.Cu" "B.Cu")
		(net "T5_BLAD2_TXD")
	)
	(segment
		(start 84.472526 -217.095578)
		(end 85.83295 -215.735154)
		(width 0.127)
		(layer "In2.Cu")
		(net "T5_BLAD2_TXD")
	)
	(segment
		(start 8.761984 -253.93015)
		(end 10.907776 -256.075942)
		(width 0.127)
		(layer "In2.Cu")
		(net "T5_BLAD2_TXD")
	)
	(segment
		(start 86.109048 -191.226186)
		(end 90.720164 -186.61507)
		(width 0.127)
		(layer "In2.Cu")
		(net "T5_BLAD2_TXD")
	)
	(segment
		(start 79.920084 -246.507)
		(end 79.920084 -236.427772)
		(width 0.127)
		(layer "In2.Cu")
		(net "T5_BLAD2_TXD")
	)
	(segment
		(start 7.452106 -253.670562)
		(end 7.711694 -253.93015)
		(width 0.127)
		(layer "In2.Cu")
		(net "T5_BLAD2_TXD")
	)
	(segment
		(start 10.907776 -257.134868)
		(end 16.670528 -262.89762)
		(width 0.127)
		(layer "In2.Cu")
		(net "T5_BLAD2_TXD")
	)
	(segment
		(start 85.83295 -191.502284)
		(end 86.109048 -191.226186)
		(width 0.127)
		(layer "In2.Cu")
		(net "T5_BLAD2_TXD")
	)
	(segment
		(start 10.907776 -256.075942)
		(end 10.907776 -257.134868)
		(width 0.127)
		(layer "In2.Cu")
		(net "T5_BLAD2_TXD")
	)
	(segment
		(start 16.670528 -262.89762)
		(end 47.146718 -262.89762)
		(width 0.127)
		(layer "In2.Cu")
		(net "T5_BLAD2_TXD")
	)
	(segment
		(start 84.472526 -231.87533)
		(end 84.472526 -217.095578)
		(width 0.127)
		(layer "In2.Cu")
		(net "T5_BLAD2_TXD")
	)
	(segment
		(start 85.83295 -215.735154)
		(end 85.83295 -191.502284)
		(width 0.127)
		(layer "In2.Cu")
		(net "T5_BLAD2_TXD")
	)
	(segment
		(start 47.146718 -262.89762)
		(end 48.76419 -261.280148)
		(width 0.127)
		(layer "In2.Cu")
		(net "T5_BLAD2_TXD")
	)
	(segment
		(start 7.711694 -253.93015)
		(end 8.761984 -253.93015)
		(width 0.127)
		(layer "In2.Cu")
		(net "T5_BLAD2_TXD")
	)
	(segment
		(start 48.76419 -261.280148)
		(end 65.146936 -261.280148)
		(width 0.127)
		(layer "In2.Cu")
		(net "T5_BLAD2_TXD")
	)
	(segment
		(start 6.448806 -253.670562)
		(end 7.452106 -253.670562)
		(width 0.127)
		(layer "In2.Cu")
		(net "T5_BLAD2_TXD")
	)
	(segment
		(start 79.920084 -236.427772)
		(end 84.472526 -231.87533)
		(width 0.127)
		(layer "In2.Cu")
		(net "T5_BLAD2_TXD")
	)
	(segment
		(start 65.146936 -261.280148)
		(end 79.920084 -246.507)
		(width 0.127)
		(layer "In2.Cu")
		(net "T5_BLAD2_TXD")
	)
	(via
		(at 83.651344 -193.724022)
		(size 0.508)
		(drill 0.254)
		(layers "F.Cu" "B.Cu")
		(net "T5_BLAD4_TXD")
	)
	(segment
		(start 84.705444 -202.289664)
		(end 83.651344 -201.235564)
		(width 0.127)
		(layer "In2.Cu")
		(net "T5_BLAD4_TXD")
	)
	(segment
		(start 83.651344 -183.860948)
		(end 83.651344 -193.724022)
		(width 0.127)
		(layer "In2.Cu")
		(net "T5_BLAD4_TXD")
	)
	(segment
		(start 42.671746 -261.639812)
		(end 43.158156 -261.153402)
		(width 0.127)
		(layer "In2.Cu")
		(net "T5_BLAD4_TXD")
	)
	(segment
		(start 83.651344 -201.235564)
		(end 83.651344 -193.724022)
		(width 0.127)
		(layer "In2.Cu")
		(net "T5_BLAD4_TXD")
	)
	(segment
		(start 12.2047 -255.289812)
		(end 12.2047 -256.784602)
		(width 0.127)
		(layer "In2.Cu")
		(net "T5_BLAD4_TXD")
	)
	(segment
		(start 84.705444 -215.22309)
		(end 84.705444 -202.289664)
		(width 0.127)
		(layer "In2.Cu")
		(net "T5_BLAD4_TXD")
	)
	(segment
		(start 64.921638 -260.103874)
		(end 78.772258 -246.253254)
		(width 0.127)
		(layer "In2.Cu")
		(net "T5_BLAD4_TXD")
	)
	(segment
		(start 45.904658 -261.153402)
		(end 46.954186 -260.103874)
		(width 0.127)
		(layer "In2.Cu")
		(net "T5_BLAD4_TXD")
	)
	(segment
		(start 46.954186 -260.103874)
		(end 64.921638 -260.103874)
		(width 0.127)
		(layer "In2.Cu")
		(net "T5_BLAD4_TXD")
	)
	(segment
		(start 90.220292 -181.889146)
		(end 85.623146 -181.889146)
		(width 0.127)
		(layer "In2.Cu")
		(net "T5_BLAD4_TXD")
	)
	(segment
		(start 83.383374 -216.54516)
		(end 84.705444 -215.22309)
		(width 0.127)
		(layer "In2.Cu")
		(net "T5_BLAD4_TXD")
	)
	(segment
		(start 78.772258 -235.951776)
		(end 83.383374 -231.34066)
		(width 0.127)
		(layer "In2.Cu")
		(net "T5_BLAD4_TXD")
	)
	(segment
		(start 6.448806 -247.670574)
		(end 7.618984 -248.840752)
		(width 0.127)
		(layer "In2.Cu")
		(net "T5_BLAD4_TXD")
	)
	(segment
		(start 12.2047 -256.784602)
		(end 17.05991 -261.639812)
		(width 0.127)
		(layer "In2.Cu")
		(net "T5_BLAD4_TXD")
	)
	(segment
		(start 78.772258 -246.253254)
		(end 78.772258 -235.951776)
		(width 0.127)
		(layer "In2.Cu")
		(net "T5_BLAD4_TXD")
	)
	(segment
		(start 90.720164 -182.389018)
		(end 90.220292 -181.889146)
		(width 0.127)
		(layer "In2.Cu")
		(net "T5_BLAD4_TXD")
	)
	(segment
		(start 43.158156 -261.153402)
		(end 45.904658 -261.153402)
		(width 0.127)
		(layer "In2.Cu")
		(net "T5_BLAD4_TXD")
	)
	(segment
		(start 90.720164 -184.07507)
		(end 90.720164 -182.389018)
		(width 0.127)
		(layer "In2.Cu")
		(net "T5_BLAD4_TXD")
	)
	(segment
		(start 83.383374 -231.34066)
		(end 83.383374 -216.54516)
		(width 0.127)
		(layer "In2.Cu")
		(net "T5_BLAD4_TXD")
	)
	(segment
		(start 7.618984 -250.704096)
		(end 12.2047 -255.289812)
		(width 0.127)
		(layer "In2.Cu")
		(net "T5_BLAD4_TXD")
	)
	(segment
		(start 7.618984 -248.840752)
		(end 7.618984 -250.704096)
		(width 0.127)
		(layer "In2.Cu")
		(net "T5_BLAD4_TXD")
	)
	(segment
		(start 17.05991 -261.639812)
		(end 42.671746 -261.639812)
		(width 0.127)
		(layer "In2.Cu")
		(net "T5_BLAD4_TXD")
	)
	(segment
		(start 85.623146 -181.889146)
		(end 83.651344 -183.860948)
		(width 0.127)
		(layer "In2.Cu")
		(net "T5_BLAD4_TXD")
	)
	(via
		(at 84.218272 -191.253618)
		(size 0.508)
		(drill 0.254)
		(layers "F.Cu" "B.Cu")
		(net "T5_BLAD3_RXD")
	)
	(segment
		(start 8.784336 -252.670564)
		(end 8.448802 -252.670564)
		(width 0.127)
		(layer "In2.Cu")
		(net "T5_BLAD3_RXD")
	)
	(segment
		(start 17.021302 -262.068564)
		(end 11.775948 -256.82321)
		(width 0.127)
		(layer "In2.Cu")
		(net "T5_BLAD3_RXD")
	)
	(segment
		(start 42.792904 -262.068564)
		(end 17.021302 -262.068564)
		(width 0.127)
		(layer "In2.Cu")
		(net "T5_BLAD3_RXD")
	)
	(segment
		(start 79.20101 -246.291608)
		(end 65.032382 -260.460236)
		(width 0.127)
		(layer "In2.Cu")
		(net "T5_BLAD3_RXD")
	)
	(segment
		(start 11.775948 -256.82321)
		(end 11.775948 -255.662176)
		(width 0.127)
		(layer "In2.Cu")
		(net "T5_BLAD3_RXD")
	)
	(segment
		(start 84.218272 -183.865012)
		(end 85.278214 -182.80507)
		(width 0.127)
		(layer "In2.Cu")
		(net "T5_BLAD3_RXD")
	)
	(segment
		(start 84.218272 -191.253618)
		(end 84.218272 -183.865012)
		(width 0.127)
		(layer "In2.Cu")
		(net "T5_BLAD3_RXD")
	)
	(segment
		(start 83.753452 -231.577134)
		(end 79.20101 -236.129576)
		(width 0.127)
		(layer "In2.Cu")
		(net "T5_BLAD3_RXD")
	)
	(segment
		(start 79.20101 -236.129576)
		(end 79.20101 -246.291608)
		(width 0.127)
		(layer "In2.Cu")
		(net "T5_BLAD3_RXD")
	)
	(segment
		(start 11.775948 -255.662176)
		(end 8.784336 -252.670564)
		(width 0.127)
		(layer "In2.Cu")
		(net "T5_BLAD3_RXD")
	)
	(segment
		(start 85.113876 -202.03033)
		(end 85.113876 -215.314784)
		(width 0.127)
		(layer "In2.Cu")
		(net "T5_BLAD3_RXD")
	)
	(segment
		(start 65.032382 -260.460236)
		(end 47.331884 -260.460236)
		(width 0.127)
		(layer "In2.Cu")
		(net "T5_BLAD3_RXD")
	)
	(segment
		(start 43.307762 -261.553706)
		(end 42.792904 -262.068564)
		(width 0.127)
		(layer "In2.Cu")
		(net "T5_BLAD3_RXD")
	)
	(segment
		(start 85.278214 -182.80507)
		(end 86.910164 -182.80507)
		(width 0.127)
		(layer "In2.Cu")
		(net "T5_BLAD3_RXD")
	)
	(segment
		(start 85.113876 -215.314784)
		(end 83.753452 -216.675208)
		(width 0.127)
		(layer "In2.Cu")
		(net "T5_BLAD3_RXD")
	)
	(segment
		(start 46.238414 -261.553706)
		(end 43.307762 -261.553706)
		(width 0.127)
		(layer "In2.Cu")
		(net "T5_BLAD3_RXD")
	)
	(segment
		(start 84.218272 -201.134726)
		(end 85.113876 -202.03033)
		(width 0.127)
		(layer "In2.Cu")
		(net "T5_BLAD3_RXD")
	)
	(segment
		(start 84.218272 -191.253618)
		(end 84.218272 -201.134726)
		(width 0.127)
		(layer "In2.Cu")
		(net "T5_BLAD3_RXD")
	)
	(segment
		(start 47.331884 -260.460236)
		(end 46.238414 -261.553706)
		(width 0.127)
		(layer "In2.Cu")
		(net "T5_BLAD3_RXD")
	)
	(segment
		(start 83.753452 -216.675208)
		(end 83.753452 -231.577134)
		(width 0.127)
		(layer "In2.Cu")
		(net "T5_BLAD3_RXD")
	)
	(via
		(at 87.403686 -190.959486)
		(size 0.508)
		(drill 0.254)
		(layers "F.Cu" "B.Cu")
		(net "T5_BLAD2_RXD")
	)
	(segment
		(start 86.164674 -215.89492)
		(end 86.164674 -192.198498)
		(width 0.127)
		(layer "In2.Cu")
		(net "T5_BLAD2_RXD")
	)
	(segment
		(start 84.824062 -232.021126)
		(end 84.824062 -217.235532)
		(width 0.127)
		(layer "In2.Cu")
		(net "T5_BLAD2_RXD")
	)
	(segment
		(start 86.164674 -192.198498)
		(end 87.403686 -190.959486)
		(width 0.127)
		(layer "In2.Cu")
		(net "T5_BLAD2_RXD")
	)
	(segment
		(start 8.448802 -254.67056)
		(end 10.296906 -256.518664)
		(width 0.127)
		(layer "In2.Cu")
		(net "T5_BLAD2_RXD")
	)
	(segment
		(start 63.712598 -263.249156)
		(end 80.27162 -246.689626)
		(width 0.127)
		(layer "In2.Cu")
		(net "T5_BLAD2_RXD")
	)
	(segment
		(start 10.296906 -256.518664)
		(end 10.296906 -257.376168)
		(width 0.127)
		(layer "In2.Cu")
		(net "T5_BLAD2_RXD")
	)
	(segment
		(start 16.169894 -263.249156)
		(end 63.712598 -263.249156)
		(width 0.127)
		(layer "In2.Cu")
		(net "T5_BLAD2_RXD")
	)
	(segment
		(start 84.824062 -217.235532)
		(end 86.164674 -215.89492)
		(width 0.127)
		(layer "In2.Cu")
		(net "T5_BLAD2_RXD")
	)
	(segment
		(start 80.27162 -246.689626)
		(end 80.27162 -236.573568)
		(width 0.127)
		(layer "In2.Cu")
		(net "T5_BLAD2_RXD")
	)
	(segment
		(start 10.296906 -257.376168)
		(end 16.169894 -263.249156)
		(width 0.127)
		(layer "In2.Cu")
		(net "T5_BLAD2_RXD")
	)
	(segment
		(start 87.403686 -190.959486)
		(end 87.403686 -190.532258)
		(width 0.127)
		(layer "In2.Cu")
		(net "T5_BLAD2_RXD")
	)
	(segment
		(start 90.536522 -187.894468)
		(end 91.990164 -186.440826)
		(width 0.127)
		(layer "In2.Cu")
		(net "T5_BLAD2_RXD")
	)
	(segment
		(start 80.27162 -236.573568)
		(end 84.824062 -232.021126)
		(width 0.127)
		(layer "In2.Cu")
		(net "T5_BLAD2_RXD")
	)
	(segment
		(start 87.403686 -190.532258)
		(end 90.041476 -187.894468)
		(width 0.127)
		(layer "In2.Cu")
		(net "T5_BLAD2_RXD")
	)
	(segment
		(start 90.041476 -187.894468)
		(end 90.536522 -187.894468)
		(width 0.127)
		(layer "In2.Cu")
		(net "T5_BLAD2_RXD")
	)
	(segment
		(start 91.990164 -186.440826)
		(end 91.990164 -185.34507)
		(width 0.127)
		(layer "In2.Cu")
		(net "T5_BLAD2_RXD")
	)
	(via
		(at 92.094558 -191.206882)
		(size 0.508)
		(drill 0.254)
		(layers "F.Cu" "B.Cu")
		(net "T5_BLAD1_TXD")
	)
	(segment
		(start 62.531244 -264.778998)
		(end 79.34198 -247.968262)
		(width 0.127)
		(layer "In5.Cu")
		(net "T5_BLAD1_TXD")
	)
	(segment
		(start 16.557244 -264.778998)
		(end 62.531244 -264.778998)
		(width 0.127)
		(layer "In5.Cu")
		(net "T5_BLAD1_TXD")
	)
	(segment
		(start 79.34198 -247.968262)
		(end 93.248734 -247.968262)
		(width 0.127)
		(layer "In5.Cu")
		(net "T5_BLAD1_TXD")
	)
	(segment
		(start 88.69045 -190.503302)
		(end 85.640164 -187.453016)
		(width 0.127)
		(layer "In5.Cu")
		(net "T5_BLAD1_TXD")
	)
	(segment
		(start 99.489514 -241.727482)
		(end 99.489514 -198.601838)
		(width 0.127)
		(layer "In5.Cu")
		(net "T5_BLAD1_TXD")
	)
	(segment
		(start 93.248734 -247.968262)
		(end 99.489514 -241.727482)
		(width 0.127)
		(layer "In5.Cu")
		(net "T5_BLAD1_TXD")
	)
	(segment
		(start 99.489514 -198.601838)
		(end 92.094558 -191.206882)
		(width 0.127)
		(layer "In5.Cu")
		(net "T5_BLAD1_TXD")
	)
	(segment
		(start 85.640164 -187.453016)
		(end 85.640164 -186.61507)
		(width 0.127)
		(layer "In5.Cu")
		(net "T5_BLAD1_TXD")
	)
	(segment
		(start 92.094558 -191.206882)
		(end 91.390978 -190.503302)
		(width 0.127)
		(layer "In5.Cu")
		(net "T5_BLAD1_TXD")
	)
	(segment
		(start 8.448802 -256.670556)
		(end 16.557244 -264.778998)
		(width 0.127)
		(layer "In5.Cu")
		(net "T5_BLAD1_TXD")
	)
	(segment
		(start 91.390978 -190.503302)
		(end 88.69045 -190.503302)
		(width 0.127)
		(layer "In5.Cu")
		(net "T5_BLAD1_TXD")
	)
	(via
		(at 81.37652 -146.428714)
		(size 0.508)
		(drill 0.254)
		(layers "F.Cu" "B.Cu")
		(net "T4_BLAD1_TXD")
	)
	(segment
		(start 7.010654 -242.398804)
		(end 8.124952 -243.513102)
		(width 0.127)
		(layer "In2.Cu")
		(net "T4_BLAD1_TXD")
	)
	(segment
		(start 81.37652 -146.428714)
		(end 85.640164 -142.16507)
		(width 0.127)
		(layer "In2.Cu")
		(net "T4_BLAD1_TXD")
	)
	(segment
		(start 31.083758 -177.839624)
		(end 59.31789 -177.839624)
		(width 0.127)
		(layer "In2.Cu")
		(net "T4_BLAD1_TXD")
	)
	(segment
		(start 3.13309 -242.398804)
		(end 7.010654 -242.398804)
		(width 0.127)
		(layer "In2.Cu")
		(net "T4_BLAD1_TXD")
	)
	(segment
		(start 1.948942 -242.670584)
		(end 2.86131 -242.670584)
		(width 0.127)
		(layer "In2.Cu")
		(net "T4_BLAD1_TXD")
	)
	(segment
		(start 2.86131 -242.670584)
		(end 3.13309 -242.398804)
		(width 0.127)
		(layer "In2.Cu")
		(net "T4_BLAD1_TXD")
	)
	(segment
		(start 23.082504 -192.3161)
		(end 23.082504 -185.840878)
		(width 0.127)
		(layer "In2.Cu")
		(net "T4_BLAD1_TXD")
	)
	(segment
		(start 9.033764 -243.513102)
		(end 26.311606 -226.23526)
		(width 0.127)
		(layer "In2.Cu")
		(net "T4_BLAD1_TXD")
	)
	(segment
		(start 59.31789 -177.839624)
		(end 79.631794 -157.52572)
		(width 0.127)
		(layer "In2.Cu")
		(net "T4_BLAD1_TXD")
	)
	(segment
		(start 26.311606 -195.545202)
		(end 23.082504 -192.3161)
		(width 0.127)
		(layer "In2.Cu")
		(net "T4_BLAD1_TXD")
	)
	(segment
		(start 23.082504 -185.840878)
		(end 31.083758 -177.839624)
		(width 0.127)
		(layer "In2.Cu")
		(net "T4_BLAD1_TXD")
	)
	(segment
		(start 8.124952 -243.513102)
		(end 9.033764 -243.513102)
		(width 0.127)
		(layer "In2.Cu")
		(net "T4_BLAD1_TXD")
	)
	(segment
		(start 26.311606 -226.23526)
		(end 26.311606 -195.545202)
		(width 0.127)
		(layer "In2.Cu")
		(net "T4_BLAD1_TXD")
	)
	(segment
		(start 79.631794 -148.17344)
		(end 81.37652 -146.428714)
		(width 0.127)
		(layer "In2.Cu")
		(net "T4_BLAD1_TXD")
	)
	(segment
		(start 79.631794 -157.52572)
		(end 79.631794 -148.17344)
		(width 0.127)
		(layer "In2.Cu")
		(net "T4_BLAD1_TXD")
	)
	(via
		(at 87.0966 -147.352004)
		(size 0.508)
		(drill 0.254)
		(layers "F.Cu" "B.Cu")
		(net "T4_BLAD2_RXD")
	)
	(segment
		(start 85.296248 -152.5397)
		(end 84.307172 -152.5397)
		(width 0.127)
		(layer "In5.Cu")
		(net "T4_BLAD2_RXD")
	)
	(segment
		(start 86.144354 -151.691594)
		(end 85.296248 -152.5397)
		(width 0.127)
		(layer "In5.Cu")
		(net "T4_BLAD2_RXD")
	)
	(segment
		(start 7.981442 -237.928912)
		(end 7.01167 -238.898684)
		(width 0.127)
		(layer "In5.Cu")
		(net "T4_BLAD2_RXD")
	)
	(segment
		(start 20.424394 -236.193076)
		(end 18.688558 -237.928912)
		(width 0.127)
		(layer "In5.Cu")
		(net "T4_BLAD2_RXD")
	)
	(segment
		(start 28.03652 -176.943512)
		(end 23.088346 -181.891686)
		(width 0.127)
		(layer "In5.Cu")
		(net "T4_BLAD2_RXD")
	)
	(segment
		(start 6.110986 -238.898684)
		(end 5.1308 -239.87887)
		(width 0.127)
		(layer "In5.Cu")
		(net "T4_BLAD2_RXD")
	)
	(segment
		(start 23.088346 -181.891686)
		(end 23.088346 -198.111872)
		(width 0.127)
		(layer "In5.Cu")
		(net "T4_BLAD2_RXD")
	)
	(segment
		(start 91.990164 -142.45844)
		(end 87.0966 -147.352004)
		(width 0.127)
		(layer "In5.Cu")
		(net "T4_BLAD2_RXD")
	)
	(segment
		(start 23.088346 -198.111872)
		(end 26.100024 -201.12355)
		(width 0.127)
		(layer "In5.Cu")
		(net "T4_BLAD2_RXD")
	)
	(segment
		(start 7.01167 -238.898684)
		(end 6.110986 -238.898684)
		(width 0.127)
		(layer "In5.Cu")
		(net "T4_BLAD2_RXD")
	)
	(segment
		(start 26.100024 -217.43797)
		(end 22.0853 -221.452694)
		(width 0.127)
		(layer "In5.Cu")
		(net "T4_BLAD2_RXD")
	)
	(segment
		(start 91.990164 -140.89507)
		(end 91.990164 -142.45844)
		(width 0.127)
		(layer "In5.Cu")
		(net "T4_BLAD2_RXD")
	)
	(segment
		(start 5.1308 -240.488724)
		(end 3.948938 -241.670586)
		(width 0.127)
		(layer "In5.Cu")
		(net "T4_BLAD2_RXD")
	)
	(segment
		(start 5.1308 -239.87887)
		(end 5.1308 -240.488724)
		(width 0.127)
		(layer "In5.Cu")
		(net "T4_BLAD2_RXD")
	)
	(segment
		(start 86.144354 -148.30425)
		(end 86.144354 -151.691594)
		(width 0.127)
		(layer "In5.Cu")
		(net "T4_BLAD2_RXD")
	)
	(segment
		(start 22.0853 -221.452694)
		(end 22.0853 -233.180128)
		(width 0.127)
		(layer "In5.Cu")
		(net "T4_BLAD2_RXD")
	)
	(segment
		(start 26.100024 -201.12355)
		(end 26.100024 -217.43797)
		(width 0.127)
		(layer "In5.Cu")
		(net "T4_BLAD2_RXD")
	)
	(segment
		(start 18.688558 -237.928912)
		(end 7.981442 -237.928912)
		(width 0.127)
		(layer "In5.Cu")
		(net "T4_BLAD2_RXD")
	)
	(segment
		(start 22.0853 -233.180128)
		(end 20.424394 -234.841034)
		(width 0.127)
		(layer "In5.Cu")
		(net "T4_BLAD2_RXD")
	)
	(segment
		(start 20.424394 -234.841034)
		(end 20.424394 -236.193076)
		(width 0.127)
		(layer "In5.Cu")
		(net "T4_BLAD2_RXD")
	)
	(segment
		(start 87.0966 -147.352004)
		(end 86.144354 -148.30425)
		(width 0.127)
		(layer "In5.Cu")
		(net "T4_BLAD2_RXD")
	)
	(segment
		(start 84.307172 -152.5397)
		(end 59.90336 -176.943512)
		(width 0.127)
		(layer "In5.Cu")
		(net "T4_BLAD2_RXD")
	)
	(segment
		(start 59.90336 -176.943512)
		(end 28.03652 -176.943512)
		(width 0.127)
		(layer "In5.Cu")
		(net "T4_BLAD2_RXD")
	)
	(via
		(at 81.722468 -152.156414)
		(size 0.508)
		(drill 0.254)
		(layers "F.Cu" "B.Cu")
		(net "T4_BLAD1_EN")
	)
	(segment
		(start 9.686798 -246.96928)
		(end 9.235186 -247.420892)
		(width 0.127)
		(layer "In2.Cu")
		(net "T4_BLAD1_EN")
	)
	(segment
		(start 81.722468 -149.168104)
		(end 81.722468 -152.156414)
		(width 0.127)
		(layer "In2.Cu")
		(net "T4_BLAD1_EN")
	)
	(segment
		(start 88.180164 -142.16507)
		(end 88.180164 -142.710408)
		(width 0.127)
		(layer "In2.Cu")
		(net "T4_BLAD1_EN")
	)
	(segment
		(start 27.669998 -227.532692)
		(end 9.686798 -245.515892)
		(width 0.127)
		(layer "In2.Cu")
		(net "T4_BLAD1_EN")
	)
	(segment
		(start 4.224274 -246.39524)
		(end 1.948942 -248.670572)
		(width 0.127)
		(layer "In2.Cu")
		(net "T4_BLAD1_EN")
	)
	(segment
		(start 81.722468 -152.156414)
		(end 81.722468 -156.91358)
		(width 0.127)
		(layer "In2.Cu")
		(net "T4_BLAD1_EN")
	)
	(segment
		(start 81.722468 -156.91358)
		(end 59.387486 -179.248562)
		(width 0.127)
		(layer "In2.Cu")
		(net "T4_BLAD1_EN")
	)
	(segment
		(start 9.235186 -247.420892)
		(end 7.96671 -247.420892)
		(width 0.127)
		(layer "In2.Cu")
		(net "T4_BLAD1_EN")
	)
	(segment
		(start 7.96671 -247.420892)
		(end 6.941058 -246.39524)
		(width 0.127)
		(layer "In2.Cu")
		(net "T4_BLAD1_EN")
	)
	(segment
		(start 88.180164 -142.710408)
		(end 81.722468 -149.168104)
		(width 0.127)
		(layer "In2.Cu")
		(net "T4_BLAD1_EN")
	)
	(segment
		(start 9.686798 -245.515892)
		(end 9.686798 -246.96928)
		(width 0.127)
		(layer "In2.Cu")
		(net "T4_BLAD1_EN")
	)
	(segment
		(start 6.941058 -246.39524)
		(end 4.224274 -246.39524)
		(width 0.127)
		(layer "In2.Cu")
		(net "T4_BLAD1_EN")
	)
	(segment
		(start 27.669998 -182.741824)
		(end 27.669998 -227.532692)
		(width 0.127)
		(layer "In2.Cu")
		(net "T4_BLAD1_EN")
	)
	(segment
		(start 31.16326 -179.248562)
		(end 27.669998 -182.741824)
		(width 0.127)
		(layer "In2.Cu")
		(net "T4_BLAD1_EN")
	)
	(segment
		(start 59.387486 -179.248562)
		(end 31.16326 -179.248562)
		(width 0.127)
		(layer "In2.Cu")
		(net "T4_BLAD1_EN")
	)
	(segment
		(start 35.53968 -464.369912)
		(end 39.535862 -464.369912)
		(width 0.508)
		(layer "F.Cu")
		(net "PSU6_REMOTE_P")
	)
	(segment
		(start 39.535862 -464.369912)
		(end 39.536624 -464.36915)
		(width 0.508)
		(layer "F.Cu")
		(net "PSU6_REMOTE_P")
	)
	(via
		(at 84.7725 -151.212804)
		(size 0.508)
		(drill 0.254)
		(layers "F.Cu" "B.Cu")
		(net "T4_BLAD3_TXD")
	)
	(segment
		(start 84.7725 -140.492734)
		(end 85.640164 -139.62507)
		(width 0.127)
		(layer "In5.Cu")
		(net "T4_BLAD3_TXD")
	)
	(segment
		(start 27.799284 -175.778922)
		(end 21.976842 -181.601364)
		(width 0.127)
		(layer "In5.Cu")
		(net "T4_BLAD3_TXD")
	)
	(segment
		(start 84.572856 -151.412448)
		(end 84.032598 -151.412448)
		(width 0.127)
		(layer "In5.Cu")
		(net "T4_BLAD3_TXD")
	)
	(segment
		(start 25.011634 -216.717626)
		(end 21.0947 -220.63456)
		(width 0.127)
		(layer "In5.Cu")
		(net "T4_BLAD3_TXD")
	)
	(segment
		(start 6.862318 -236.57306)
		(end 6.018276 -236.57306)
		(width 0.127)
		(layer "In5.Cu")
		(net "T4_BLAD3_TXD")
	)
	(segment
		(start 21.0947 -232.610406)
		(end 18.144998 -235.560108)
		(width 0.127)
		(layer "In5.Cu")
		(net "T4_BLAD3_TXD")
	)
	(segment
		(start 6.018276 -236.57306)
		(end 4.923536 -237.6678)
		(width 0.127)
		(layer "In5.Cu")
		(net "T4_BLAD3_TXD")
	)
	(segment
		(start 4.923536 -237.6678)
		(end 3.951732 -237.6678)
		(width 0.127)
		(layer "In5.Cu")
		(net "T4_BLAD3_TXD")
	)
	(segment
		(start 3.951732 -237.6678)
		(end 3.948938 -237.670594)
		(width 0.127)
		(layer "In5.Cu")
		(net "T4_BLAD3_TXD")
	)
	(segment
		(start 84.7725 -151.212804)
		(end 84.572856 -151.412448)
		(width 0.127)
		(layer "In5.Cu")
		(net "T4_BLAD3_TXD")
	)
	(segment
		(start 59.666124 -175.778922)
		(end 27.799284 -175.778922)
		(width 0.127)
		(layer "In5.Cu")
		(net "T4_BLAD3_TXD")
	)
	(segment
		(start 7.87527 -235.560108)
		(end 6.862318 -236.57306)
		(width 0.127)
		(layer "In5.Cu")
		(net "T4_BLAD3_TXD")
	)
	(segment
		(start 84.7725 -151.212804)
		(end 84.7725 -140.492734)
		(width 0.127)
		(layer "In5.Cu")
		(net "T4_BLAD3_TXD")
	)
	(segment
		(start 21.0947 -220.63456)
		(end 21.0947 -232.610406)
		(width 0.127)
		(layer "In5.Cu")
		(net "T4_BLAD3_TXD")
	)
	(segment
		(start 21.976842 -198.549768)
		(end 25.011634 -201.58456)
		(width 0.127)
		(layer "In5.Cu")
		(net "T4_BLAD3_TXD")
	)
	(segment
		(start 25.011634 -201.58456)
		(end 25.011634 -216.717626)
		(width 0.127)
		(layer "In5.Cu")
		(net "T4_BLAD3_TXD")
	)
	(segment
		(start 21.976842 -181.601364)
		(end 21.976842 -198.549768)
		(width 0.127)
		(layer "In5.Cu")
		(net "T4_BLAD3_TXD")
	)
	(segment
		(start 18.144998 -235.560108)
		(end 7.87527 -235.560108)
		(width 0.127)
		(layer "In5.Cu")
		(net "T4_BLAD3_TXD")
	)
	(segment
		(start 84.032598 -151.412448)
		(end 59.666124 -175.778922)
		(width 0.127)
		(layer "In5.Cu")
		(net "T4_BLAD3_TXD")
	)
	(via
		(at 85.696298 -148.90242)
		(size 0.508)
		(drill 0.254)
		(layers "F.Cu" "B.Cu")
		(net "T4_BLAD2_TXD")
	)
	(segment
		(start 25.735026 -201.23531)
		(end 22.749256 -198.24954)
		(width 0.127)
		(layer "In5.Cu")
		(net "T4_BLAD2_TXD")
	)
	(segment
		(start 84.19719 -152.182322)
		(end 85.177122 -152.182322)
		(width 0.127)
		(layer "In5.Cu")
		(net "T4_BLAD2_TXD")
	)
	(segment
		(start 59.800998 -176.578514)
		(end 84.19719 -152.182322)
		(width 0.127)
		(layer "In5.Cu")
		(net "T4_BLAD2_TXD")
	)
	(segment
		(start 21.7551 -232.993946)
		(end 21.7551 -221.266512)
		(width 0.127)
		(layer "In5.Cu")
		(net "T4_BLAD2_TXD")
	)
	(segment
		(start 85.696298 -151.663146)
		(end 85.696298 -148.90242)
		(width 0.127)
		(layer "In5.Cu")
		(net "T4_BLAD2_TXD")
	)
	(segment
		(start 22.749256 -181.763416)
		(end 27.934158 -176.578514)
		(width 0.127)
		(layer "In5.Cu")
		(net "T4_BLAD2_TXD")
	)
	(segment
		(start 85.696298 -148.90242)
		(end 85.696298 -147.864576)
		(width 0.127)
		(layer "In5.Cu")
		(net "T4_BLAD2_TXD")
	)
	(segment
		(start 20.059396 -234.68965)
		(end 21.7551 -232.993946)
		(width 0.127)
		(layer "In5.Cu")
		(net "T4_BLAD2_TXD")
	)
	(segment
		(start 4.688586 -239.804702)
		(end 5.959602 -238.533686)
		(width 0.127)
		(layer "In5.Cu")
		(net "T4_BLAD2_TXD")
	)
	(segment
		(start 90.720164 -142.84071)
		(end 90.720164 -142.16507)
		(width 0.127)
		(layer "In5.Cu")
		(net "T4_BLAD2_TXD")
	)
	(segment
		(start 7.841996 -237.563914)
		(end 18.537174 -237.563914)
		(width 0.127)
		(layer "In5.Cu")
		(net "T4_BLAD2_TXD")
	)
	(segment
		(start 85.696298 -147.864576)
		(end 90.720164 -142.84071)
		(width 0.127)
		(layer "In5.Cu")
		(net "T4_BLAD2_TXD")
	)
	(segment
		(start 18.537174 -237.563914)
		(end 20.059396 -236.041692)
		(width 0.127)
		(layer "In5.Cu")
		(net "T4_BLAD2_TXD")
	)
	(segment
		(start 5.959602 -238.533686)
		(end 6.872224 -238.533686)
		(width 0.127)
		(layer "In5.Cu")
		(net "T4_BLAD2_TXD")
	)
	(segment
		(start 27.934158 -176.578514)
		(end 59.800998 -176.578514)
		(width 0.127)
		(layer "In5.Cu")
		(net "T4_BLAD2_TXD")
	)
	(segment
		(start 20.059396 -236.041692)
		(end 20.059396 -234.68965)
		(width 0.127)
		(layer "In5.Cu")
		(net "T4_BLAD2_TXD")
	)
	(segment
		(start 22.749256 -198.24954)
		(end 22.749256 -181.763416)
		(width 0.127)
		(layer "In5.Cu")
		(net "T4_BLAD2_TXD")
	)
	(segment
		(start 85.177122 -152.182322)
		(end 85.696298 -151.663146)
		(width 0.127)
		(layer "In5.Cu")
		(net "T4_BLAD2_TXD")
	)
	(segment
		(start 21.7551 -221.266512)
		(end 25.735026 -217.286586)
		(width 0.127)
		(layer "In5.Cu")
		(net "T4_BLAD2_TXD")
	)
	(segment
		(start 4.262374 -240.667794)
		(end 4.688586 -240.241582)
		(width 0.127)
		(layer "In5.Cu")
		(net "T4_BLAD2_TXD")
	)
	(segment
		(start 1.951736 -240.667794)
		(end 4.262374 -240.667794)
		(width 0.127)
		(layer "In5.Cu")
		(net "T4_BLAD2_TXD")
	)
	(segment
		(start 25.735026 -217.286586)
		(end 25.735026 -201.23531)
		(width 0.127)
		(layer "In5.Cu")
		(net "T4_BLAD2_TXD")
	)
	(segment
		(start 4.688586 -240.241582)
		(end 4.688586 -239.804702)
		(width 0.127)
		(layer "In5.Cu")
		(net "T4_BLAD2_TXD")
	)
	(segment
		(start 1.948942 -240.670588)
		(end 1.951736 -240.667794)
		(width 0.127)
		(layer "In5.Cu")
		(net "T4_BLAD2_TXD")
	)
	(segment
		(start 6.872224 -238.533686)
		(end 7.841996 -237.563914)
		(width 0.127)
		(layer "In5.Cu")
		(net "T4_BLAD2_TXD")
	)
	(segment
		(start 39.738808 -457.408534)
		(end 39.738808 -456.76185)
		(width 0.1524)
		(layer "F.Cu")
		(net "PSU6_RETURN")
	)
	(segment
		(start 39.738808 -456.76185)
		(end 37.18687 -454.209912)
		(width 0.1524)
		(layer "F.Cu")
		(net "PSU6_RETURN")
	)
	(segment
		(start 39.54526 -458.70876)
		(end 39.738808 -458.515212)
		(width 0.1524)
		(layer "F.Cu")
		(net "PSU6_RETURN")
	)
	(segment
		(start 39.738808 -458.515212)
		(end 39.738808 -457.408534)
		(width 0.1524)
		(layer "F.Cu")
		(net "PSU6_RETURN")
	)
	(segment
		(start 39.54526 -459.16596)
		(end 39.54526 -458.70876)
		(width 0.1524)
		(layer "F.Cu")
		(net "PSU6_RETURN")
	)
	(segment
		(start 37.18687 -454.209912)
		(end 35.53968 -454.209912)
		(width 0.1524)
		(layer "F.Cu")
		(net "PSU6_RETURN")
	)
	(via
		(at 39.738808 -457.408534)
		(size 0.508)
		(drill 0.254)
		(layers "F.Cu" "B.Cu")
		(net "PSU6_RETURN")
	)
	(via
		(at 84.294218 -149.81174)
		(size 0.508)
		(drill 0.254)
		(layers "F.Cu" "B.Cu")
		(net "T4_BLAD4_RXD")
	)
	(segment
		(start 4.220972 -236.670596)
		(end 1.948942 -236.670596)
		(width 0.127)
		(layer "In5.Cu")
		(net "T4_BLAD4_RXD")
	)
	(segment
		(start 84.294218 -149.81174)
		(end 84.294218 -150.683722)
		(width 0.127)
		(layer "In5.Cu")
		(net "T4_BLAD4_RXD")
	)
	(segment
		(start 24.572468 -201.63028)
		(end 24.572468 -216.622376)
		(width 0.127)
		(layer "In5.Cu")
		(net "T4_BLAD4_RXD")
	)
	(segment
		(start 84.294218 -150.683722)
		(end 59.561984 -175.415956)
		(width 0.127)
		(layer "In5.Cu")
		(net "T4_BLAD4_RXD")
	)
	(segment
		(start 21.237956 -181.87289)
		(end 21.237956 -198.295768)
		(width 0.127)
		(layer "In5.Cu")
		(net "T4_BLAD4_RXD")
	)
	(segment
		(start 84.294218 -139.427458)
		(end 84.294218 -149.81174)
		(width 0.127)
		(layer "In5.Cu")
		(net "T4_BLAD4_RXD")
	)
	(segment
		(start 91.990164 -138.35507)
		(end 90.973402 -137.338308)
		(width 0.127)
		(layer "In5.Cu")
		(net "T4_BLAD4_RXD")
	)
	(segment
		(start 6.004814 -234.886754)
		(end 4.220972 -236.670596)
		(width 0.127)
		(layer "In5.Cu")
		(net "T4_BLAD4_RXD")
	)
	(segment
		(start 90.973402 -137.338308)
		(end 86.383368 -137.338308)
		(width 0.127)
		(layer "In5.Cu")
		(net "T4_BLAD4_RXD")
	)
	(segment
		(start 19.327114 -233.777536)
		(end 8.328406 -233.777536)
		(width 0.127)
		(layer "In5.Cu")
		(net "T4_BLAD4_RXD")
	)
	(segment
		(start 20.7645 -232.34015)
		(end 19.327114 -233.777536)
		(width 0.127)
		(layer "In5.Cu")
		(net "T4_BLAD4_RXD")
	)
	(segment
		(start 27.69489 -175.415956)
		(end 21.237956 -181.87289)
		(width 0.127)
		(layer "In5.Cu")
		(net "T4_BLAD4_RXD")
	)
	(segment
		(start 8.328406 -233.777536)
		(end 7.219188 -234.886754)
		(width 0.127)
		(layer "In5.Cu")
		(net "T4_BLAD4_RXD")
	)
	(segment
		(start 20.7645 -220.430344)
		(end 20.7645 -232.34015)
		(width 0.127)
		(layer "In5.Cu")
		(net "T4_BLAD4_RXD")
	)
	(segment
		(start 59.561984 -175.415956)
		(end 27.69489 -175.415956)
		(width 0.127)
		(layer "In5.Cu")
		(net "T4_BLAD4_RXD")
	)
	(segment
		(start 86.383368 -137.338308)
		(end 84.294218 -139.427458)
		(width 0.127)
		(layer "In5.Cu")
		(net "T4_BLAD4_RXD")
	)
	(segment
		(start 24.572468 -216.622376)
		(end 20.7645 -220.430344)
		(width 0.127)
		(layer "In5.Cu")
		(net "T4_BLAD4_RXD")
	)
	(segment
		(start 7.219188 -234.886754)
		(end 6.004814 -234.886754)
		(width 0.127)
		(layer "In5.Cu")
		(net "T4_BLAD4_RXD")
	)
	(segment
		(start 21.237956 -198.295768)
		(end 24.572468 -201.63028)
		(width 0.127)
		(layer "In5.Cu")
		(net "T4_BLAD4_RXD")
	)
	(via
		(at 80.701896 -149.4155)
		(size 0.508)
		(drill 0.254)
		(layers "F.Cu" "B.Cu")
		(net "T4_BLAD1_RXD")
	)
	(segment
		(start 9.28243 -245.369334)
		(end 8.076692 -245.369334)
		(width 0.127)
		(layer "In2.Cu")
		(net "T4_BLAD1_RXD")
	)
	(segment
		(start 4.735322 -244.456966)
		(end 3.948938 -243.670582)
		(width 0.127)
		(layer "In2.Cu")
		(net "T4_BLAD1_RXD")
	)
	(segment
		(start 25.922732 -183.978042)
		(end 25.922732 -194.07632)
		(width 0.127)
		(layer "In2.Cu")
		(net "T4_BLAD1_RXD")
	)
	(segment
		(start 7.164324 -244.456966)
		(end 4.735322 -244.456966)
		(width 0.127)
		(layer "In2.Cu")
		(net "T4_BLAD1_RXD")
	)
	(segment
		(start 59.603894 -178.529488)
		(end 31.371286 -178.529488)
		(width 0.127)
		(layer "In2.Cu")
		(net "T4_BLAD1_RXD")
	)
	(segment
		(start 8.076692 -245.369334)
		(end 7.164324 -244.456966)
		(width 0.127)
		(layer "In2.Cu")
		(net "T4_BLAD1_RXD")
	)
	(segment
		(start 31.371286 -178.529488)
		(end 25.922732 -183.978042)
		(width 0.127)
		(layer "In2.Cu")
		(net "T4_BLAD1_RXD")
	)
	(segment
		(start 25.922732 -194.07632)
		(end 27.009598 -195.163186)
		(width 0.127)
		(layer "In2.Cu")
		(net "T4_BLAD1_RXD")
	)
	(segment
		(start 80.701896 -148.918168)
		(end 86.910164 -142.7099)
		(width 0.127)
		(layer "In2.Cu")
		(net "T4_BLAD1_RXD")
	)
	(segment
		(start 27.009598 -227.642166)
		(end 9.28243 -245.369334)
		(width 0.127)
		(layer "In2.Cu")
		(net "T4_BLAD1_RXD")
	)
	(segment
		(start 80.701896 -149.4155)
		(end 80.701896 -157.431486)
		(width 0.127)
		(layer "In2.Cu")
		(net "T4_BLAD1_RXD")
	)
	(segment
		(start 80.701896 -157.431486)
		(end 59.603894 -178.529488)
		(width 0.127)
		(layer "In2.Cu")
		(net "T4_BLAD1_RXD")
	)
	(segment
		(start 86.910164 -142.7099)
		(end 86.910164 -140.89507)
		(width 0.127)
		(layer "In2.Cu")
		(net "T4_BLAD1_RXD")
	)
	(segment
		(start 27.009598 -195.163186)
		(end 27.009598 -227.642166)
		(width 0.127)
		(layer "In2.Cu")
		(net "T4_BLAD1_RXD")
	)
	(segment
		(start 80.701896 -149.4155)
		(end 80.701896 -148.918168)
		(width 0.127)
		(layer "In2.Cu")
		(net "T4_BLAD1_RXD")
	)
	(via
		(at 83.727544 -148.51761)
		(size 0.508)
		(drill 0.254)
		(layers "F.Cu" "B.Cu")
		(net "T4_BLAD4_TXD")
	)
	(segment
		(start 20.576286 -182.067454)
		(end 20.576286 -198.247508)
		(width 0.127)
		(layer "In5.Cu")
		(net "T4_BLAD4_TXD")
	)
	(segment
		(start 19.185382 -233.435398)
		(end 8.117332 -233.435398)
		(width 0.127)
		(layer "In5.Cu")
		(net "T4_BLAD4_TXD")
	)
	(segment
		(start 7.008114 -234.544616)
		(end 5.863082 -234.544616)
		(width 0.127)
		(layer "In5.Cu")
		(net "T4_BLAD4_TXD")
	)
	(segment
		(start 91.095576 -139.249658)
		(end 92.465144 -139.249658)
		(width 0.127)
		(layer "In5.Cu")
		(net "T4_BLAD4_TXD")
	)
	(segment
		(start 83.727544 -150.782274)
		(end 59.436 -175.073818)
		(width 0.127)
		(layer "In5.Cu")
		(net "T4_BLAD4_TXD")
	)
	(segment
		(start 8.117332 -233.435398)
		(end 7.008114 -234.544616)
		(width 0.127)
		(layer "In5.Cu")
		(net "T4_BLAD4_TXD")
	)
	(segment
		(start 24.23033 -216.480644)
		(end 20.2438 -220.467174)
		(width 0.127)
		(layer "In5.Cu")
		(net "T4_BLAD4_TXD")
	)
	(segment
		(start 83.727544 -139.277598)
		(end 83.727544 -148.51761)
		(width 0.127)
		(layer "In5.Cu")
		(net "T4_BLAD4_TXD")
	)
	(segment
		(start 5.863082 -234.544616)
		(end 4.7371 -235.670598)
		(width 0.127)
		(layer "In5.Cu")
		(net "T4_BLAD4_TXD")
	)
	(segment
		(start 24.23033 -201.901552)
		(end 24.23033 -216.480644)
		(width 0.127)
		(layer "In5.Cu")
		(net "T4_BLAD4_TXD")
	)
	(segment
		(start 83.727544 -148.51761)
		(end 83.727544 -150.782274)
		(width 0.127)
		(layer "In5.Cu")
		(net "T4_BLAD4_TXD")
	)
	(segment
		(start 92.836492 -137.977118)
		(end 91.855544 -136.99617)
		(width 0.127)
		(layer "In5.Cu")
		(net "T4_BLAD4_TXD")
	)
	(segment
		(start 90.720164 -139.62507)
		(end 91.095576 -139.249658)
		(width 0.127)
		(layer "In5.Cu")
		(net "T4_BLAD4_TXD")
	)
	(segment
		(start 92.465144 -139.249658)
		(end 92.836492 -138.87831)
		(width 0.127)
		(layer "In5.Cu")
		(net "T4_BLAD4_TXD")
	)
	(segment
		(start 20.2438 -232.37698)
		(end 19.185382 -233.435398)
		(width 0.127)
		(layer "In5.Cu")
		(net "T4_BLAD4_TXD")
	)
	(segment
		(start 92.836492 -138.87831)
		(end 92.836492 -137.977118)
		(width 0.127)
		(layer "In5.Cu")
		(net "T4_BLAD4_TXD")
	)
	(segment
		(start 27.569922 -175.073818)
		(end 20.576286 -182.067454)
		(width 0.127)
		(layer "In5.Cu")
		(net "T4_BLAD4_TXD")
	)
	(segment
		(start 20.2438 -220.467174)
		(end 20.2438 -232.37698)
		(width 0.127)
		(layer "In5.Cu")
		(net "T4_BLAD4_TXD")
	)
	(segment
		(start 4.7371 -235.670598)
		(end 3.948938 -235.670598)
		(width 0.127)
		(layer "In5.Cu")
		(net "T4_BLAD4_TXD")
	)
	(segment
		(start 86.008972 -136.99617)
		(end 83.727544 -139.277598)
		(width 0.127)
		(layer "In5.Cu")
		(net "T4_BLAD4_TXD")
	)
	(segment
		(start 91.855544 -136.99617)
		(end 86.008972 -136.99617)
		(width 0.127)
		(layer "In5.Cu")
		(net "T4_BLAD4_TXD")
	)
	(segment
		(start 59.436 -175.073818)
		(end 27.569922 -175.073818)
		(width 0.127)
		(layer "In5.Cu")
		(net "T4_BLAD4_TXD")
	)
	(segment
		(start 20.576286 -198.247508)
		(end 24.23033 -201.901552)
		(width 0.127)
		(layer "In5.Cu")
		(net "T4_BLAD4_TXD")
	)
	(via
		(at 81.10347 -147.856194)
		(size 0.508)
		(drill 0.254)
		(layers "F.Cu" "B.Cu")
		(net "T4_BLAD3_EN")
	)
	(segment
		(start 26.653744 -195.366386)
		(end 26.653744 -226.444302)
		(width 0.127)
		(layer "In2.Cu")
		(net "T4_BLAD3_EN")
	)
	(segment
		(start 9.2075 -243.890546)
		(end 7.968488 -243.890546)
		(width 0.127)
		(layer "In2.Cu")
		(net "T4_BLAD3_EN")
	)
	(segment
		(start 7.968488 -243.890546)
		(end 6.935724 -242.857782)
		(width 0.127)
		(layer "In2.Cu")
		(net "T4_BLAD3_EN")
	)
	(segment
		(start 25.559004 -194.271646)
		(end 26.653744 -195.366386)
		(width 0.127)
		(layer "In2.Cu")
		(net "T4_BLAD3_EN")
	)
	(segment
		(start 2.864612 -243.41582)
		(end 2.864612 -245.754906)
		(width 0.127)
		(layer "In2.Cu")
		(net "T4_BLAD3_EN")
	)
	(segment
		(start 86.889082 -139.62507)
		(end 88.180164 -139.62507)
		(width 0.127)
		(layer "In2.Cu")
		(net "T4_BLAD3_EN")
	)
	(segment
		(start 59.460638 -178.183794)
		(end 31.24073 -178.183794)
		(width 0.127)
		(layer "In2.Cu")
		(net "T4_BLAD3_EN")
	)
	(segment
		(start 31.24073 -178.183794)
		(end 25.559004 -183.86552)
		(width 0.127)
		(layer "In2.Cu")
		(net "T4_BLAD3_EN")
	)
	(segment
		(start 2.864612 -245.754906)
		(end 1.948942 -246.670576)
		(width 0.127)
		(layer "In2.Cu")
		(net "T4_BLAD3_EN")
	)
	(segment
		(start 3.42265 -242.857782)
		(end 2.864612 -243.41582)
		(width 0.127)
		(layer "In2.Cu")
		(net "T4_BLAD3_EN")
	)
	(segment
		(start 6.935724 -242.857782)
		(end 3.42265 -242.857782)
		(width 0.127)
		(layer "In2.Cu")
		(net "T4_BLAD3_EN")
	)
	(segment
		(start 25.559004 -183.86552)
		(end 25.559004 -194.271646)
		(width 0.127)
		(layer "In2.Cu")
		(net "T4_BLAD3_EN")
	)
	(segment
		(start 80.23606 -157.408372)
		(end 59.460638 -178.183794)
		(width 0.127)
		(layer "In2.Cu")
		(net "T4_BLAD3_EN")
	)
	(segment
		(start 81.10347 -147.856194)
		(end 80.23606 -148.723604)
		(width 0.127)
		(layer "In2.Cu")
		(net "T4_BLAD3_EN")
	)
	(segment
		(start 85.969348 -140.544804)
		(end 86.889082 -139.62507)
		(width 0.127)
		(layer "In2.Cu")
		(net "T4_BLAD3_EN")
	)
	(segment
		(start 85.969348 -141.287754)
		(end 85.969348 -140.544804)
		(width 0.127)
		(layer "In2.Cu")
		(net "T4_BLAD3_EN")
	)
	(segment
		(start 81.10347 -147.856194)
		(end 86.540594 -142.41907)
		(width 0.127)
		(layer "In2.Cu")
		(net "T4_BLAD3_EN")
	)
	(segment
		(start 80.23606 -148.723604)
		(end 80.23606 -157.408372)
		(width 0.127)
		(layer "In2.Cu")
		(net "T4_BLAD3_EN")
	)
	(segment
		(start 86.540594 -141.859)
		(end 85.969348 -141.287754)
		(width 0.127)
		(layer "In2.Cu")
		(net "T4_BLAD3_EN")
	)
	(segment
		(start 86.540594 -142.41907)
		(end 86.540594 -141.859)
		(width 0.127)
		(layer "In2.Cu")
		(net "T4_BLAD3_EN")
	)
	(segment
		(start 26.653744 -226.444302)
		(end 9.2075 -243.890546)
		(width 0.127)
		(layer "In2.Cu")
		(net "T4_BLAD3_EN")
	)
	(via
		(at 85.500718 -146.806412)
		(size 0.508)
		(drill 0.254)
		(layers "F.Cu" "B.Cu")
		(net "T4_BLAD3_RXD")
	)
	(segment
		(start 6.15823 -236.910372)
		(end 4.595622 -238.47298)
		(width 0.127)
		(layer "In5.Cu")
		(net "T4_BLAD3_RXD")
	)
	(segment
		(start 22.390608 -198.464932)
		(end 25.350978 -201.425302)
		(width 0.127)
		(layer "In5.Cu")
		(net "T4_BLAD3_RXD")
	)
	(segment
		(start 86.910164 -139.643612)
		(end 86.910164 -138.35507)
		(width 0.127)
		(layer "In5.Cu")
		(net "T4_BLAD3_RXD")
	)
	(segment
		(start 84.15528 -151.756872)
		(end 59.768994 -176.143158)
		(width 0.127)
		(layer "In5.Cu")
		(net "T4_BLAD3_RXD")
	)
	(segment
		(start 3.726688 -238.47298)
		(end 3.53187 -238.667798)
		(width 0.127)
		(layer "In5.Cu")
		(net "T4_BLAD3_RXD")
	)
	(segment
		(start 18.378678 -235.89742)
		(end 8.03656 -235.89742)
		(width 0.127)
		(layer "In5.Cu")
		(net "T4_BLAD3_RXD")
	)
	(segment
		(start 25.350978 -216.941146)
		(end 21.4249 -220.867224)
		(width 0.127)
		(layer "In5.Cu")
		(net "T4_BLAD3_RXD")
	)
	(segment
		(start 85.500464 -146.806412)
		(end 86.77275 -145.534126)
		(width 0.127)
		(layer "In5.Cu")
		(net "T4_BLAD3_RXD")
	)
	(segment
		(start 27.902408 -176.143158)
		(end 22.390608 -181.654958)
		(width 0.127)
		(layer "In5.Cu")
		(net "T4_BLAD3_RXD")
	)
	(segment
		(start 22.390608 -181.654958)
		(end 22.390608 -198.464932)
		(width 0.127)
		(layer "In5.Cu")
		(net "T4_BLAD3_RXD")
	)
	(segment
		(start 59.768994 -176.143158)
		(end 27.902408 -176.143158)
		(width 0.127)
		(layer "In5.Cu")
		(net "T4_BLAD3_RXD")
	)
	(segment
		(start 4.595622 -238.47298)
		(end 3.726688 -238.47298)
		(width 0.127)
		(layer "In5.Cu")
		(net "T4_BLAD3_RXD")
	)
	(segment
		(start 25.350978 -201.425302)
		(end 25.350978 -216.941146)
		(width 0.127)
		(layer "In5.Cu")
		(net "T4_BLAD3_RXD")
	)
	(segment
		(start 85.229954 -147.076922)
		(end 85.229954 -151.51735)
		(width 0.127)
		(layer "In5.Cu")
		(net "T4_BLAD3_RXD")
	)
	(segment
		(start 86.77275 -145.534126)
		(end 86.77275 -141.915896)
		(width 0.127)
		(layer "In5.Cu")
		(net "T4_BLAD3_RXD")
	)
	(segment
		(start 85.500464 -146.806412)
		(end 85.229954 -147.076922)
		(width 0.127)
		(layer "In5.Cu")
		(net "T4_BLAD3_RXD")
	)
	(segment
		(start 21.4249 -220.867224)
		(end 21.4249 -232.851198)
		(width 0.127)
		(layer "In5.Cu")
		(net "T4_BLAD3_RXD")
	)
	(segment
		(start 8.03656 -235.89742)
		(end 7.023608 -236.910372)
		(width 0.127)
		(layer "In5.Cu")
		(net "T4_BLAD3_RXD")
	)
	(segment
		(start 86.044532 -141.187678)
		(end 86.044532 -140.509244)
		(width 0.127)
		(layer "In5.Cu")
		(net "T4_BLAD3_RXD")
	)
	(segment
		(start 7.023608 -236.910372)
		(end 6.15823 -236.910372)
		(width 0.127)
		(layer "In5.Cu")
		(net "T4_BLAD3_RXD")
	)
	(segment
		(start 21.4249 -232.851198)
		(end 18.378678 -235.89742)
		(width 0.127)
		(layer "In5.Cu")
		(net "T4_BLAD3_RXD")
	)
	(segment
		(start 84.990432 -151.756872)
		(end 84.15528 -151.756872)
		(width 0.127)
		(layer "In5.Cu")
		(net "T4_BLAD3_RXD")
	)
	(segment
		(start 85.229954 -151.51735)
		(end 84.990432 -151.756872)
		(width 0.127)
		(layer "In5.Cu")
		(net "T4_BLAD3_RXD")
	)
	(segment
		(start 86.77275 -141.915896)
		(end 86.044532 -141.187678)
		(width 0.127)
		(layer "In5.Cu")
		(net "T4_BLAD3_RXD")
	)
	(segment
		(start 86.044532 -140.509244)
		(end 86.910164 -139.643612)
		(width 0.127)
		(layer "In5.Cu")
		(net "T4_BLAD3_RXD")
	)
	(segment
		(start 3.53187 -238.667798)
		(end 1.951736 -238.667798)
		(width 0.127)
		(layer "In5.Cu")
		(net "T4_BLAD3_RXD")
	)
	(segment
		(start 1.951736 -238.667798)
		(end 1.948942 -238.670592)
		(width 0.127)
		(layer "In5.Cu")
		(net "T4_BLAD3_RXD")
	)
	(segment
		(start 85.500464 -146.806412)
		(end 85.500718 -146.806412)
		(width 0.127)
		(layer "In5.Cu")
		(net "T4_BLAD3_RXD")
	)
	(segment
		(start 22.26691 -320.124836)
		(end 22.26691 -336.234024)
		(width 0.1524)
		(layer "F.Cu")
		(net "I2C_PSU3_SCL")
	)
	(segment
		(start 9.764268 -319.669922)
		(end 11.962384 -317.471806)
		(width 0.1524)
		(layer "F.Cu")
		(net "I2C_PSU3_SCL")
	)
	(segment
		(start 8.449818 -319.669922)
		(end 9.764268 -319.669922)
		(width 0.1524)
		(layer "F.Cu")
		(net "I2C_PSU3_SCL")
	)
	(segment
		(start 19.61388 -317.471806)
		(end 22.26691 -320.124836)
		(width 0.1524)
		(layer "F.Cu")
		(net "I2C_PSU3_SCL")
	)
	(segment
		(start 22.26691 -336.234024)
		(end 25.582626 -339.54974)
		(width 0.1524)
		(layer "F.Cu")
		(net "I2C_PSU3_SCL")
	)
	(segment
		(start 11.962384 -317.471806)
		(end 19.61388 -317.471806)
		(width 0.1524)
		(layer "F.Cu")
		(net "I2C_PSU3_SCL")
	)
	(via
		(at 25.582626 -339.54974)
		(size 0.508)
		(drill 0.254)
		(layers "F.Cu" "B.Cu")
		(net "I2C_PSU3_SCL")
	)
	(segment
		(start 34.454592 -447.1797)
		(end 26.453084 -439.178192)
		(width 0.1524)
		(layer "B.Cu")
		(net "I2C_PSU3_SCL")
	)
	(segment
		(start 35.53968 -451.669912)
		(end 34.454592 -450.584824)
		(width 0.1524)
		(layer "B.Cu")
		(net "I2C_PSU3_SCL")
	)
	(segment
		(start 34.23539 -360.42092)
		(end 24.937466 -351.122996)
		(width 0.1524)
		(layer "B.Cu")
		(net "I2C_PSU3_SCL")
	)
	(segment
		(start 35.53968 -363.270038)
		(end 35.53968 -362.603034)
		(width 0.1524)
		(layer "B.Cu")
		(net "I2C_PSU3_SCL")
	)
	(segment
		(start 33.11525 -370.47424)
		(end 33.11525 -365.694468)
		(width 0.1524)
		(layer "B.Cu")
		(net "I2C_PSU3_SCL")
	)
	(segment
		(start 26.453084 -439.178192)
		(end 26.453084 -375.855738)
		(width 0.1524)
		(layer "B.Cu")
		(net "I2C_PSU3_SCL")
	)
	(segment
		(start 24.937466 -340.1949)
		(end 25.582626 -339.54974)
		(width 0.1524)
		(layer "B.Cu")
		(net "I2C_PSU3_SCL")
	)
	(segment
		(start 33.11525 -365.694468)
		(end 35.53968 -363.270038)
		(width 0.1524)
		(layer "B.Cu")
		(net "I2C_PSU3_SCL")
	)
	(segment
		(start 34.23539 -361.298744)
		(end 34.23539 -360.42092)
		(width 0.1524)
		(layer "B.Cu")
		(net "I2C_PSU3_SCL")
	)
	(segment
		(start 34.454592 -450.584824)
		(end 34.454592 -447.1797)
		(width 0.1524)
		(layer "B.Cu")
		(net "I2C_PSU3_SCL")
	)
	(segment
		(start 24.937466 -351.122996)
		(end 24.937466 -340.1949)
		(width 0.1524)
		(layer "B.Cu")
		(net "I2C_PSU3_SCL")
	)
	(segment
		(start 31.192724 -372.396766)
		(end 33.11525 -370.47424)
		(width 0.1524)
		(layer "B.Cu")
		(net "I2C_PSU3_SCL")
	)
	(segment
		(start 26.453084 -375.855738)
		(end 29.912056 -372.396766)
		(width 0.1524)
		(layer "B.Cu")
		(net "I2C_PSU3_SCL")
	)
	(segment
		(start 35.53968 -362.603034)
		(end 34.23539 -361.298744)
		(width 0.1524)
		(layer "B.Cu")
		(net "I2C_PSU3_SCL")
	)
	(segment
		(start 29.912056 -372.396766)
		(end 31.192724 -372.396766)
		(width 0.1524)
		(layer "B.Cu")
		(net "I2C_PSU3_SCL")
	)
	(segment
		(start 40.959024 -105.42143)
		(end 39.706296 -105.42143)
		(width 0.1524)
		(layer "F.Cu")
		(net "PSU2_AD0")
	)
	(segment
		(start 37.507418 -105.689908)
		(end 35.53968 -105.689908)
		(width 0.1524)
		(layer "F.Cu")
		(net "PSU2_AD0")
	)
	(segment
		(start 37.775134 -105.422192)
		(end 37.507418 -105.689908)
		(width 0.1524)
		(layer "F.Cu")
		(net "PSU2_AD0")
	)
	(segment
		(start 39.706296 -105.42143)
		(end 39.705534 -105.422192)
		(width 0.1524)
		(layer "F.Cu")
		(net "PSU2_AD0")
	)
	(segment
		(start 39.705534 -105.422192)
		(end 37.775134 -105.422192)
		(width 0.1524)
		(layer "F.Cu")
		(net "PSU2_AD0")
	)
	(segment
		(start 35.53968 -277.40991)
		(end 37.588952 -277.40991)
		(width 0.1524)
		(layer "F.Cu")
		(net "PSU4_RETURN")
	)
	(segment
		(start 39.840916 -279.661874)
		(end 39.840916 -280.119074)
		(width 0.1524)
		(layer "F.Cu")
		(net "PSU4_RETURN")
	)
	(segment
		(start 37.588952 -277.40991)
		(end 39.840916 -279.661874)
		(width 0.1524)
		(layer "F.Cu")
		(net "PSU4_RETURN")
	)
	(segment
		(start 39.656512 -280.303478)
		(end 39.656512 -281.140662)
		(width 0.1524)
		(layer "F.Cu")
		(net "PSU4_RETURN")
	)
	(segment
		(start 39.840916 -280.119074)
		(end 39.656512 -280.303478)
		(width 0.1524)
		(layer "F.Cu")
		(net "PSU4_RETURN")
	)
	(via
		(at 39.840916 -279.661874)
		(size 0.508)
		(drill 0.254)
		(layers "F.Cu" "B.Cu")
		(net "PSU4_RETURN")
	)
	(via
		(at 93.702378 -102.694232)
		(size 0.508)
		(drill 0.254)
		(layers "F.Cu" "B.Cu")
		(net "T3_BLAD3_EN")
	)
	(segment
		(start 25.870408 -190.64986)
		(end 24.727916 -191.792352)
		(width 0.127)
		(layer "In5.Cu")
		(net "T3_BLAD3_EN")
	)
	(segment
		(start 86.908132 -95.170244)
		(end 85.967316 -96.11106)
		(width 0.127)
		(layer "In5.Cu")
		(net "T3_BLAD3_EN")
	)
	(segment
		(start 86.56574 -97.421954)
		(end 86.56574 -98.765868)
		(width 0.127)
		(layer "In5.Cu")
		(net "T3_BLAD3_EN")
	)
	(segment
		(start 88.175084 -95.170244)
		(end 86.908132 -95.170244)
		(width 0.127)
		(layer "In5.Cu")
		(net "T3_BLAD3_EN")
	)
	(segment
		(start 88.17991 -95.17507)
		(end 88.175084 -95.170244)
		(width 0.127)
		(layer "In5.Cu")
		(net "T3_BLAD3_EN")
	)
	(segment
		(start 18.33245 -239.858804)
		(end 8.03148 -239.858804)
		(width 0.127)
		(layer "In5.Cu")
		(net "T3_BLAD3_EN")
	)
	(segment
		(start 85.967316 -96.11106)
		(end 85.967316 -96.82353)
		(width 0.127)
		(layer "In5.Cu")
		(net "T3_BLAD3_EN")
	)
	(segment
		(start 26.79827 -200.651618)
		(end 26.79827 -217.983562)
		(width 0.127)
		(layer "In5.Cu")
		(net "T3_BLAD3_EN")
	)
	(segment
		(start 59.958224 -177.82286)
		(end 29.533088 -177.82286)
		(width 0.127)
		(layer "In5.Cu")
		(net "T3_BLAD3_EN")
	)
	(segment
		(start 7.425436 -240.464848)
		(end 7.425436 -242.693952)
		(width 0.127)
		(layer "In5.Cu")
		(net "T3_BLAD3_EN")
	)
	(segment
		(start 24.727916 -191.792352)
		(end 24.727916 -198.581264)
		(width 0.127)
		(layer "In5.Cu")
		(net "T3_BLAD3_EN")
	)
	(segment
		(start 99.771454 -108.763308)
		(end 99.771454 -152.973278)
		(width 0.127)
		(layer "In5.Cu")
		(net "T3_BLAD3_EN")
	)
	(segment
		(start 24.727916 -198.581264)
		(end 26.79827 -200.651618)
		(width 0.127)
		(layer "In5.Cu")
		(net "T3_BLAD3_EN")
	)
	(segment
		(start 99.771454 -152.973278)
		(end 91.891866 -160.852866)
		(width 0.127)
		(layer "In5.Cu")
		(net "T3_BLAD3_EN")
	)
	(segment
		(start 8.03148 -239.858804)
		(end 7.425436 -240.464848)
		(width 0.127)
		(layer "In5.Cu")
		(net "T3_BLAD3_EN")
	)
	(segment
		(start 76.928218 -160.852866)
		(end 59.958224 -177.82286)
		(width 0.127)
		(layer "In5.Cu")
		(net "T3_BLAD3_EN")
	)
	(segment
		(start 21.278088 -236.913166)
		(end 18.33245 -239.858804)
		(width 0.127)
		(layer "In5.Cu")
		(net "T3_BLAD3_EN")
	)
	(segment
		(start 91.891866 -160.852866)
		(end 76.928218 -160.852866)
		(width 0.127)
		(layer "In5.Cu")
		(net "T3_BLAD3_EN")
	)
	(segment
		(start 24.398986 -220.382846)
		(end 24.398986 -231.95026)
		(width 0.127)
		(layer "In5.Cu")
		(net "T3_BLAD3_EN")
	)
	(segment
		(start 29.533088 -177.82286)
		(end 25.870408 -181.48554)
		(width 0.127)
		(layer "In5.Cu")
		(net "T3_BLAD3_EN")
	)
	(segment
		(start 91.895676 -100.88753)
		(end 93.702378 -102.694232)
		(width 0.127)
		(layer "In5.Cu")
		(net "T3_BLAD3_EN")
	)
	(segment
		(start 88.687402 -100.88753)
		(end 91.895676 -100.88753)
		(width 0.127)
		(layer "In5.Cu")
		(net "T3_BLAD3_EN")
	)
	(segment
		(start 26.79827 -217.983562)
		(end 24.398986 -220.382846)
		(width 0.127)
		(layer "In5.Cu")
		(net "T3_BLAD3_EN")
	)
	(segment
		(start 21.278088 -235.071158)
		(end 21.278088 -236.913166)
		(width 0.127)
		(layer "In5.Cu")
		(net "T3_BLAD3_EN")
	)
	(segment
		(start 24.398986 -231.95026)
		(end 21.278088 -235.071158)
		(width 0.127)
		(layer "In5.Cu")
		(net "T3_BLAD3_EN")
	)
	(segment
		(start 93.702378 -102.694232)
		(end 99.771454 -108.763308)
		(width 0.127)
		(layer "In5.Cu")
		(net "T3_BLAD3_EN")
	)
	(segment
		(start 7.425436 -242.693952)
		(end 6.448806 -243.670582)
		(width 0.127)
		(layer "In5.Cu")
		(net "T3_BLAD3_EN")
	)
	(segment
		(start 86.56574 -98.765868)
		(end 88.687402 -100.88753)
		(width 0.127)
		(layer "In5.Cu")
		(net "T3_BLAD3_EN")
	)
	(segment
		(start 25.870408 -181.48554)
		(end 25.870408 -190.64986)
		(width 0.127)
		(layer "In5.Cu")
		(net "T3_BLAD3_EN")
	)
	(segment
		(start 85.967316 -96.82353)
		(end 86.56574 -97.421954)
		(width 0.127)
		(layer "In5.Cu")
		(net "T3_BLAD3_EN")
	)
	(via
		(at 92.41155 -102.049072)
		(size 0.508)
		(drill 0.254)
		(layers "F.Cu" "B.Cu")
		(net "T3_BLAD1_TXD")
	)
	(segment
		(start 23.494746 -197.976236)
		(end 26.444702 -200.926192)
		(width 0.127)
		(layer "In5.Cu")
		(net "T3_BLAD1_TXD")
	)
	(segment
		(start 85.63991 -98.714814)
		(end 85.63991 -97.71507)
		(width 0.127)
		(layer "In5.Cu")
		(net "T3_BLAD1_TXD")
	)
	(segment
		(start 92.41155 -102.049072)
		(end 91.939618 -101.57714)
		(width 0.127)
		(layer "In5.Cu")
		(net "T3_BLAD1_TXD")
	)
	(segment
		(start 23.494746 -181.952392)
		(end 23.494746 -197.976236)
		(width 0.127)
		(layer "In5.Cu")
		(net "T3_BLAD1_TXD")
	)
	(segment
		(start 76.91755 -160.396428)
		(end 59.947556 -177.366422)
		(width 0.127)
		(layer "In5.Cu")
		(net "T3_BLAD1_TXD")
	)
	(segment
		(start 99.315016 -152.899364)
		(end 91.817952 -160.396428)
		(width 0.127)
		(layer "In5.Cu")
		(net "T3_BLAD1_TXD")
	)
	(segment
		(start 99.315016 -108.952538)
		(end 99.315016 -152.899364)
		(width 0.127)
		(layer "In5.Cu")
		(net "T3_BLAD1_TXD")
	)
	(segment
		(start 91.817952 -160.396428)
		(end 76.91755 -160.396428)
		(width 0.127)
		(layer "In5.Cu")
		(net "T3_BLAD1_TXD")
	)
	(segment
		(start 91.939618 -101.57714)
		(end 88.502236 -101.57714)
		(width 0.127)
		(layer "In5.Cu")
		(net "T3_BLAD1_TXD")
	)
	(segment
		(start 24.03475 -220.101414)
		(end 24.03475 -231.828848)
		(width 0.127)
		(layer "In5.Cu")
		(net "T3_BLAD1_TXD")
	)
	(segment
		(start 28.080716 -177.366422)
		(end 23.494746 -181.952392)
		(width 0.127)
		(layer "In5.Cu")
		(net "T3_BLAD1_TXD")
	)
	(segment
		(start 26.444702 -200.926192)
		(end 26.444702 -217.691462)
		(width 0.127)
		(layer "In5.Cu")
		(net "T3_BLAD1_TXD")
	)
	(segment
		(start 20.82165 -236.723936)
		(end 18.16481 -239.380776)
		(width 0.127)
		(layer "In5.Cu")
		(net "T3_BLAD1_TXD")
	)
	(segment
		(start 24.03475 -231.828848)
		(end 20.82165 -235.041948)
		(width 0.127)
		(layer "In5.Cu")
		(net "T3_BLAD1_TXD")
	)
	(segment
		(start 20.82165 -235.041948)
		(end 20.82165 -236.723936)
		(width 0.127)
		(layer "In5.Cu")
		(net "T3_BLAD1_TXD")
	)
	(segment
		(start 7.741666 -239.380776)
		(end 7.454646 -239.667796)
		(width 0.127)
		(layer "In5.Cu")
		(net "T3_BLAD1_TXD")
	)
	(segment
		(start 88.502236 -101.57714)
		(end 85.63991 -98.714814)
		(width 0.127)
		(layer "In5.Cu")
		(net "T3_BLAD1_TXD")
	)
	(segment
		(start 7.454646 -239.667796)
		(end 6.4516 -239.667796)
		(width 0.127)
		(layer "In5.Cu")
		(net "T3_BLAD1_TXD")
	)
	(segment
		(start 18.16481 -239.380776)
		(end 7.741666 -239.380776)
		(width 0.127)
		(layer "In5.Cu")
		(net "T3_BLAD1_TXD")
	)
	(segment
		(start 92.41155 -102.049072)
		(end 99.315016 -108.952538)
		(width 0.127)
		(layer "In5.Cu")
		(net "T3_BLAD1_TXD")
	)
	(segment
		(start 26.444702 -217.691462)
		(end 24.03475 -220.101414)
		(width 0.127)
		(layer "In5.Cu")
		(net "T3_BLAD1_TXD")
	)
	(segment
		(start 59.947556 -177.366422)
		(end 28.080716 -177.366422)
		(width 0.127)
		(layer "In5.Cu")
		(net "T3_BLAD1_TXD")
	)
	(segment
		(start 6.4516 -239.667796)
		(end 6.448806 -239.67059)
		(width 0.127)
		(layer "In5.Cu")
		(net "T3_BLAD1_TXD")
	)
	(segment
		(start 39.45636 -102.804468)
		(end 39.45636 -103.52405)
		(width 0.1524)
		(layer "F.Cu")
		(net "PSU2_RETURN")
	)
	(segment
		(start 35.53968 -100.609908)
		(end 38.54704 -100.609908)
		(width 0.1524)
		(layer "F.Cu")
		(net "PSU2_RETURN")
	)
	(segment
		(start 39.84371 -101.906578)
		(end 39.84371 -102.417118)
		(width 0.1524)
		(layer "F.Cu")
		(net "PSU2_RETURN")
	)
	(segment
		(start 38.54704 -100.609908)
		(end 39.84371 -101.906578)
		(width 0.1524)
		(layer "F.Cu")
		(net "PSU2_RETURN")
	)
	(segment
		(start 39.84371 -102.417118)
		(end 39.45636 -102.804468)
		(width 0.1524)
		(layer "F.Cu")
		(net "PSU2_RETURN")
	)
	(via
		(at 39.84371 -101.906578)
		(size 0.508)
		(drill 0.254)
		(layers "F.Cu" "B.Cu")
		(net "PSU2_RETURN")
	)
	(via
		(at 83.5533 -103.940864)
		(size 0.508)
		(drill 0.254)
		(layers "F.Cu" "B.Cu")
		(net "T3_BLAD3_RXD")
	)
	(segment
		(start 20.158202 -230.706168)
		(end 15.193772 -235.670598)
		(width 0.127)
		(layer "In2.Cu")
		(net "T3_BLAD3_RXD")
	)
	(segment
		(start 84.049616 -142.267178)
		(end 81.894172 -144.422622)
		(width 0.127)
		(layer "In2.Cu")
		(net "T3_BLAD3_RXD")
	)
	(segment
		(start 86.910418 -95.276416)
		(end 87.68461 -96.050608)
		(width 0.127)
		(layer "In2.Cu")
		(net "T3_BLAD3_RXD")
	)
	(segment
		(start 84.049616 -137.696448)
		(end 84.049616 -142.267178)
		(width 0.127)
		(layer "In2.Cu")
		(net "T3_BLAD3_RXD")
	)
	(segment
		(start 87.68461 -96.050608)
		(end 87.68461 -97.04832)
		(width 0.127)
		(layer "In2.Cu")
		(net "T3_BLAD3_RXD")
	)
	(segment
		(start 86.90991 -93.90507)
		(end 86.910418 -93.905578)
		(width 0.127)
		(layer "In2.Cu")
		(net "T3_BLAD3_RXD")
	)
	(segment
		(start 25.25395 -224.237296)
		(end 20.158202 -229.333044)
		(width 0.127)
		(layer "In2.Cu")
		(net "T3_BLAD3_RXD")
	)
	(segment
		(start 83.5533 -103.940864)
		(end 83.5533 -113.606834)
		(width 0.127)
		(layer "In2.Cu")
		(net "T3_BLAD3_RXD")
	)
	(segment
		(start 58.861198 -176.819306)
		(end 28.501086 -176.819306)
		(width 0.127)
		(layer "In2.Cu")
		(net "T3_BLAD3_RXD")
	)
	(segment
		(start 83.5533 -113.606834)
		(end 84.80679 -114.860324)
		(width 0.127)
		(layer "In2.Cu")
		(net "T3_BLAD3_RXD")
	)
	(segment
		(start 87.1728 -99.544886)
		(end 83.5533 -103.164386)
		(width 0.127)
		(layer "In2.Cu")
		(net "T3_BLAD3_RXD")
	)
	(segment
		(start 87.1728 -97.56013)
		(end 87.1728 -99.544886)
		(width 0.127)
		(layer "In2.Cu")
		(net "T3_BLAD3_RXD")
	)
	(segment
		(start 84.80679 -114.860324)
		(end 84.80679 -136.939274)
		(width 0.127)
		(layer "In2.Cu")
		(net "T3_BLAD3_RXD")
	)
	(segment
		(start 78.187042 -147.789392)
		(end 78.187042 -157.493462)
		(width 0.127)
		(layer "In2.Cu")
		(net "T3_BLAD3_RXD")
	)
	(segment
		(start 15.193772 -235.670598)
		(end 6.448806 -235.670598)
		(width 0.127)
		(layer "In2.Cu")
		(net "T3_BLAD3_RXD")
	)
	(segment
		(start 83.5533 -103.164386)
		(end 83.5533 -103.940864)
		(width 0.127)
		(layer "In2.Cu")
		(net "T3_BLAD3_RXD")
	)
	(segment
		(start 87.68461 -97.04832)
		(end 87.1728 -97.56013)
		(width 0.127)
		(layer "In2.Cu")
		(net "T3_BLAD3_RXD")
	)
	(segment
		(start 81.894172 -144.422622)
		(end 81.553812 -144.422622)
		(width 0.127)
		(layer "In2.Cu")
		(net "T3_BLAD3_RXD")
	)
	(segment
		(start 81.553812 -144.422622)
		(end 78.187042 -147.789392)
		(width 0.127)
		(layer "In2.Cu")
		(net "T3_BLAD3_RXD")
	)
	(segment
		(start 20.158202 -229.333044)
		(end 20.158202 -230.706168)
		(width 0.127)
		(layer "In2.Cu")
		(net "T3_BLAD3_RXD")
	)
	(segment
		(start 25.25395 -200.01357)
		(end 25.25395 -224.237296)
		(width 0.127)
		(layer "In2.Cu")
		(net "T3_BLAD3_RXD")
	)
	(segment
		(start 86.910418 -93.905578)
		(end 86.910418 -95.276416)
		(width 0.127)
		(layer "In2.Cu")
		(net "T3_BLAD3_RXD")
	)
	(segment
		(start 21.818346 -196.577966)
		(end 25.25395 -200.01357)
		(width 0.127)
		(layer "In2.Cu")
		(net "T3_BLAD3_RXD")
	)
	(segment
		(start 28.501086 -176.819306)
		(end 21.818346 -183.502046)
		(width 0.127)
		(layer "In2.Cu")
		(net "T3_BLAD3_RXD")
	)
	(segment
		(start 84.80679 -136.939274)
		(end 84.049616 -137.696448)
		(width 0.127)
		(layer "In2.Cu")
		(net "T3_BLAD3_RXD")
	)
	(segment
		(start 21.818346 -183.502046)
		(end 21.818346 -196.577966)
		(width 0.127)
		(layer "In2.Cu")
		(net "T3_BLAD3_RXD")
	)
	(segment
		(start 78.187042 -157.493462)
		(end 58.861198 -176.819306)
		(width 0.127)
		(layer "In2.Cu")
		(net "T3_BLAD3_RXD")
	)
	(via
		(at 95.133668 -101.925628)
		(size 0.508)
		(drill 0.254)
		(layers "F.Cu" "B.Cu")
		(net "T3_BLAD1_EN")
	)
	(segment
		(start 100.857812 -107.649772)
		(end 100.857812 -152.913334)
		(width 0.127)
		(layer "In5.Cu")
		(net "T3_BLAD1_EN")
	)
	(segment
		(start 90.019124 -99.554284)
		(end 88.17991 -97.71507)
		(width 0.127)
		(layer "In5.Cu")
		(net "T3_BLAD1_EN")
	)
	(segment
		(start 22.41423 -237.313724)
		(end 15.933674 -243.79428)
		(width 0.127)
		(layer "In5.Cu")
		(net "T3_BLAD1_EN")
	)
	(segment
		(start 92.762324 -99.554284)
		(end 90.019124 -99.554284)
		(width 0.127)
		(layer "In5.Cu")
		(net "T3_BLAD1_EN")
	)
	(segment
		(start 92.094558 -161.676588)
		(end 77.038962 -161.676588)
		(width 0.127)
		(layer "In5.Cu")
		(net "T3_BLAD1_EN")
	)
	(segment
		(start 27.817572 -200.045066)
		(end 27.817572 -218.774518)
		(width 0.127)
		(layer "In5.Cu")
		(net "T3_BLAD1_EN")
	)
	(segment
		(start 27.772868 -182.076344)
		(end 27.772868 -191.784224)
		(width 0.127)
		(layer "In5.Cu")
		(net "T3_BLAD1_EN")
	)
	(segment
		(start 22.41423 -235.504736)
		(end 22.41423 -237.313724)
		(width 0.127)
		(layer "In5.Cu")
		(net "T3_BLAD1_EN")
	)
	(segment
		(start 95.133668 -101.925628)
		(end 100.857812 -107.649772)
		(width 0.127)
		(layer "In5.Cu")
		(net "T3_BLAD1_EN")
	)
	(segment
		(start 100.857812 -152.913334)
		(end 92.094558 -161.676588)
		(width 0.127)
		(layer "In5.Cu")
		(net "T3_BLAD1_EN")
	)
	(segment
		(start 30.939994 -178.909218)
		(end 27.772868 -182.076344)
		(width 0.127)
		(layer "In5.Cu")
		(net "T3_BLAD1_EN")
	)
	(segment
		(start 27.817572 -218.774518)
		(end 27.08783 -219.50426)
		(width 0.127)
		(layer "In5.Cu")
		(net "T3_BLAD1_EN")
	)
	(segment
		(start 27.772868 -191.784224)
		(end 26.613104 -192.943988)
		(width 0.127)
		(layer "In5.Cu")
		(net "T3_BLAD1_EN")
	)
	(segment
		(start 15.933674 -243.79428)
		(end 8.325104 -243.79428)
		(width 0.127)
		(layer "In5.Cu")
		(net "T3_BLAD1_EN")
	)
	(segment
		(start 26.613104 -192.943988)
		(end 26.613104 -198.840598)
		(width 0.127)
		(layer "In5.Cu")
		(net "T3_BLAD1_EN")
	)
	(segment
		(start 77.038962 -161.676588)
		(end 59.806332 -178.909218)
		(width 0.127)
		(layer "In5.Cu")
		(net "T3_BLAD1_EN")
	)
	(segment
		(start 26.613104 -198.840598)
		(end 27.817572 -200.045066)
		(width 0.127)
		(layer "In5.Cu")
		(net "T3_BLAD1_EN")
	)
	(segment
		(start 59.806332 -178.909218)
		(end 30.939994 -178.909218)
		(width 0.127)
		(layer "In5.Cu")
		(net "T3_BLAD1_EN")
	)
	(segment
		(start 95.133668 -101.925628)
		(end 92.762324 -99.554284)
		(width 0.127)
		(layer "In5.Cu")
		(net "T3_BLAD1_EN")
	)
	(segment
		(start 27.08783 -219.50426)
		(end 27.08783 -230.831136)
		(width 0.127)
		(layer "In5.Cu")
		(net "T3_BLAD1_EN")
	)
	(segment
		(start 8.325104 -243.79428)
		(end 6.448806 -245.670578)
		(width 0.127)
		(layer "In5.Cu")
		(net "T3_BLAD1_EN")
	)
	(segment
		(start 27.08783 -230.831136)
		(end 22.41423 -235.504736)
		(width 0.127)
		(layer "In5.Cu")
		(net "T3_BLAD1_EN")
	)
	(via
		(at 82.853784 -105.151428)
		(size 0.508)
		(drill 0.254)
		(layers "F.Cu" "B.Cu")
		(net "T3_BLAD3_TXD")
	)
	(segment
		(start 58.717434 -176.472596)
		(end 28.380436 -176.472596)
		(width 0.127)
		(layer "In2.Cu")
		(net "T3_BLAD3_TXD")
	)
	(segment
		(start 84.339176 -101.450394)
		(end 84.339176 -97.760028)
		(width 0.127)
		(layer "In2.Cu")
		(net "T3_BLAD3_TXD")
	)
	(segment
		(start 85.640418 -95.175578)
		(end 85.63991 -95.17507)
		(width 0.127)
		(layer "In2.Cu")
		(net "T3_BLAD3_TXD")
	)
	(segment
		(start 82.853784 -113.397792)
		(end 84.46008 -115.004088)
		(width 0.127)
		(layer "In2.Cu")
		(net "T3_BLAD3_TXD")
	)
	(segment
		(start 84.46008 -136.79551)
		(end 83.702906 -137.552684)
		(width 0.127)
		(layer "In2.Cu")
		(net "T3_BLAD3_TXD")
	)
	(segment
		(start 15.608046 -234.6706)
		(end 8.448802 -234.6706)
		(width 0.127)
		(layer "In2.Cu")
		(net "T3_BLAD3_TXD")
	)
	(segment
		(start 82.853784 -102.935786)
		(end 84.339176 -101.450394)
		(width 0.127)
		(layer "In2.Cu")
		(net "T3_BLAD3_TXD")
	)
	(segment
		(start 83.702906 -137.552684)
		(end 83.702906 -142.123414)
		(width 0.127)
		(layer "In2.Cu")
		(net "T3_BLAD3_TXD")
	)
	(segment
		(start 82.853784 -105.151428)
		(end 82.853784 -102.935786)
		(width 0.127)
		(layer "In2.Cu")
		(net "T3_BLAD3_TXD")
	)
	(segment
		(start 28.380436 -176.472596)
		(end 21.384768 -183.468264)
		(width 0.127)
		(layer "In2.Cu")
		(net "T3_BLAD3_TXD")
	)
	(segment
		(start 84.339176 -97.760028)
		(end 85.640418 -96.458786)
		(width 0.127)
		(layer "In2.Cu")
		(net "T3_BLAD3_TXD")
	)
	(segment
		(start 84.46008 -115.004088)
		(end 84.46008 -136.79551)
		(width 0.127)
		(layer "In2.Cu")
		(net "T3_BLAD3_TXD")
	)
	(segment
		(start 81.410048 -144.075912)
		(end 77.840332 -147.645628)
		(width 0.127)
		(layer "In2.Cu")
		(net "T3_BLAD3_TXD")
	)
	(segment
		(start 81.750408 -144.075912)
		(end 81.410048 -144.075912)
		(width 0.127)
		(layer "In2.Cu")
		(net "T3_BLAD3_TXD")
	)
	(segment
		(start 83.702906 -142.123414)
		(end 81.750408 -144.075912)
		(width 0.127)
		(layer "In2.Cu")
		(net "T3_BLAD3_TXD")
	)
	(segment
		(start 77.840332 -147.645628)
		(end 77.840332 -157.349698)
		(width 0.127)
		(layer "In2.Cu")
		(net "T3_BLAD3_TXD")
	)
	(segment
		(start 82.853784 -105.151428)
		(end 82.853784 -113.397792)
		(width 0.127)
		(layer "In2.Cu")
		(net "T3_BLAD3_TXD")
	)
	(segment
		(start 19.744182 -230.534464)
		(end 15.608046 -234.6706)
		(width 0.127)
		(layer "In2.Cu")
		(net "T3_BLAD3_TXD")
	)
	(segment
		(start 24.881586 -223.936306)
		(end 19.744182 -229.07371)
		(width 0.127)
		(layer "In2.Cu")
		(net "T3_BLAD3_TXD")
	)
	(segment
		(start 85.640418 -96.458786)
		(end 85.640418 -95.175578)
		(width 0.127)
		(layer "In2.Cu")
		(net "T3_BLAD3_TXD")
	)
	(segment
		(start 24.881586 -200.291446)
		(end 24.881586 -223.936306)
		(width 0.127)
		(layer "In2.Cu")
		(net "T3_BLAD3_TXD")
	)
	(segment
		(start 19.744182 -229.07371)
		(end 19.744182 -230.534464)
		(width 0.127)
		(layer "In2.Cu")
		(net "T3_BLAD3_TXD")
	)
	(segment
		(start 21.384768 -183.468264)
		(end 21.384768 -196.794628)
		(width 0.127)
		(layer "In2.Cu")
		(net "T3_BLAD3_TXD")
	)
	(segment
		(start 77.840332 -157.349698)
		(end 58.717434 -176.472596)
		(width 0.127)
		(layer "In2.Cu")
		(net "T3_BLAD3_TXD")
	)
	(segment
		(start 21.384768 -196.794628)
		(end 24.881586 -200.291446)
		(width 0.127)
		(layer "In2.Cu")
		(net "T3_BLAD3_TXD")
	)
	(via
		(at 86.892638 -102.027736)
		(size 0.508)
		(drill 0.254)
		(layers "F.Cu" "B.Cu")
		(net "T3_BLAD2_RXD")
	)
	(segment
		(start 59.146186 -177.506884)
		(end 28.74772 -177.506884)
		(width 0.127)
		(layer "In2.Cu")
		(net "T3_BLAD2_RXD")
	)
	(segment
		(start 25.968706 -199.633078)
		(end 25.968706 -224.642934)
		(width 0.127)
		(layer "In2.Cu")
		(net "T3_BLAD2_RXD")
	)
	(segment
		(start 90.96756 -98.56978)
		(end 90.350594 -98.56978)
		(width 0.127)
		(layer "In2.Cu")
		(net "T3_BLAD2_RXD")
	)
	(segment
		(start 90.350594 -98.56978)
		(end 86.892638 -102.027736)
		(width 0.127)
		(layer "In2.Cu")
		(net "T3_BLAD2_RXD")
	)
	(segment
		(start 78.87462 -157.77845)
		(end 59.146186 -177.506884)
		(width 0.127)
		(layer "In2.Cu")
		(net "T3_BLAD2_RXD")
	)
	(segment
		(start 21.002498 -229.609142)
		(end 21.002498 -231.036622)
		(width 0.127)
		(layer "In2.Cu")
		(net "T3_BLAD2_RXD")
	)
	(segment
		(start 85.494368 -114.575336)
		(end 85.494368 -137.224262)
		(width 0.127)
		(layer "In2.Cu")
		(net "T3_BLAD2_RXD")
	)
	(segment
		(start 85.494368 -137.224262)
		(end 84.737194 -137.981436)
		(width 0.127)
		(layer "In2.Cu")
		(net "T3_BLAD2_RXD")
	)
	(segment
		(start 78.87462 -148.07438)
		(end 78.87462 -157.77845)
		(width 0.127)
		(layer "In2.Cu")
		(net "T3_BLAD2_RXD")
	)
	(segment
		(start 84.793836 -104.126538)
		(end 84.793836 -113.874804)
		(width 0.127)
		(layer "In2.Cu")
		(net "T3_BLAD2_RXD")
	)
	(segment
		(start 21.002498 -231.036622)
		(end 13.368528 -238.670592)
		(width 0.127)
		(layer "In2.Cu")
		(net "T3_BLAD2_RXD")
	)
	(segment
		(start 81.8388 -145.1102)
		(end 78.87462 -148.07438)
		(width 0.127)
		(layer "In2.Cu")
		(net "T3_BLAD2_RXD")
	)
	(segment
		(start 13.368528 -238.670592)
		(end 8.448802 -238.670592)
		(width 0.127)
		(layer "In2.Cu")
		(net "T3_BLAD2_RXD")
	)
	(segment
		(start 22.708108 -196.37248)
		(end 25.968706 -199.633078)
		(width 0.127)
		(layer "In2.Cu")
		(net "T3_BLAD2_RXD")
	)
	(segment
		(start 82.17916 -145.1102)
		(end 81.8388 -145.1102)
		(width 0.127)
		(layer "In2.Cu")
		(net "T3_BLAD2_RXD")
	)
	(segment
		(start 22.708108 -183.546496)
		(end 22.708108 -196.37248)
		(width 0.127)
		(layer "In2.Cu")
		(net "T3_BLAD2_RXD")
	)
	(segment
		(start 84.737194 -142.552166)
		(end 82.17916 -145.1102)
		(width 0.127)
		(layer "In2.Cu")
		(net "T3_BLAD2_RXD")
	)
	(segment
		(start 84.737194 -137.981436)
		(end 84.737194 -142.552166)
		(width 0.127)
		(layer "In2.Cu")
		(net "T3_BLAD2_RXD")
	)
	(segment
		(start 91.98991 -97.54743)
		(end 90.96756 -98.56978)
		(width 0.127)
		(layer "In2.Cu")
		(net "T3_BLAD2_RXD")
	)
	(segment
		(start 86.892638 -102.027736)
		(end 84.793836 -104.126538)
		(width 0.127)
		(layer "In2.Cu")
		(net "T3_BLAD2_RXD")
	)
	(segment
		(start 25.968706 -224.642934)
		(end 21.002498 -229.609142)
		(width 0.127)
		(layer "In2.Cu")
		(net "T3_BLAD2_RXD")
	)
	(segment
		(start 84.793836 -113.874804)
		(end 85.494368 -114.575336)
		(width 0.127)
		(layer "In2.Cu")
		(net "T3_BLAD2_RXD")
	)
	(segment
		(start 91.98991 -96.44507)
		(end 91.98991 -97.54743)
		(width 0.127)
		(layer "In2.Cu")
		(net "T3_BLAD2_RXD")
	)
	(segment
		(start 28.74772 -177.506884)
		(end 22.708108 -183.546496)
		(width 0.127)
		(layer "In2.Cu")
		(net "T3_BLAD2_RXD")
	)
	(segment
		(start 7.264908 -252.912372)
		(end 8.065516 -253.71298)
		(width 0.1524)
		(layer "F.Cu")
		(net "I2C_PSU2_SCL")
	)
	(segment
		(start 3.29438 -252.670564)
		(end 3.536188 -252.912372)
		(width 0.1524)
		(layer "F.Cu")
		(net "I2C_PSU2_SCL")
	)
	(segment
		(start 10.489692 -254.381254)
		(end 25.038558 -254.381254)
		(width 0.1524)
		(layer "F.Cu")
		(net "I2C_PSU2_SCL")
	)
	(segment
		(start 25.038558 -254.381254)
		(end 25.574498 -253.845314)
		(width 0.1524)
		(layer "F.Cu")
		(net "I2C_PSU2_SCL")
	)
	(segment
		(start 9.821418 -253.71298)
		(end 10.489692 -254.381254)
		(width 0.1524)
		(layer "F.Cu")
		(net "I2C_PSU2_SCL")
	)
	(segment
		(start 8.065516 -253.71298)
		(end 9.821418 -253.71298)
		(width 0.1524)
		(layer "F.Cu")
		(net "I2C_PSU2_SCL")
	)
	(segment
		(start 3.536188 -252.912372)
		(end 7.264908 -252.912372)
		(width 0.1524)
		(layer "F.Cu")
		(net "I2C_PSU2_SCL")
	)
	(segment
		(start 1.948942 -252.670564)
		(end 3.29438 -252.670564)
		(width 0.1524)
		(layer "F.Cu")
		(net "I2C_PSU2_SCL")
	)
	(via
		(at 25.574498 -253.845314)
		(size 0.508)
		(drill 0.254)
		(layers "F.Cu" "B.Cu")
		(net "I2C_PSU2_SCL")
	)
	(segment
		(start 25.574498 -250.732798)
		(end 25.574498 -253.845314)
		(width 0.1524)
		(layer "B.Cu")
		(net "I2C_PSU2_SCL")
	)
	(segment
		(start 24.646382 -204.769212)
		(end 24.646382 -249.804682)
		(width 0.1524)
		(layer "B.Cu")
		(net "I2C_PSU2_SCL")
	)
	(segment
		(start 34.291016 -187.7187)
		(end 34.291016 -198.27494)
		(width 0.1524)
		(layer "B.Cu")
		(net "I2C_PSU2_SCL")
	)
	(segment
		(start 35.53968 -186.470036)
		(end 34.291016 -187.7187)
		(width 0.1524)
		(layer "B.Cu")
		(net "I2C_PSU2_SCL")
	)
	(segment
		(start 37.03701 -273.37258)
		(end 37.03701 -269.727426)
		(width 0.1524)
		(layer "B.Cu")
		(net "I2C_PSU2_SCL")
	)
	(segment
		(start 34.291016 -198.27494)
		(end 31.87192 -200.694036)
		(width 0.1524)
		(layer "B.Cu")
		(net "I2C_PSU2_SCL")
	)
	(segment
		(start 25.574498 -258.264914)
		(end 25.574498 -253.845314)
		(width 0.1524)
		(layer "B.Cu")
		(net "I2C_PSU2_SCL")
	)
	(segment
		(start 28.721558 -200.694036)
		(end 24.646382 -204.769212)
		(width 0.1524)
		(layer "B.Cu")
		(net "I2C_PSU2_SCL")
	)
	(segment
		(start 31.87192 -200.694036)
		(end 28.721558 -200.694036)
		(width 0.1524)
		(layer "B.Cu")
		(net "I2C_PSU2_SCL")
	)
	(segment
		(start 35.53968 -274.86991)
		(end 37.03701 -273.37258)
		(width 0.1524)
		(layer "B.Cu")
		(net "I2C_PSU2_SCL")
	)
	(segment
		(start 24.646382 -249.804682)
		(end 25.574498 -250.732798)
		(width 0.1524)
		(layer "B.Cu")
		(net "I2C_PSU2_SCL")
	)
	(segment
		(start 37.03701 -269.727426)
		(end 25.574498 -258.264914)
		(width 0.1524)
		(layer "B.Cu")
		(net "I2C_PSU2_SCL")
	)
	(segment
		(start 6.449822 -324.669912)
		(end 7.25932 -324.669912)
		(width 0.1524)
		(layer "F.Cu")
		(net "FAN5_TACH")
	)
	(segment
		(start 7.39902 -324.530212)
		(end 10.390632 -324.530212)
		(width 0.1524)
		(layer "F.Cu")
		(net "FAN5_TACH")
	)
	(segment
		(start 10.390632 -324.530212)
		(end 10.910824 -324.01002)
		(width 0.1524)
		(layer "F.Cu")
		(net "FAN5_TACH")
	)
	(segment
		(start 10.910824 -324.01002)
		(end 13.063728 -324.01002)
		(width 0.1524)
		(layer "F.Cu")
		(net "FAN5_TACH")
	)
	(segment
		(start 7.25932 -324.669912)
		(end 7.39902 -324.530212)
		(width 0.1524)
		(layer "F.Cu")
		(net "FAN5_TACH")
	)
	(segment
		(start 8.74776 -326.796654)
		(end 8.134858 -326.796654)
		(width 0.1524)
		(layer "B.Cu")
		(net "FAN5_TACH")
	)
	(segment
		(start 12.582398 -345.830144)
		(end 9.878822 -343.126568)
		(width 0.1524)
		(layer "B.Cu")
		(net "FAN5_TACH")
	)
	(segment
		(start 8.51408 -444.6651)
		(end 8.51408 -421.467788)
		(width 0.1524)
		(layer "B.Cu")
		(net "FAN5_TACH")
	)
	(segment
		(start 4.290568 -460.040482)
		(end 4.290568 -448.888612)
		(width 0.1524)
		(layer "B.Cu")
		(net "FAN5_TACH")
	)
	(segment
		(start 7.576566 -325.796656)
		(end 6.449822 -324.669912)
		(width 0.1524)
		(layer "B.Cu")
		(net "FAN5_TACH")
	)
	(segment
		(start 12.582398 -372.33987)
		(end 12.582398 -345.830144)
		(width 0.1524)
		(layer "B.Cu")
		(net "FAN5_TACH")
	)
	(segment
		(start 8.134858 -326.796654)
		(end 7.576566 -326.238362)
		(width 0.1524)
		(layer "B.Cu")
		(net "FAN5_TACH")
	)
	(segment
		(start 9.878822 -327.927716)
		(end 8.74776 -326.796654)
		(width 0.1524)
		(layer "B.Cu")
		(net "FAN5_TACH")
	)
	(segment
		(start 22.592284 -407.389584)
		(end 22.592284 -382.349756)
		(width 0.1524)
		(layer "B.Cu")
		(net "FAN5_TACH")
	)
	(segment
		(start 5.944108 -461.694022)
		(end 4.290568 -460.040482)
		(width 0.1524)
		(layer "B.Cu")
		(net "FAN5_TACH")
	)
	(segment
		(start 4.290568 -448.888612)
		(end 8.51408 -444.6651)
		(width 0.1524)
		(layer "B.Cu")
		(net "FAN5_TACH")
	)
	(segment
		(start 9.878822 -343.126568)
		(end 9.878822 -327.927716)
		(width 0.1524)
		(layer "B.Cu")
		(net "FAN5_TACH")
	)
	(segment
		(start 22.592284 -382.349756)
		(end 12.582398 -372.33987)
		(width 0.1524)
		(layer "B.Cu")
		(net "FAN5_TACH")
	)
	(segment
		(start 7.576566 -326.238362)
		(end 7.576566 -325.796656)
		(width 0.1524)
		(layer "B.Cu")
		(net "FAN5_TACH")
	)
	(segment
		(start 8.51408 -421.467788)
		(end 22.592284 -407.389584)
		(width 0.1524)
		(layer "B.Cu")
		(net "FAN5_TACH")
	)
	(via
		(at 81.52892 -107.49915)
		(size 0.508)
		(drill 0.254)
		(layers "F.Cu" "B.Cu")
		(net "T3_BLAD4_TXD")
	)
	(segment
		(start 86.031324 -92.1131)
		(end 83.312762 -94.831662)
		(width 0.127)
		(layer "In2.Cu")
		(net "T3_BLAD4_TXD")
	)
	(segment
		(start 92.026486 -95.17507)
		(end 93.095318 -94.106238)
		(width 0.127)
		(layer "In2.Cu")
		(net "T3_BLAD4_TXD")
	)
	(segment
		(start 93.095318 -93.33865)
		(end 91.869768 -92.1131)
		(width 0.127)
		(layer "In2.Cu")
		(net "T3_BLAD4_TXD")
	)
	(segment
		(start 83.312762 -100.645468)
		(end 81.52892 -102.42931)
		(width 0.127)
		(layer "In2.Cu")
		(net "T3_BLAD4_TXD")
	)
	(segment
		(start 93.095318 -94.106238)
		(end 93.095318 -93.33865)
		(width 0.127)
		(layer "In2.Cu")
		(net "T3_BLAD4_TXD")
	)
	(segment
		(start 20.40382 -197.069202)
		(end 20.40382 -183.514746)
		(width 0.127)
		(layer "In2.Cu")
		(net "T3_BLAD4_TXD")
	)
	(segment
		(start 15.506192 -233.670094)
		(end 19.074638 -230.101648)
		(width 0.127)
		(layer "In2.Cu")
		(net "T3_BLAD4_TXD")
	)
	(segment
		(start 83.033362 -137.275062)
		(end 83.790536 -136.517888)
		(width 0.127)
		(layer "In2.Cu")
		(net "T3_BLAD4_TXD")
	)
	(segment
		(start 91.869768 -92.1131)
		(end 86.031324 -92.1131)
		(width 0.127)
		(layer "In2.Cu")
		(net "T3_BLAD4_TXD")
	)
	(segment
		(start 83.312762 -94.831662)
		(end 83.312762 -100.645468)
		(width 0.127)
		(layer "In2.Cu")
		(net "T3_BLAD4_TXD")
	)
	(segment
		(start 24.159464 -200.824846)
		(end 20.40382 -197.069202)
		(width 0.127)
		(layer "In2.Cu")
		(net "T3_BLAD4_TXD")
	)
	(segment
		(start 19.074638 -230.101648)
		(end 19.074638 -228.75113)
		(width 0.127)
		(layer "In2.Cu")
		(net "T3_BLAD4_TXD")
	)
	(segment
		(start 90.71991 -95.17507)
		(end 92.026486 -95.17507)
		(width 0.127)
		(layer "In2.Cu")
		(net "T3_BLAD4_TXD")
	)
	(segment
		(start 77.170788 -157.072076)
		(end 77.170788 -147.368006)
		(width 0.127)
		(layer "In2.Cu")
		(net "T3_BLAD4_TXD")
	)
	(segment
		(start 20.40382 -183.514746)
		(end 28.115514 -175.803052)
		(width 0.127)
		(layer "In2.Cu")
		(net "T3_BLAD4_TXD")
	)
	(segment
		(start 81.132426 -143.406368)
		(end 81.472786 -143.406368)
		(width 0.127)
		(layer "In2.Cu")
		(net "T3_BLAD4_TXD")
	)
	(segment
		(start 28.115514 -175.803052)
		(end 58.439812 -175.803052)
		(width 0.127)
		(layer "In2.Cu")
		(net "T3_BLAD4_TXD")
	)
	(segment
		(start 77.170788 -147.368006)
		(end 81.132426 -143.406368)
		(width 0.127)
		(layer "In2.Cu")
		(net "T3_BLAD4_TXD")
	)
	(segment
		(start 81.52892 -113.020094)
		(end 81.52892 -107.49915)
		(width 0.127)
		(layer "In2.Cu")
		(net "T3_BLAD4_TXD")
	)
	(segment
		(start 9.448292 -233.670094)
		(end 15.506192 -233.670094)
		(width 0.127)
		(layer "In2.Cu")
		(net "T3_BLAD4_TXD")
	)
	(segment
		(start 81.472786 -143.406368)
		(end 83.033362 -141.845792)
		(width 0.127)
		(layer "In2.Cu")
		(net "T3_BLAD4_TXD")
	)
	(segment
		(start 24.159464 -223.666304)
		(end 24.159464 -200.824846)
		(width 0.127)
		(layer "In2.Cu")
		(net "T3_BLAD4_TXD")
	)
	(segment
		(start 83.790536 -136.517888)
		(end 83.790536 -115.28171)
		(width 0.127)
		(layer "In2.Cu")
		(net "T3_BLAD4_TXD")
	)
	(segment
		(start 8.448802 -232.670604)
		(end 9.448292 -233.670094)
		(width 0.127)
		(layer "In2.Cu")
		(net "T3_BLAD4_TXD")
	)
	(segment
		(start 83.033362 -141.845792)
		(end 83.033362 -137.275062)
		(width 0.127)
		(layer "In2.Cu")
		(net "T3_BLAD4_TXD")
	)
	(segment
		(start 58.439812 -175.803052)
		(end 77.170788 -157.072076)
		(width 0.127)
		(layer "In2.Cu")
		(net "T3_BLAD4_TXD")
	)
	(segment
		(start 83.790536 -115.28171)
		(end 81.52892 -113.020094)
		(width 0.127)
		(layer "In2.Cu")
		(net "T3_BLAD4_TXD")
	)
	(segment
		(start 81.52892 -102.42931)
		(end 81.52892 -107.49915)
		(width 0.127)
		(layer "In2.Cu")
		(net "T3_BLAD4_TXD")
	)
	(segment
		(start 19.074638 -228.75113)
		(end 24.159464 -223.666304)
		(width 0.127)
		(layer "In2.Cu")
		(net "T3_BLAD4_TXD")
	)
	(segment
		(start 37.555932 -194.089782)
		(end 37.580824 -194.114674)
		(width 0.1524)
		(layer "F.Cu")
		(net "PSU3_AD0")
	)
	(segment
		(start 35.53968 -194.090036)
		(end 36.539932 -194.090036)
		(width 0.1524)
		(layer "F.Cu")
		(net "PSU3_AD0")
	)
	(segment
		(start 36.539932 -194.090036)
		(end 37.555932 -194.089782)
		(width 0.1524)
		(layer "F.Cu")
		(net "PSU3_AD0")
	)
	(segment
		(start 37.580824 -194.114674)
		(end 39.50081 -194.114674)
		(width 0.1524)
		(layer "F.Cu")
		(net "PSU3_AD0")
	)
	(segment
		(start 13.038074 -322.972176)
		(end 11.00709 -322.972176)
		(width 0.1524)
		(layer "F.Cu")
		(net "FAN6_TACH")
	)
	(segment
		(start 11.00709 -322.972176)
		(end 10.309352 -323.669914)
		(width 0.1524)
		(layer "F.Cu")
		(net "FAN6_TACH")
	)
	(segment
		(start 10.309352 -323.669914)
		(end 8.449818 -323.669914)
		(width 0.1524)
		(layer "F.Cu")
		(net "FAN6_TACH")
	)
	(segment
		(start 8.914638 -449.094098)
		(end 5.944108 -449.094098)
		(width 0.1524)
		(layer "B.Cu")
		(net "FAN6_TACH")
	)
	(segment
		(start 10.590022 -325.810118)
		(end 10.590022 -342.831928)
		(width 0.1524)
		(layer "B.Cu")
		(net "FAN6_TACH")
	)
	(segment
		(start 8.449818 -323.669914)
		(end 10.590022 -325.810118)
		(width 0.1524)
		(layer "B.Cu")
		(net "FAN6_TACH")
	)
	(segment
		(start 10.590022 -342.831928)
		(end 13.293598 -345.535504)
		(width 0.1524)
		(layer "B.Cu")
		(net "FAN6_TACH")
	)
	(segment
		(start 13.293598 -345.535504)
		(end 13.293598 -372.04523)
		(width 0.1524)
		(layer "B.Cu")
		(net "FAN6_TACH")
	)
	(segment
		(start 12.89304 -445.115696)
		(end 8.914638 -449.094098)
		(width 0.1524)
		(layer "B.Cu")
		(net "FAN6_TACH")
	)
	(segment
		(start 23.303484 -408.285442)
		(end 12.89304 -418.695886)
		(width 0.1524)
		(layer "B.Cu")
		(net "FAN6_TACH")
	)
	(segment
		(start 23.303484 -382.055116)
		(end 23.303484 -408.285442)
		(width 0.1524)
		(layer "B.Cu")
		(net "FAN6_TACH")
	)
	(segment
		(start 12.89304 -418.695886)
		(end 12.89304 -445.115696)
		(width 0.1524)
		(layer "B.Cu")
		(net "FAN6_TACH")
	)
	(segment
		(start 13.293598 -372.04523)
		(end 23.303484 -382.055116)
		(width 0.1524)
		(layer "B.Cu")
		(net "FAN6_TACH")
	)
	(via
		(at 95.108268 -103.341678)
		(size 0.508)
		(drill 0.254)
		(layers "F.Cu" "B.Cu")
		(net "T3_BLAD1_RXD")
	)
	(segment
		(start 92.198698 -100.432108)
		(end 88.70569 -100.432108)
		(width 0.127)
		(layer "In5.Cu")
		(net "T3_BLAD1_RXD")
	)
	(segment
		(start 26.221944 -190.765684)
		(end 25.161494 -191.826134)
		(width 0.127)
		(layer "In5.Cu")
		(net "T3_BLAD1_RXD")
	)
	(segment
		(start 100.111052 -108.344462)
		(end 100.111052 -153.113994)
		(width 0.127)
		(layer "In5.Cu")
		(net "T3_BLAD1_RXD")
	)
	(segment
		(start 21.617686 -235.211874)
		(end 21.617686 -237.053882)
		(width 0.127)
		(layer "In5.Cu")
		(net "T3_BLAD1_RXD")
	)
	(segment
		(start 26.221944 -182.6514)
		(end 26.221944 -190.765684)
		(width 0.127)
		(layer "In5.Cu")
		(net "T3_BLAD1_RXD")
	)
	(segment
		(start 86.90991 -98.636328)
		(end 86.90991 -96.44507)
		(width 0.127)
		(layer "In5.Cu")
		(net "T3_BLAD1_RXD")
	)
	(segment
		(start 8.451596 -240.667794)
		(end 8.448802 -240.670588)
		(width 0.127)
		(layer "In5.Cu")
		(net "T3_BLAD1_RXD")
	)
	(segment
		(start 95.108268 -103.341678)
		(end 100.111052 -108.344462)
		(width 0.127)
		(layer "In5.Cu")
		(net "T3_BLAD1_RXD")
	)
	(segment
		(start 25.161494 -191.826134)
		(end 25.161494 -198.516494)
		(width 0.127)
		(layer "In5.Cu")
		(net "T3_BLAD1_RXD")
	)
	(segment
		(start 26.40203 -230.42753)
		(end 21.617686 -235.211874)
		(width 0.127)
		(layer "In5.Cu")
		(net "T3_BLAD1_RXD")
	)
	(segment
		(start 88.70569 -100.432108)
		(end 86.90991 -98.636328)
		(width 0.127)
		(layer "In5.Cu")
		(net "T3_BLAD1_RXD")
	)
	(segment
		(start 60.085732 -178.162458)
		(end 30.710886 -178.162458)
		(width 0.127)
		(layer "In5.Cu")
		(net "T3_BLAD1_RXD")
	)
	(segment
		(start 100.111052 -153.113994)
		(end 92.032582 -161.192464)
		(width 0.127)
		(layer "In5.Cu")
		(net "T3_BLAD1_RXD")
	)
	(segment
		(start 21.617686 -237.053882)
		(end 18.003774 -240.667794)
		(width 0.127)
		(layer "In5.Cu")
		(net "T3_BLAD1_RXD")
	)
	(segment
		(start 18.003774 -240.667794)
		(end 8.451596 -240.667794)
		(width 0.127)
		(layer "In5.Cu")
		(net "T3_BLAD1_RXD")
	)
	(segment
		(start 95.108268 -103.341678)
		(end 92.198698 -100.432108)
		(width 0.127)
		(layer "In5.Cu")
		(net "T3_BLAD1_RXD")
	)
	(segment
		(start 27.140408 -218.395296)
		(end 26.40203 -219.133674)
		(width 0.127)
		(layer "In5.Cu")
		(net "T3_BLAD1_RXD")
	)
	(segment
		(start 25.161494 -198.516494)
		(end 27.140408 -200.495408)
		(width 0.127)
		(layer "In5.Cu")
		(net "T3_BLAD1_RXD")
	)
	(segment
		(start 30.710886 -178.162458)
		(end 26.221944 -182.6514)
		(width 0.127)
		(layer "In5.Cu")
		(net "T3_BLAD1_RXD")
	)
	(segment
		(start 92.032582 -161.192464)
		(end 77.055726 -161.192464)
		(width 0.127)
		(layer "In5.Cu")
		(net "T3_BLAD1_RXD")
	)
	(segment
		(start 27.140408 -200.495408)
		(end 27.140408 -218.395296)
		(width 0.127)
		(layer "In5.Cu")
		(net "T3_BLAD1_RXD")
	)
	(segment
		(start 77.055726 -161.192464)
		(end 60.085732 -178.162458)
		(width 0.127)
		(layer "In5.Cu")
		(net "T3_BLAD1_RXD")
	)
	(segment
		(start 26.40203 -219.133674)
		(end 26.40203 -230.42753)
		(width 0.127)
		(layer "In5.Cu")
		(net "T3_BLAD1_RXD")
	)
	(segment
		(start 10.818368 -321.89166)
		(end 9.764522 -322.945506)
		(width 0.1524)
		(layer "F.Cu")
		(net "FAN2_TACH")
	)
	(segment
		(start 7.264908 -323.669914)
		(end 1.949958 -323.669914)
		(width 0.1524)
		(layer "F.Cu")
		(net "FAN2_TACH")
	)
	(segment
		(start 13.055092 -321.89166)
		(end 10.818368 -321.89166)
		(width 0.1524)
		(layer "F.Cu")
		(net "FAN2_TACH")
	)
	(segment
		(start 9.764522 -322.945506)
		(end 7.989316 -322.945506)
		(width 0.1524)
		(layer "F.Cu")
		(net "FAN2_TACH")
	)
	(segment
		(start 7.989316 -322.945506)
		(end 7.264908 -323.669914)
		(width 0.1524)
		(layer "F.Cu")
		(net "FAN2_TACH")
	)
	(segment
		(start 23.659084 -381.907796)
		(end 13.653262 -371.901974)
		(width 0.1524)
		(layer "B.Cu")
		(net "FAN2_TACH")
	)
	(segment
		(start 13.653262 -371.901974)
		(end 13.653262 -345.392248)
		(width 0.1524)
		(layer "B.Cu")
		(net "FAN2_TACH")
	)
	(segment
		(start 10.958576 -342.697562)
		(end 10.958576 -325.415656)
		(width 0.1524)
		(layer "B.Cu")
		(net "FAN2_TACH")
	)
	(segment
		(start 23.659084 -408.899614)
		(end 23.659084 -381.907796)
		(width 0.1524)
		(layer "B.Cu")
		(net "FAN2_TACH")
	)
	(segment
		(start 4.16941 -323.669914)
		(end 1.949958 -323.669914)
		(width 0.1524)
		(layer "B.Cu")
		(net "FAN2_TACH")
	)
	(segment
		(start 7.787894 -320.856102)
		(end 7.100824 -321.543172)
		(width 0.1524)
		(layer "B.Cu")
		(net "FAN2_TACH")
	)
	(segment
		(start 13.653262 -345.392248)
		(end 10.958576 -342.697562)
		(width 0.1524)
		(layer "B.Cu")
		(net "FAN2_TACH")
	)
	(segment
		(start 13.390372 -447.14795)
		(end 13.390372 -419.168326)
		(width 0.1524)
		(layer "B.Cu")
		(net "FAN2_TACH")
	)
	(segment
		(start 10.958576 -325.415656)
		(end 10.333736 -324.790816)
		(width 0.1524)
		(layer "B.Cu")
		(net "FAN2_TACH")
	)
	(segment
		(start 11.444224 -449.094098)
		(end 13.390372 -447.14795)
		(width 0.1524)
		(layer "B.Cu")
		(net "FAN2_TACH")
	)
	(segment
		(start 13.390372 -419.168326)
		(end 23.659084 -408.899614)
		(width 0.1524)
		(layer "B.Cu")
		(net "FAN2_TACH")
	)
	(segment
		(start 10.333736 -324.790816)
		(end 10.333736 -322.031614)
		(width 0.1524)
		(layer "B.Cu")
		(net "FAN2_TACH")
	)
	(segment
		(start 7.100824 -321.543172)
		(end 6.296152 -321.543172)
		(width 0.1524)
		(layer "B.Cu")
		(net "FAN2_TACH")
	)
	(segment
		(start 6.296152 -321.543172)
		(end 4.16941 -323.669914)
		(width 0.1524)
		(layer "B.Cu")
		(net "FAN2_TACH")
	)
	(segment
		(start 10.333736 -322.031614)
		(end 9.158224 -320.856102)
		(width 0.1524)
		(layer "B.Cu")
		(net "FAN2_TACH")
	)
	(segment
		(start 9.158224 -320.856102)
		(end 7.787894 -320.856102)
		(width 0.1524)
		(layer "B.Cu")
		(net "FAN2_TACH")
	)
	(via
		(at 82.121502 -106.251502)
		(size 0.508)
		(drill 0.254)
		(layers "F.Cu" "B.Cu")
		(net "T3_BLAD4_RXD")
	)
	(segment
		(start 9.162796 -234.147614)
		(end 15.50289 -234.147614)
		(width 0.127)
		(layer "In2.Cu")
		(net "T3_BLAD4_RXD")
	)
	(segment
		(start 83.368642 -141.98473)
		(end 83.368642 -137.414)
		(width 0.127)
		(layer "In2.Cu")
		(net "T3_BLAD4_RXD")
	)
	(segment
		(start 20.97405 -196.977254)
		(end 20.97405 -183.411622)
		(width 0.127)
		(layer "In2.Cu")
		(net "T3_BLAD4_RXD")
	)
	(segment
		(start 83.766914 -94.851728)
		(end 83.766914 -100.98278)
		(width 0.127)
		(layer "In2.Cu")
		(net "T3_BLAD4_RXD")
	)
	(segment
		(start 20.97405 -183.411622)
		(end 28.24734 -176.138332)
		(width 0.127)
		(layer "In2.Cu")
		(net "T3_BLAD4_RXD")
	)
	(segment
		(start 8.685784 -233.670602)
		(end 9.162796 -234.147614)
		(width 0.127)
		(layer "In2.Cu")
		(net "T3_BLAD4_RXD")
	)
	(segment
		(start 84.125816 -115.142772)
		(end 82.121502 -113.138458)
		(width 0.127)
		(layer "In2.Cu")
		(net "T3_BLAD4_RXD")
	)
	(segment
		(start 19.409918 -230.240586)
		(end 19.409918 -228.90607)
		(width 0.127)
		(layer "In2.Cu")
		(net "T3_BLAD4_RXD")
	)
	(segment
		(start 6.448806 -233.670602)
		(end 8.685784 -233.670602)
		(width 0.127)
		(layer "In2.Cu")
		(net "T3_BLAD4_RXD")
	)
	(segment
		(start 86.170262 -92.44838)
		(end 83.766914 -94.851728)
		(width 0.127)
		(layer "In2.Cu")
		(net "T3_BLAD4_RXD")
	)
	(segment
		(start 77.506068 -157.211014)
		(end 77.506068 -147.506944)
		(width 0.127)
		(layer "In2.Cu")
		(net "T3_BLAD4_RXD")
	)
	(segment
		(start 83.766914 -100.98278)
		(end 82.121502 -102.628192)
		(width 0.127)
		(layer "In2.Cu")
		(net "T3_BLAD4_RXD")
	)
	(segment
		(start 82.121502 -102.628192)
		(end 82.121502 -106.251502)
		(width 0.127)
		(layer "In2.Cu")
		(net "T3_BLAD4_RXD")
	)
	(segment
		(start 84.125816 -136.656826)
		(end 84.125816 -115.142772)
		(width 0.127)
		(layer "In2.Cu")
		(net "T3_BLAD4_RXD")
	)
	(segment
		(start 24.501602 -200.504806)
		(end 20.97405 -196.977254)
		(width 0.127)
		(layer "In2.Cu")
		(net "T3_BLAD4_RXD")
	)
	(segment
		(start 58.57875 -176.138332)
		(end 77.506068 -157.211014)
		(width 0.127)
		(layer "In2.Cu")
		(net "T3_BLAD4_RXD")
	)
	(segment
		(start 28.24734 -176.138332)
		(end 58.57875 -176.138332)
		(width 0.127)
		(layer "In2.Cu")
		(net "T3_BLAD4_RXD")
	)
	(segment
		(start 83.368642 -137.414)
		(end 84.125816 -136.656826)
		(width 0.127)
		(layer "In2.Cu")
		(net "T3_BLAD4_RXD")
	)
	(segment
		(start 19.409918 -228.90607)
		(end 24.501602 -223.814386)
		(width 0.127)
		(layer "In2.Cu")
		(net "T3_BLAD4_RXD")
	)
	(segment
		(start 24.501602 -223.814386)
		(end 24.501602 -200.504806)
		(width 0.127)
		(layer "In2.Cu")
		(net "T3_BLAD4_RXD")
	)
	(segment
		(start 81.271364 -143.741648)
		(end 81.611724 -143.741648)
		(width 0.127)
		(layer "In2.Cu")
		(net "T3_BLAD4_RXD")
	)
	(segment
		(start 81.611724 -143.741648)
		(end 83.368642 -141.98473)
		(width 0.127)
		(layer "In2.Cu")
		(net "T3_BLAD4_RXD")
	)
	(segment
		(start 82.121502 -113.138458)
		(end 82.121502 -106.251502)
		(width 0.127)
		(layer "In2.Cu")
		(net "T3_BLAD4_RXD")
	)
	(segment
		(start 15.50289 -234.147614)
		(end 19.409918 -230.240586)
		(width 0.127)
		(layer "In2.Cu")
		(net "T3_BLAD4_RXD")
	)
	(segment
		(start 90.53322 -92.44838)
		(end 86.170262 -92.44838)
		(width 0.127)
		(layer "In2.Cu")
		(net "T3_BLAD4_RXD")
	)
	(segment
		(start 91.98991 -93.90507)
		(end 90.53322 -92.44838)
		(width 0.127)
		(layer "In2.Cu")
		(net "T3_BLAD4_RXD")
	)
	(segment
		(start 77.506068 -147.506944)
		(end 81.271364 -143.741648)
		(width 0.127)
		(layer "In2.Cu")
		(net "T3_BLAD4_RXD")
	)
	(via
		(at 85.222588 -102.624382)
		(size 0.508)
		(drill 0.254)
		(layers "F.Cu" "B.Cu")
		(net "T3_BLAD2_TXD")
	)
	(segment
		(start 82.036666 -144.766538)
		(end 81.696306 -144.766538)
		(width 0.127)
		(layer "In2.Cu")
		(net "T3_BLAD2_TXD")
	)
	(segment
		(start 78.530958 -147.931886)
		(end 78.530958 -157.635956)
		(width 0.127)
		(layer "In2.Cu")
		(net "T3_BLAD2_TXD")
	)
	(segment
		(start 84.273644 -113.840768)
		(end 85.150706 -114.71783)
		(width 0.127)
		(layer "In2.Cu")
		(net "T3_BLAD2_TXD")
	)
	(segment
		(start 28.624276 -177.163222)
		(end 22.29739 -183.490108)
		(width 0.127)
		(layer "In2.Cu")
		(net "T3_BLAD2_TXD")
	)
	(segment
		(start 20.59178 -229.438962)
		(end 20.59178 -230.866442)
		(width 0.127)
		(layer "In2.Cu")
		(net "T3_BLAD2_TXD")
	)
	(segment
		(start 84.393532 -142.409672)
		(end 82.036666 -144.766538)
		(width 0.127)
		(layer "In2.Cu")
		(net "T3_BLAD2_TXD")
	)
	(segment
		(start 85.222588 -102.624382)
		(end 84.273644 -103.573326)
		(width 0.127)
		(layer "In2.Cu")
		(net "T3_BLAD2_TXD")
	)
	(segment
		(start 84.393532 -137.838942)
		(end 84.393532 -142.409672)
		(width 0.127)
		(layer "In2.Cu")
		(net "T3_BLAD2_TXD")
	)
	(segment
		(start 78.530958 -157.635956)
		(end 59.003692 -177.163222)
		(width 0.127)
		(layer "In2.Cu")
		(net "T3_BLAD2_TXD")
	)
	(segment
		(start 25.603708 -224.427034)
		(end 20.59178 -229.438962)
		(width 0.127)
		(layer "In2.Cu")
		(net "T3_BLAD2_TXD")
	)
	(segment
		(start 90.1319 -97.71507)
		(end 90.71991 -97.71507)
		(width 0.127)
		(layer "In2.Cu")
		(net "T3_BLAD2_TXD")
	)
	(segment
		(start 25.603708 -199.792844)
		(end 25.603708 -224.427034)
		(width 0.127)
		(layer "In2.Cu")
		(net "T3_BLAD2_TXD")
	)
	(segment
		(start 22.29739 -183.490108)
		(end 22.29739 -196.486526)
		(width 0.127)
		(layer "In2.Cu")
		(net "T3_BLAD2_TXD")
	)
	(segment
		(start 85.222588 -102.624382)
		(end 90.1319 -97.71507)
		(width 0.127)
		(layer "In2.Cu")
		(net "T3_BLAD2_TXD")
	)
	(segment
		(start 20.59178 -230.866442)
		(end 13.787628 -237.670594)
		(width 0.127)
		(layer "In2.Cu")
		(net "T3_BLAD2_TXD")
	)
	(segment
		(start 85.150706 -137.081768)
		(end 84.393532 -137.838942)
		(width 0.127)
		(layer "In2.Cu")
		(net "T3_BLAD2_TXD")
	)
	(segment
		(start 22.29739 -196.486526)
		(end 25.603708 -199.792844)
		(width 0.127)
		(layer "In2.Cu")
		(net "T3_BLAD2_TXD")
	)
	(segment
		(start 85.150706 -114.71783)
		(end 85.150706 -137.081768)
		(width 0.127)
		(layer "In2.Cu")
		(net "T3_BLAD2_TXD")
	)
	(segment
		(start 84.273644 -103.573326)
		(end 84.273644 -113.840768)
		(width 0.127)
		(layer "In2.Cu")
		(net "T3_BLAD2_TXD")
	)
	(segment
		(start 13.787628 -237.670594)
		(end 6.448806 -237.670594)
		(width 0.127)
		(layer "In2.Cu")
		(net "T3_BLAD2_TXD")
	)
	(segment
		(start 81.696306 -144.766538)
		(end 78.530958 -147.931886)
		(width 0.127)
		(layer "In2.Cu")
		(net "T3_BLAD2_TXD")
	)
	(segment
		(start 59.003692 -177.163222)
		(end 28.624276 -177.163222)
		(width 0.127)
		(layer "In2.Cu")
		(net "T3_BLAD2_TXD")
	)
	(segment
		(start 7.721346 -324.911974)
		(end 7.168134 -325.465186)
		(width 0.1524)
		(layer "F.Cu")
		(net "FAN1_TACH")
	)
	(segment
		(start 4.745228 -325.465186)
		(end 3.949954 -324.669912)
		(width 0.1524)
		(layer "F.Cu")
		(net "FAN1_TACH")
	)
	(segment
		(start 8.959088 -324.911974)
		(end 7.721346 -324.911974)
		(width 0.1524)
		(layer "F.Cu")
		(net "FAN1_TACH")
	)
	(segment
		(start 12.752324 -325.376286)
		(end 9.4234 -325.376286)
		(width 0.1524)
		(layer "F.Cu")
		(net "FAN1_TACH")
	)
	(segment
		(start 7.168134 -325.465186)
		(end 4.745228 -325.465186)
		(width 0.1524)
		(layer "F.Cu")
		(net "FAN1_TACH")
	)
	(segment
		(start 13.063728 -325.064882)
		(end 12.752324 -325.376286)
		(width 0.1524)
		(layer "F.Cu")
		(net "FAN1_TACH")
	)
	(segment
		(start 9.4234 -325.376286)
		(end 8.959088 -324.911974)
		(width 0.1524)
		(layer "F.Cu")
		(net "FAN1_TACH")
	)
	(segment
		(start 17.782794 -395.572996)
		(end 17.782794 -410.304488)
		(width 0.1524)
		(layer "B.Cu")
		(net "FAN1_TACH")
	)
	(segment
		(start 8.60552 -330.61021)
		(end 9.167622 -331.172312)
		(width 0.1524)
		(layer "B.Cu")
		(net "FAN1_TACH")
	)
	(segment
		(start 9.167622 -344.047826)
		(end 11.871198 -346.751402)
		(width 0.1524)
		(layer "B.Cu")
		(net "FAN1_TACH")
	)
	(segment
		(start 8.12038 -330.61021)
		(end 8.60552 -330.61021)
		(width 0.1524)
		(layer "B.Cu")
		(net "FAN1_TACH")
	)
	(segment
		(start 2.638806 -461.574388)
		(end 4.167124 -463.102706)
		(width 0.1524)
		(layer "B.Cu")
		(net "FAN1_TACH")
	)
	(segment
		(start 3.949954 -325.515986)
		(end 4.769866 -326.335898)
		(width 0.1524)
		(layer "B.Cu")
		(net "FAN1_TACH")
	)
	(segment
		(start 10.03554 -463.102706)
		(end 11.444224 -461.694022)
		(width 0.1524)
		(layer "B.Cu")
		(net "FAN1_TACH")
	)
	(segment
		(start 3.949954 -324.669912)
		(end 3.949954 -325.515986)
		(width 0.1524)
		(layer "B.Cu")
		(net "FAN1_TACH")
	)
	(segment
		(start 10.906252 -372.490238)
		(end 10.906252 -388.696454)
		(width 0.1524)
		(layer "B.Cu")
		(net "FAN1_TACH")
	)
	(segment
		(start 11.871198 -371.525292)
		(end 10.906252 -372.490238)
		(width 0.1524)
		(layer "B.Cu")
		(net "FAN1_TACH")
	)
	(segment
		(start 2.638806 -448.289934)
		(end 2.638806 -461.574388)
		(width 0.1524)
		(layer "B.Cu")
		(net "FAN1_TACH")
	)
	(segment
		(start 4.338828 -423.748454)
		(end 4.338828 -446.589912)
		(width 0.1524)
		(layer "B.Cu")
		(net "FAN1_TACH")
	)
	(segment
		(start 10.906252 -388.696454)
		(end 17.782794 -395.572996)
		(width 0.1524)
		(layer "B.Cu")
		(net "FAN1_TACH")
	)
	(segment
		(start 4.769866 -326.335898)
		(end 4.769866 -328.229468)
		(width 0.1524)
		(layer "B.Cu")
		(net "FAN1_TACH")
	)
	(segment
		(start 17.782794 -410.304488)
		(end 4.338828 -423.748454)
		(width 0.1524)
		(layer "B.Cu")
		(net "FAN1_TACH")
	)
	(segment
		(start 4.769866 -328.229468)
		(end 6.121908 -329.58151)
		(width 0.1524)
		(layer "B.Cu")
		(net "FAN1_TACH")
	)
	(segment
		(start 11.871198 -346.751402)
		(end 11.871198 -371.525292)
		(width 0.1524)
		(layer "B.Cu")
		(net "FAN1_TACH")
	)
	(segment
		(start 4.167124 -463.102706)
		(end 10.03554 -463.102706)
		(width 0.1524)
		(layer "B.Cu")
		(net "FAN1_TACH")
	)
	(segment
		(start 6.121908 -329.58151)
		(end 7.09168 -329.58151)
		(width 0.1524)
		(layer "B.Cu")
		(net "FAN1_TACH")
	)
	(segment
		(start 7.09168 -329.58151)
		(end 8.12038 -330.61021)
		(width 0.1524)
		(layer "B.Cu")
		(net "FAN1_TACH")
	)
	(segment
		(start 9.167622 -331.172312)
		(end 9.167622 -344.047826)
		(width 0.1524)
		(layer "B.Cu")
		(net "FAN1_TACH")
	)
	(segment
		(start 4.338828 -446.589912)
		(end 2.638806 -448.289934)
		(width 0.1524)
		(layer "B.Cu")
		(net "FAN1_TACH")
	)
	(segment
		(start 46.785784 -244.518434)
		(end 46.785784 -245.712234)
		(width 0.508)
		(layer "F.Cu")
		(net "GND")
	)
	(segment
		(start 69.726556 -171.735496)
		(end 69.726556 -170.736768)
		(width 0.508)
		(layer "F.Cu")
		(net "GND")
	)
	(segment
		(start 67.14109 -206.29118)
		(end 68.592192 -206.29118)
		(width 0.4572)
		(layer "F.Cu")
		(net "GND")
	)
	(segment
		(start 72.81291 -108.96981)
		(end 72.81291 -109.942376)
		(width 0.508)
		(layer "F.Cu")
		(net "GND")
	)
	(segment
		(start 22.112478 -448.10426)
		(end 22.846792 -448.10426)
		(width 0.508)
		(layer "F.Cu")
		(net "GND")
	)
	(segment
		(start 67.92468 -38.421056)
		(end 67.92468 -37.47516)
		(width 0.508)
		(layer "F.Cu")
		(net "GND")
	)
	(segment
		(start 66.823844 -38.421056)
		(end 66.823844 -37.50945)
		(width 0.508)
		(layer "F.Cu")
		(net "GND")
	)
	(segment
		(start 67.101974 -216.215722)
		(end 67.101974 -215.227916)
		(width 0.508)
		(layer "F.Cu")
		(net "GND")
	)
	(segment
		(start 70.678548 -483.08133)
		(end 70.678548 -482.175058)
		(width 0.508)
		(layer "F.Cu")
		(net "GND")
	)
	(segment
		(start 46.808136 -239.669066)
		(end 46.808136 -240.876074)
		(width 0.508)
		(layer "F.Cu")
		(net "GND")
	)
	(segment
		(start 17.162272 -330.055474)
		(end 17.162272 -329.350116)
		(width 0.4572)
		(layer "F.Cu")
		(net "GND")
	)
	(segment
		(start 25.702006 -277.377144)
		(end 24.624792 -277.377144)
		(width 0.508)
		(layer "F.Cu")
		(net "GND")
	)
	(segment
		(start 74.69886 -419.688772)
		(end 74.69886 -420.765732)
		(width 0.508)
		(layer "F.Cu")
		(net "GND")
	)
	(segment
		(start 26.78557 -373.44858)
		(end 26.76906 -373.43207)
		(width 0.508)
		(layer "F.Cu")
		(net "GND")
	)
	(segment
		(start 66.689986 -303.609756)
		(end 66.689986 -302.711358)
		(width 0.508)
		(layer "F.Cu")
		(net "GND")
	)
	(segment
		(start 25.725628 -278.486362)
		(end 25.057608 -278.486362)
		(width 0.4572)
		(layer "F.Cu")
		(net "GND")
	)
	(segment
		(start 71.815198 -197.792594)
		(end 71.815198 -198.791322)
		(width 0.508)
		(layer "F.Cu")
		(net "GND")
	)
	(segment
		(start 72.520302 -82.935318)
		(end 72.520302 -81.962752)
		(width 0.508)
		(layer "F.Cu")
		(net "GND")
	)
	(segment
		(start 78.393544 -384.526282)
		(end 79.729076 -384.526282)
		(width 0.508)
		(layer "F.Cu")
		(net "GND")
	)
	(segment
		(start 71.11746 -374.811798)
		(end 71.11746 -375.77649)
		(width 0.508)
		(layer "F.Cu")
		(net "GND")
	)
	(segment
		(start 73.963276 -241.918744)
		(end 73.963276 -242.936268)
		(width 0.508)
		(layer "F.Cu")
		(net "GND")
	)
	(segment
		(start 25.457658 -361.78236)
		(end 24.740362 -361.78236)
		(width 0.508)
		(layer "F.Cu")
		(net "GND")
	)
	(segment
		(start 77.43698 -393.052554)
		(end 77.43698 -391.975594)
		(width 0.508)
		(layer "F.Cu")
		(net "GND")
	)
	(segment
		(start 70.558152 -216.215722)
		(end 70.558152 -215.198198)
		(width 0.508)
		(layer "F.Cu")
		(net "GND")
	)
	(segment
		(start 70.308978 -303.609756)
		(end 70.308978 -302.711358)
		(width 0.508)
		(layer "F.Cu")
		(net "GND")
	)
	(segment
		(start 69.370956 -198.637144)
		(end 69.370956 -199.635872)
		(width 0.508)
		(layer "F.Cu")
		(net "GND")
	)
	(segment
		(start 67.187064 -127.233426)
		(end 67.187064 -126.324614)
		(width 0.508)
		(layer "F.Cu")
		(net "GND")
	)
	(segment
		(start 73.199752 -286.366204)
		(end 73.199752 -287.311084)
		(width 0.508)
		(layer "F.Cu")
		(net "GND")
	)
	(segment
		(start 46.311566 -260.355588)
		(end 46.779942 -260.355588)
		(width 0.508)
		(layer "F.Cu")
		(net "GND")
	)
	(segment
		(start 40.471344 -197.274942)
		(end 40.927274 -196.819012)
		(width 0.508)
		(layer "F.Cu")
		(net "GND")
	)
	(segment
		(start 15.140686 -451.706234)
		(end 14.33195 -451.706234)
		(width 0.508)
		(layer "F.Cu")
		(net "GND")
	)
	(segment
		(start 40.249602 -17.30502)
		(end 41.296844 -17.30502)
		(width 0.508)
		(layer "F.Cu")
		(net "GND")
	)
	(segment
		(start 74.804524 -82.935318)
		(end 74.804524 -81.962752)
		(width 0.508)
		(layer "F.Cu")
		(net "GND")
	)
	(segment
		(start 68.607686 -171.735496)
		(end 68.607686 -170.736768)
		(width 0.508)
		(layer "F.Cu")
		(net "GND")
	)
	(segment
		(start 25.668224 -186.752992)
		(end 24.773636 -186.752992)
		(width 0.508)
		(layer "F.Cu")
		(net "GND")
	)
	(segment
		(start 15.313406 -447.797428)
		(end 13.99032 -447.797428)
		(width 0.508)
		(layer "F.Cu")
		(net "GND")
	)
	(segment
		(start 26.843736 -285.030164)
		(end 26.843736 -285.983426)
		(width 0.508)
		(layer "F.Cu")
		(net "GND")
	)
	(segment
		(start 26.65476 -11.980418)
		(end 26.072084 -12.563094)
		(width 0.4572)
		(layer "F.Cu")
		(net "GND")
	)
	(segment
		(start 73.353676 -472.101672)
		(end 74.575924 -472.101672)
		(width 0.508)
		(layer "F.Cu")
		(net "GND")
	)
	(segment
		(start 74.345292 -286.366204)
		(end 74.345292 -287.311084)
		(width 0.508)
		(layer "F.Cu")
		(net "GND")
	)
	(segment
		(start 25.474422 -367.771426)
		(end 24.75611 -367.771426)
		(width 0.4572)
		(layer "F.Cu")
		(net "GND")
	)
	(segment
		(start 26.88463 -5.61086)
		(end 27.00909 -5.73532)
		(width 0.4572)
		(layer "F.Cu")
		(net "GND")
	)
	(segment
		(start 25.703784 -189.265306)
		(end 24.923496 -189.265306)
		(width 0.4572)
		(layer "F.Cu")
		(net "GND")
	)
	(segment
		(start 20.415504 -457.541122)
		(end 20.415504 -456.225402)
		(width 0.508)
		(layer "F.Cu")
		(net "GND")
	)
	(segment
		(start 15.313406 -445.813434)
		(end 13.956792 -445.813434)
		(width 0.508)
		(layer "F.Cu")
		(net "GND")
	)
	(segment
		(start 72.478392 -154.168348)
		(end 72.478392 -155.07716)
		(width 0.508)
		(layer "F.Cu")
		(net "GND")
	)
	(segment
		(start 71.405496 -259.050028)
		(end 71.405496 -258.105148)
		(width 0.508)
		(layer "F.Cu")
		(net "GND")
	)
	(segment
		(start 25.825958 -453.535034)
		(end 25.157938 -453.535034)
		(width 0.508)
		(layer "F.Cu")
		(net "GND")
	)
	(segment
		(start 40.792908 -374.14708)
		(end 41.209468 -373.73052)
		(width 0.508)
		(layer "F.Cu")
		(net "GND")
	)
	(segment
		(start 25.531572 -94.464886)
		(end 24.754078 -94.464886)
		(width 0.508)
		(layer "F.Cu")
		(net "GND")
	)
	(segment
		(start 76.120498 -19.149822)
		(end 76.120498 -20.009612)
		(width 0.508)
		(layer "F.Cu")
		(net "GND")
	)
	(segment
		(start 25.825958 -448.493388)
		(end 25.172162 -448.493388)
		(width 0.508)
		(layer "F.Cu")
		(net "GND")
	)
	(segment
		(start 25.457658 -365.50092)
		(end 24.636984 -365.50092)
		(width 0.508)
		(layer "F.Cu")
		(net "GND")
	)
	(segment
		(start 72.157844 -420.533322)
		(end 72.157844 -421.610282)
		(width 0.508)
		(layer "F.Cu")
		(net "GND")
	)
	(segment
		(start 72.087232 -331.577188)
		(end 72.087232 -332.475586)
		(width 0.508)
		(layer "F.Cu")
		(net "GND")
	)
	(segment
		(start 72.19696 -350.098868)
		(end 72.19696 -349.134176)
		(width 0.508)
		(layer "F.Cu")
		(net "GND")
	)
	(segment
		(start 69.108828 -303.609756)
		(end 69.108828 -302.711358)
		(width 0.508)
		(layer "F.Cu")
		(net "GND")
	)
	(segment
		(start 75.10145 -393.052554)
		(end 75.10145 -391.975594)
		(width 0.508)
		(layer "F.Cu")
		(net "GND")
	)
	(segment
		(start 25.668224 -183.06923)
		(end 25.042114 -183.06923)
		(width 0.508)
		(layer "F.Cu")
		(net "GND")
	)
	(segment
		(start 26.528268 -196.6214)
		(end 25.715976 -196.6214)
		(width 0.4572)
		(layer "F.Cu")
		(net "GND")
	)
	(segment
		(start 26.65476 -11.75639)
		(end 26.65476 -11.980418)
		(width 0.4572)
		(layer "F.Cu")
		(net "GND")
	)
	(segment
		(start 21.911564 -449.860162)
		(end 22.564598 -449.860162)
		(width 0.508)
		(layer "F.Cu")
		(net "GND")
	)
	(segment
		(start 71.96836 -171.735496)
		(end 71.96836 -170.736768)
		(width 0.508)
		(layer "F.Cu")
		(net "GND")
	)
	(segment
		(start 71.390764 -464.787234)
		(end 71.390764 -465.980526)
		(width 0.508)
		(layer "F.Cu")
		(net "GND")
	)
	(segment
		(start 75.059286 -153.323798)
		(end 75.059286 -154.23261)
		(width 0.508)
		(layer "F.Cu")
		(net "GND")
	)
	(segment
		(start 77.254354 -19.149822)
		(end 77.254354 -20.009612)
		(width 0.508)
		(layer "F.Cu")
		(net "GND")
	)
	(segment
		(start 41.427146 -370.095526)
		(end 40.704008 -370.099336)
		(width 0.508)
		(layer "F.Cu")
		(net "GND")
	)
	(segment
		(start 70.236842 -38.421056)
		(end 70.236842 -37.48659)
		(width 0.508)
		(layer "F.Cu")
		(net "GND")
	)
	(segment
		(start 18.33372 -174.17034)
		(end 20.202144 -174.17034)
		(width 0.508)
		(layer "F.Cu")
		(net "GND")
	)
	(segment
		(start 17.875504 -457.541122)
		(end 17.875504 -456.281282)
		(width 0.508)
		(layer "F.Cu")
		(net "GND")
	)
	(segment
		(start 25.457658 -366.710722)
		(end 24.636222 -366.710722)
		(width 0.508)
		(layer "F.Cu")
		(net "GND")
	)
	(segment
		(start 40.989758 -103.52405)
		(end 40.25646 -103.52405)
		(width 0.508)
		(layer "F.Cu")
		(net "GND")
	)
	(segment
		(start 67.291966 -29.351986)
		(end 67.977258 -29.351986)
		(width 0.4572)
		(layer "F.Cu")
		(net "GND")
	)
	(segment
		(start 69.116194 -117.627146)
		(end 69.847714 -117.627146)
		(width 0.4572)
		(layer "F.Cu")
		(net "GND")
	)
	(segment
		(start 20.717002 -179.957984)
		(end 20.717002 -179.180998)
		(width 0.508)
		(layer "F.Cu")
		(net "GND")
	)
	(segment
		(start 41.4655 -461.1751)
		(end 41.4655 -461.170274)
		(width 0.508)
		(layer "F.Cu")
		(net "GND")
	)
	(segment
		(start 26.547572 -108.230416)
		(end 25.90546 -108.230416)
		(width 0.4572)
		(layer "F.Cu")
		(net "GND")
	)
	(segment
		(start 76.299568 -393.052554)
		(end 76.299568 -391.975594)
		(width 0.508)
		(layer "F.Cu")
		(net "GND")
	)
	(segment
		(start 25.702006 -276.12213)
		(end 24.625046 -276.12213)
		(width 0.508)
		(layer "F.Cu")
		(net "GND")
	)
	(segment
		(start 46.779942 -260.355588)
		(end 47.84979 -259.28574)
		(width 0.508)
		(layer "F.Cu")
		(net "GND")
	)
	(segment
		(start 69.073522 -38.421056)
		(end 69.073522 -37.49802)
		(width 0.508)
		(layer "F.Cu")
		(net "GND")
	)
	(segment
		(start 78.397354 -19.149822)
		(end 78.397354 -20.009612)
		(width 0.508)
		(layer "F.Cu")
		(net "GND")
	)
	(segment
		(start 41.18356 -459.16596)
		(end 40.34536 -459.16596)
		(width 0.508)
		(layer "F.Cu")
		(net "GND")
	)
	(segment
		(start 4.204208 -415.366962)
		(end 4.204208 -416.05327)
		(width 0.508)
		(layer "F.Cu")
		(net "GND")
	)
	(segment
		(start 21.685504 -457.541122)
		(end 21.685504 -456.243944)
		(width 0.508)
		(layer "F.Cu")
		(net "GND")
	)
	(segment
		(start 71.518526 -109.81436)
		(end 71.518526 -110.786926)
		(width 0.508)
		(layer "F.Cu")
		(net "GND")
	)
	(segment
		(start 25.531572 -100.590096)
		(end 24.801322 -100.590096)
		(width 0.508)
		(layer "F.Cu")
		(net "GND")
	)
	(segment
		(start 4.059936 -146.374358)
		(end 4.059936 -147.027646)
		(width 0.508)
		(layer "F.Cu")
		(net "GND")
	)
	(segment
		(start 68.727066 -350.098614)
		(end 68.727066 -349.155004)
		(width 0.508)
		(layer "F.Cu")
		(net "GND")
	)
	(segment
		(start 72.284082 -438.63641)
		(end 72.284082 -437.76011)
		(width 0.508)
		(layer "F.Cu")
		(net "GND")
	)
	(segment
		(start 73.687178 -259.050028)
		(end 73.687178 -258.105148)
		(width 0.508)
		(layer "F.Cu")
		(net "GND")
	)
	(segment
		(start 40.456612 -281.140662)
		(end 41.18356 -281.140662)
		(width 0.508)
		(layer "F.Cu")
		(net "GND")
	)
	(segment
		(start 72.635364 -242.763294)
		(end 72.635364 -243.780818)
		(width 0.508)
		(layer "F.Cu")
		(net "GND")
	)
	(segment
		(start 40.959278 -106.900726)
		(end 40.959278 -106.221276)
		(width 0.508)
		(layer "F.Cu")
		(net "GND")
	)
	(segment
		(start 25.85212 -454.646538)
		(end 25.220676 -454.646538)
		(width 0.4572)
		(layer "F.Cu")
		(net "GND")
	)
	(segment
		(start 19.145504 -457.541122)
		(end 19.145504 -456.243944)
		(width 0.508)
		(layer "F.Cu")
		(net "GND")
	)
	(segment
		(start 25.597612 -9.509252)
		(end 24.743918 -9.509252)
		(width 0.508)
		(layer "F.Cu")
		(net "GND")
	)
	(segment
		(start 40.959278 -106.221276)
		(end 40.959024 -106.22153)
		(width 0.508)
		(layer "F.Cu")
		(net "GND")
	)
	(segment
		(start 25.825958 -447.250058)
		(end 25.163272 -447.250058)
		(width 0.508)
		(layer "F.Cu")
		(net "GND")
	)
	(segment
		(start 70.555104 -127.233426)
		(end 70.555104 -126.324614)
		(width 0.508)
		(layer "F.Cu")
		(net "GND")
	)
	(segment
		(start 80.662018 -19.149822)
		(end 80.662018 -20.009612)
		(width 0.508)
		(layer "F.Cu")
		(net "GND")
	)
	(segment
		(start 81.29143 -508.515874)
		(end 81.29143 -509.32461)
		(width 0.508)
		(layer "F.Cu")
		(net "GND")
	)
	(segment
		(start 41.103804 -192.216278)
		(end 40.3733 -192.216278)
		(width 0.508)
		(layer "F.Cu")
		(net "GND")
	)
	(segment
		(start 26.450798 -19.859244)
		(end 26.445464 -19.864578)
		(width 0.508)
		(layer "F.Cu")
		(net "GND")
	)
	(segment
		(start 70.658736 -197.792594)
		(end 70.658736 -198.791322)
		(width 0.508)
		(layer "F.Cu")
		(net "GND")
	)
	(segment
		(start 16.017494 -330.097384)
		(end 16.017494 -329.263248)
		(width 0.4572)
		(layer "F.Cu")
		(net "GND")
	)
	(segment
		(start 41.427146 -370.099336)
		(end 41.427146 -370.095526)
		(width 0.508)
		(layer "F.Cu")
		(net "GND")
	)
	(segment
		(start 72.802242 -463.942684)
		(end 72.802242 -464.6676)
		(width 0.508)
		(layer "F.Cu")
		(net "GND")
	)
	(segment
		(start 15.313406 -449.79209)
		(end 14.108176 -449.79209)
		(width 0.508)
		(layer "F.Cu")
		(net "GND")
	)
	(segment
		(start 22.510496 -446.545208)
		(end 22.510496 -447.011552)
		(width 0.508)
		(layer "F.Cu")
		(net "GND")
	)
	(segment
		(start 22.624034 -444.049658)
		(end 23.817834 -444.049658)
		(width 0.508)
		(layer "F.Cu")
		(net "GND")
	)
	(segment
		(start 74.709782 -330.732638)
		(end 74.709782 -331.631036)
		(width 0.508)
		(layer "F.Cu")
		(net "GND")
	)
	(segment
		(start 69.982334 -374.811798)
		(end 69.982334 -375.77649)
		(width 0.508)
		(layer "F.Cu")
		(net "GND")
	)
	(segment
		(start 81.332832 -295.215564)
		(end 82.752184 -295.215564)
		(width 0.508)
		(layer "F.Cu")
		(net "GND")
	)
	(segment
		(start 40.275002 -461.170274)
		(end 41.4655 -461.1751)
		(width 0.508)
		(layer "F.Cu")
		(net "GND")
	)
	(segment
		(start 25.702006 -272.345404)
		(end 24.580596 -272.345404)
		(width 0.508)
		(layer "F.Cu")
		(net "GND")
	)
	(segment
		(start 79.524606 -19.149822)
		(end 79.524606 -20.009612)
		(width 0.508)
		(layer "F.Cu")
		(net "GND")
	)
	(segment
		(start 13.74902 -334.823562)
		(end 13.74902 -333.695802)
		(width 0.508)
		(layer "F.Cu")
		(net "GND")
	)
	(segment
		(start 71.044562 -438.63641)
		(end 71.044562 -437.743092)
		(width 0.508)
		(layer "F.Cu")
		(net "GND")
	)
	(segment
		(start 26.445464 -19.864578)
		(end 26.445464 -20.969478)
		(width 0.508)
		(layer "F.Cu")
		(net "GND")
	)
	(segment
		(start 40.51427 -371.513354)
		(end 41.281096 -371.513354)
		(width 0.508)
		(layer "F.Cu")
		(net "GND")
	)
	(segment
		(start 74.798682 -19.994372)
		(end 74.798682 -21.013928)
		(width 0.508)
		(layer "F.Cu")
		(net "GND")
	)
	(segment
		(start 68.972938 -65.218056)
		(end 68.972938 -66.129662)
		(width 0.508)
		(layer "F.Cu")
		(net "GND")
	)
	(segment
		(start 46.825662 -253.125732)
		(end 46.825662 -254.395224)
		(width 0.508)
		(layer "F.Cu")
		(net "GND")
	)
	(segment
		(start 40.30091 -194.114674)
		(end 41.057576 -194.114674)
		(width 0.508)
		(layer "F.Cu")
		(net "GND")
	)
	(segment
		(start 73.909936 -153.323798)
		(end 73.909936 -154.23261)
		(width 0.508)
		(layer "F.Cu")
		(net "GND")
	)
	(segment
		(start 2.772156 -146.357594)
		(end 2.772156 -147.027392)
		(width 0.508)
		(layer "F.Cu")
		(net "GND")
	)
	(segment
		(start 22.510496 -447.011552)
		(end 22.112478 -447.40957)
		(width 0.508)
		(layer "F.Cu")
		(net "GND")
	)
	(segment
		(start 25.702006 -271.14881)
		(end 24.613616 -271.14881)
		(width 0.508)
		(layer "F.Cu")
		(net "GND")
	)
	(segment
		(start 41.245536 -14.412976)
		(end 40.557704 -14.412976)
		(width 0.508)
		(layer "F.Cu")
		(net "GND")
	)
	(segment
		(start 26.839926 -461.829912)
		(end 26.839926 -461.067658)
		(width 0.4572)
		(layer "F.Cu")
		(net "GND")
	)
	(segment
		(start 46.765972 -257.889502)
		(end 46.765972 -258.89712)
		(width 0.508)
		(layer "F.Cu")
		(net "GND")
	)
	(segment
		(start 41.792906 -283.49829)
		(end 40.86098 -283.49829)
		(width 0.508)
		(layer "F.Cu")
		(net "GND")
	)
	(segment
		(start 40.221408 -18.414238)
		(end 41.082468 -18.414238)
		(width 0.508)
		(layer "F.Cu")
		(net "GND")
	)
	(segment
		(start 73.63333 -82.935318)
		(end 73.63333 -81.962752)
		(width 0.508)
		(layer "F.Cu")
		(net "GND")
	)
	(segment
		(start 69.44487 -127.233426)
		(end 69.44487 -126.324614)
		(width 0.508)
		(layer "F.Cu")
		(net "GND")
	)
	(segment
		(start 70.260718 -64.373506)
		(end 70.260718 -65.1256)
		(width 0.508)
		(layer "F.Cu")
		(net "GND")
	)
	(segment
		(start 68.592192 -206.29118)
		(end 68.59778 -206.296768)
		(width 0.4572)
		(layer "F.Cu")
		(net "GND")
	)
	(segment
		(start 26.78557 -374.115076)
		(end 26.78557 -373.44858)
		(width 0.508)
		(layer "F.Cu")
		(net "GND")
	)
	(segment
		(start 2.832862 -415.40049)
		(end 2.832862 -416.16249)
		(width 0.508)
		(layer "F.Cu")
		(net "GND")
	)
	(segment
		(start 40.334692 -374.14708)
		(end 40.792908 -374.14708)
		(width 0.508)
		(layer "F.Cu")
		(net "GND")
	)
	(segment
		(start 22.112478 -447.40957)
		(end 22.112478 -448.10426)
		(width 0.508)
		(layer "F.Cu")
		(net "GND")
	)
	(segment
		(start 2.931414 -396.058136)
		(end 2.931414 -396.83182)
		(width 0.508)
		(layer "F.Cu")
		(net "GND")
	)
	(segment
		(start 71.810118 -483.08133)
		(end 71.810118 -482.175058)
		(width 0.508)
		(layer "F.Cu")
		(net "GND")
	)
	(segment
		(start 19.758914 -172.90034)
		(end 20.19808 -173.339506)
		(width 0.508)
		(layer "F.Cu")
		(net "GND")
	)
	(segment
		(start 79.898748 -509.119378)
		(end 79.898748 -510.308098)
		(width 0.508)
		(layer "F.Cu")
		(net "GND")
	)
	(segment
		(start 69.774816 -438.63641)
		(end 69.774816 -437.691784)
		(width 0.508)
		(layer "F.Cu")
		(net "GND")
	)
	(segment
		(start 73.532746 -438.63641)
		(end 73.532746 -437.82869)
		(width 0.508)
		(layer "F.Cu")
		(net "GND")
	)
	(segment
		(start 73.927716 -393.052554)
		(end 73.927716 -391.975594)
		(width 0.508)
		(layer "F.Cu")
		(net "GND")
	)
	(segment
		(start 69.549518 -483.08133)
		(end 69.549518 -482.175058)
		(width 0.508)
		(layer "F.Cu")
		(net "GND")
	)
	(segment
		(start 81.78927 -19.149822)
		(end 81.78927 -20.009612)
		(width 0.508)
		(layer "F.Cu")
		(net "GND")
	)
	(segment
		(start 69.41947 -216.215722)
		(end 69.41947 -215.198198)
		(width 0.508)
		(layer "F.Cu")
		(net "GND")
	)
	(segment
		(start 25.531572 -95.65132)
		(end 24.774144 -95.65132)
		(width 0.508)
		(layer "F.Cu")
		(net "GND")
	)
	(segment
		(start 73.45934 -330.732638)
		(end 73.45934 -331.631036)
		(width 0.508)
		(layer "F.Cu")
		(net "GND")
	)
	(segment
		(start 70.85457 -171.735496)
		(end 70.85457 -170.736768)
		(width 0.508)
		(layer "F.Cu")
		(net "GND")
	)
	(segment
		(start 68.639436 -375.656348)
		(end 68.639436 -376.62104)
		(width 0.508)
		(layer "F.Cu")
		(net "GND")
	)
	(segment
		(start 13.853922 -330.080874)
		(end 13.853922 -329.314302)
		(width 0.4572)
		(layer "F.Cu")
		(net "GND")
	)
	(segment
		(start 22.524974 -178.204622)
		(end 22.524974 -178.843432)
		(width 0.508)
		(layer "F.Cu")
		(net "GND")
	)
	(segment
		(start 25.668224 -187.950348)
		(end 24.750522 -187.950348)
		(width 0.508)
		(layer "F.Cu")
		(net "GND")
	)
	(segment
		(start 23.61692 -172.90034)
		(end 21.891498 -172.90034)
		(width 0.508)
		(layer "F.Cu")
		(net "GND")
	)
	(segment
		(start 82.499962 -508.515874)
		(end 82.499962 -509.339088)
		(width 0.508)
		(layer "F.Cu")
		(net "GND")
	)
	(segment
		(start 25.597612 -8.344662)
		(end 24.743918 -8.344662)
		(width 0.508)
		(layer "F.Cu")
		(net "GND")
	)
	(segment
		(start 23.06828 -448.325748)
		(end 23.23084 -448.325748)
		(width 0.508)
		(layer "F.Cu")
		(net "GND")
	)
	(segment
		(start 75.151996 -241.918744)
		(end 75.151996 -242.936268)
		(width 0.508)
		(layer "F.Cu")
		(net "GND")
	)
	(segment
		(start 40.198802 -197.274942)
		(end 40.471344 -197.274942)
		(width 0.508)
		(layer "F.Cu")
		(net "GND")
	)
	(segment
		(start 46.896528 -248.705116)
		(end 46.896528 -249.789442)
		(width 0.508)
		(layer "F.Cu")
		(net "GND")
	)
	(segment
		(start 25.531572 -99.36988)
		(end 24.88819 -99.36988)
		(width 0.508)
		(layer "F.Cu")
		(net "GND")
	)
	(segment
		(start 13.820902 -318.358012)
		(end 14.594332 -318.358012)
		(width 0.4572)
		(layer "F.Cu")
		(net "GND")
	)
	(segment
		(start 67.867276 -303.609756)
		(end 67.867276 -302.711358)
		(width 0.508)
		(layer "F.Cu")
		(net "GND")
	)
	(segment
		(start 22.846792 -448.10426)
		(end 23.06828 -448.325748)
		(width 0.508)
		(layer "F.Cu")
		(net "GND")
	)
	(segment
		(start 74.0537 -463.942684)
		(end 74.0537 -464.780884)
		(width 0.508)
		(layer "F.Cu")
		(net "GND")
	)
	(segment
		(start 72.928734 -483.08133)
		(end 72.928734 -482.175058)
		(width 0.508)
		(layer "F.Cu")
		(net "GND")
	)
	(segment
		(start 68.246244 -216.215722)
		(end 68.246244 -215.261952)
		(width 0.508)
		(layer "F.Cu")
		(net "GND")
	)
	(segment
		(start 71.423022 -64.373506)
		(end 71.423022 -65.182496)
		(width 0.508)
		(layer "F.Cu")
		(net "GND")
	)
	(segment
		(start 25.457658 -360.550968)
		(end 24.84755 -360.550968)
		(width 0.508)
		(layer "F.Cu")
		(net "GND")
	)
	(segment
		(start 23.61692 -174.17034)
		(end 22.014942 -174.17034)
		(width 0.508)
		(layer "F.Cu")
		(net "GND")
	)
	(segment
		(start 68.310252 -127.233426)
		(end 68.310252 -126.324614)
		(width 0.508)
		(layer "F.Cu")
		(net "GND")
	)
	(segment
		(start 73.914508 -108.96981)
		(end 73.914508 -109.942376)
		(width 0.508)
		(layer "F.Cu")
		(net "GND")
	)
	(segment
		(start 26.88463 -5.10032)
		(end 26.88463 -5.61086)
		(width 0.4572)
		(layer "F.Cu")
		(net "GND")
	)
	(segment
		(start 70.997572 -350.098614)
		(end 70.997572 -349.133922)
		(width 0.508)
		(layer "F.Cu")
		(net "GND")
	)
	(segment
		(start 26.88463 -4.025138)
		(end 26.88463 -5.10032)
		(width 0.4572)
		(layer "F.Cu")
		(net "GND")
	)
	(segment
		(start 74.832718 -259.050028)
		(end 74.832718 -258.105148)
		(width 0.508)
		(layer "F.Cu")
		(net "GND")
	)
	(segment
		(start 25.668224 -181.847998)
		(end 25.035256 -181.847998)
		(width 0.508)
		(layer "F.Cu")
		(net "GND")
	)
	(segment
		(start 71.871332 -287.210754)
		(end 71.871332 -288.155634)
		(width 0.508)
		(layer "F.Cu")
		(net "GND")
	)
	(segment
		(start 27.452828 -10.617962)
		(end 27.452828 -9.880346)
		(width 0.4572)
		(layer "F.Cu")
		(net "GND")
	)
	(segment
		(start 18.33372 -172.90034)
		(end 19.758914 -172.90034)
		(width 0.508)
		(layer "F.Cu")
		(net "GND")
	)
	(segment
		(start 71.392796 -82.935318)
		(end 71.392796 -81.962752)
		(width 0.508)
		(layer "F.Cu")
		(net "GND")
	)
	(segment
		(start 69.863208 -350.098614)
		(end 69.863208 -349.17761)
		(width 0.508)
		(layer "F.Cu")
		(net "GND")
	)
	(segment
		(start 72.559164 -259.050028)
		(end 72.559164 -258.105148)
		(width 0.508)
		(layer "F.Cu")
		(net "GND")
	)
	(segment
		(start 3.414014 -126.68631)
		(end 3.414014 -125.974094)
		(width 0.508)
		(layer "F.Cu")
		(net "GND")
	)
	(segment
		(start 73.512934 -419.688772)
		(end 73.512934 -420.765732)
		(width 0.508)
		(layer "F.Cu")
		(net "GND")
	)
	(segment
		(start 25.825958 -452.257668)
		(end 25.113742 -452.257668)
		(width 0.508)
		(layer "F.Cu")
		(net "GND")
	)
	(via
		(at 58.716672 -255.185672)
		(size 0.508)
		(drill 0.254)
		(layers "F.Cu" "B.Cu")
		(net "GND")
	)
	(via
		(at 60.549028 -426.17898)
		(size 0.508)
		(drill 0.254)
		(layers "F.Cu" "B.Cu")
		(net "GND")
	)
	(via
		(at 57.205626 -0.762508)
		(size 0.508)
		(drill 0.254)
		(layers "F.Cu" "B.Cu")
		(net "GND")
	)
	(via
		(at 70.308978 -302.711358)
		(size 0.508)
		(drill 0.254)
		(layers "F.Cu" "B.Cu")
		(net "GND")
	)
	(via
		(at 0.762254 -279.408636)
		(size 0.508)
		(drill 0.254)
		(layers "F.Cu" "B.Cu")
		(net "GND")
	)
	(via
		(at 42.291 -30.131004)
		(size 0.508)
		(drill 0.254)
		(layers "F.Cu" "B.Cu")
		(net "GND")
	)
	(via
		(at 44.925234 -300.66996)
		(size 0.508)
		(drill 0.254)
		(layers "F.Cu" "B.Cu")
		(net "GND")
	)
	(via
		(at 70.658736 -198.791322)
		(size 0.508)
		(drill 0.254)
		(layers "F.Cu" "B.Cu")
		(net "GND")
	)
	(via
		(at 25.157938 -453.535034)
		(size 0.508)
		(drill 0.254)
		(layers "F.Cu" "B.Cu")
		(net "GND")
	)
	(via
		(at 102.238048 -436.145432)
		(size 0.508)
		(drill 0.254)
		(layers "F.Cu" "B.Cu")
		(net "GND")
	)
	(via
		(at 0.762254 -266.708636)
		(size 0.508)
		(drill 0.254)
		(layers "F.Cu" "B.Cu")
		(net "GND")
	)
	(via
		(at 60.546234 -122.524774)
		(size 0.508)
		(drill 0.254)
		(layers "F.Cu" "B.Cu")
		(net "GND")
	)
	(via
		(at 41.369488 -212.548216)
		(size 0.508)
		(drill 0.254)
		(layers "F.Cu" "B.Cu")
		(net "GND")
	)
	(via
		(at 0.762254 -495.308636)
		(size 0.508)
		(drill 0.254)
		(layers "F.Cu" "B.Cu")
		(net "GND")
	)
	(via
		(at 57.839356 -62.22873)
		(size 0.508)
		(drill 0.254)
		(layers "F.Cu" "B.Cu")
		(net "GND")
	)
	(via
		(at 44.37253 -208.97215)
		(size 0.508)
		(drill 0.254)
		(layers "F.Cu" "B.Cu")
		(net "GND")
	)
	(via
		(at 73.914508 -109.942376)
		(size 0.508)
		(drill 0.254)
		(layers "F.Cu" "B.Cu")
		(net "GND")
	)
	(via
		(at 75.059286 -154.23261)
		(size 0.508)
		(drill 0.254)
		(layers "F.Cu" "B.Cu")
		(net "GND")
	)
	(via
		(at 90.015314 -347.413834)
		(size 0.508)
		(drill 0.254)
		(layers "F.Cu" "B.Cu")
		(net "GND")
	)
	(via
		(at 63.168784 -124.535946)
		(size 0.508)
		(drill 0.254)
		(layers "F.Cu" "B.Cu")
		(net "GND")
	)
	(via
		(at 57.033922 -73.65746)
		(size 0.508)
		(drill 0.254)
		(layers "F.Cu" "B.Cu")
		(net "GND")
	)
	(via
		(at 61.986922 -162.312096)
		(size 0.508)
		(drill 0.254)
		(layers "F.Cu" "B.Cu")
		(net "GND")
	)
	(via
		(at 60.44057 -14.477746)
		(size 0.508)
		(drill 0.254)
		(layers "F.Cu" "B.Cu")
		(net "GND")
	)
	(via
		(at 62.406784 -126.426468)
		(size 0.508)
		(drill 0.254)
		(layers "F.Cu" "B.Cu")
		(net "GND")
	)
	(via
		(at 61.178948 -67.815968)
		(size 0.508)
		(drill 0.254)
		(layers "F.Cu" "B.Cu")
		(net "GND")
	)
	(via
		(at 67.165982 -158.577534)
		(size 0.508)
		(drill 0.254)
		(layers "F.Cu" "B.Cu")
		(net "GND")
	)
	(via
		(at 13.956792 -445.813434)
		(size 0.508)
		(drill 0.254)
		(layers "F.Cu" "B.Cu")
		(net "GND")
	)
	(via
		(at 42.247566 -35.718242)
		(size 0.508)
		(drill 0.254)
		(layers "F.Cu" "B.Cu")
		(net "GND")
	)
	(via
		(at 45.937424 -386.211826)
		(size 0.508)
		(drill 0.254)
		(layers "F.Cu" "B.Cu")
		(net "GND")
	)
	(via
		(at 40.49522 -119.108982)
		(size 0.508)
		(drill 0.254)
		(layers "F.Cu" "B.Cu")
		(net "GND")
	)
	(via
		(at 61.408818 -241.923316)
		(size 0.508)
		(drill 0.254)
		(layers "F.Cu" "B.Cu")
		(net "GND")
	)
	(via
		(at 58.307986 -427.85411)
		(size 0.508)
		(drill 0.254)
		(layers "F.Cu" "B.Cu")
		(net "GND")
	)
	(via
		(at 60.50788 -158.361126)
		(size 0.508)
		(drill 0.254)
		(layers "F.Cu" "B.Cu")
		(net "GND")
	)
	(via
		(at 42.131488 -212.548216)
		(size 0.508)
		(drill 0.254)
		(layers "F.Cu" "B.Cu")
		(net "GND")
	)
	(via
		(at 60.646818 -247.333008)
		(size 0.508)
		(drill 0.254)
		(layers "F.Cu" "B.Cu")
		(net "GND")
	)
	(via
		(at 59.023758 -128.467612)
		(size 0.508)
		(drill 0.254)
		(layers "F.Cu" "B.Cu")
		(net "GND")
	)
	(via
		(at 64.69634 -152.784302)
		(size 0.508)
		(drill 0.254)
		(layers "F.Cu" "B.Cu")
		(net "GND")
	)
	(via
		(at 62.453012 -427.85411)
		(size 0.508)
		(drill 0.254)
		(layers "F.Cu" "B.Cu")
		(net "GND")
	)
	(via
		(at 60.646818 -243.756942)
		(size 0.508)
		(drill 0.254)
		(layers "F.Cu" "B.Cu")
		(net "GND")
	)
	(via
		(at 102.238048 -258.345432)
		(size 0.508)
		(drill 0.254)
		(layers "F.Cu" "B.Cu")
		(net "GND")
	)
	(via
		(at 39.34968 -487.227118)
		(size 0.508)
		(drill 0.254)
		(layers "F.Cu" "B.Cu")
		(net "GND")
	)
	(via
		(at 92.244926 -347.413834)
		(size 0.508)
		(drill 0.254)
		(layers "F.Cu" "B.Cu")
		(net "GND")
	)
	(via
		(at 62.844426 -253.275846)
		(size 0.508)
		(drill 0.254)
		(layers "F.Cu" "B.Cu")
		(net "GND")
	)
	(via
		(at 41.18356 -281.140662)
		(size 0.508)
		(drill 0.254)
		(layers "F.Cu" "B.Cu")
		(net "GND")
	)
	(via
		(at 60.080398 -65.804796)
		(size 0.508)
		(drill 0.254)
		(layers "F.Cu" "B.Cu")
		(net "GND")
	)
	(via
		(at 58.305192 -117.115082)
		(size 0.508)
		(drill 0.254)
		(layers "F.Cu" "B.Cu")
		(net "GND")
	)
	(via
		(at 63.06312 -21.955506)
		(size 0.508)
		(drill 0.254)
		(layers "F.Cu" "B.Cu")
		(net "GND")
	)
	(via
		(at 59.787028 -426.17898)
		(size 0.508)
		(drill 0.254)
		(layers "F.Cu" "B.Cu")
		(net "GND")
	)
	(via
		(at 69.982334 -375.77649)
		(size 0.508)
		(drill 0.254)
		(layers "F.Cu" "B.Cu")
		(net "GND")
	)
	(via
		(at 39.689786 -124.69622)
		(size 0.508)
		(drill 0.254)
		(layers "F.Cu" "B.Cu")
		(net "GND")
	)
	(via
		(at 69.847714 -117.627146)
		(size 0.508)
		(drill 0.254)
		(layers "F.Cu" "B.Cu")
		(net "GND")
	)
	(via
		(at 58.264552 -433.796948)
		(size 0.508)
		(drill 0.254)
		(layers "F.Cu" "B.Cu")
		(net "GND")
	)
	(via
		(at 61.178948 -73.65746)
		(size 0.508)
		(drill 0.254)
		(layers "F.Cu" "B.Cu")
		(net "GND")
	)
	(via
		(at 61.159136 -20.064984)
		(size 0.508)
		(drill 0.254)
		(layers "F.Cu" "B.Cu")
		(net "GND")
	)
	(via
		(at 39.393114 -473.964762)
		(size 0.508)
		(drill 0.254)
		(layers "F.Cu" "B.Cu")
		(net "GND")
	)
	(via
		(at 102.238048 -131.345432)
		(size 0.508)
		(drill 0.254)
		(layers "F.Cu" "B.Cu")
		(net "GND")
	)
	(via
		(at 43.78325 -302.34509)
		(size 0.508)
		(drill 0.254)
		(layers "F.Cu" "B.Cu")
		(net "GND")
	)
	(via
		(at 59.522106 -245.657878)
		(size 0.508)
		(drill 0.254)
		(layers "F.Cu" "B.Cu")
		(net "GND")
	)
	(via
		(at 77.254354 -20.009612)
		(size 0.508)
		(drill 0.254)
		(layers "F.Cu" "B.Cu")
		(net "GND")
	)
	(via
		(at 60.603384 -249.34418)
		(size 0.508)
		(drill 0.254)
		(layers "F.Cu" "B.Cu")
		(net "GND")
	)
	(via
		(at 43.009566 -41.559734)
		(size 0.508)
		(drill 0.254)
		(layers "F.Cu" "B.Cu")
		(net "GND")
	)
	(via
		(at 57.839356 -60.395104)
		(size 0.508)
		(drill 0.254)
		(layers "F.Cu" "B.Cu")
		(net "GND")
	)
	(via
		(at 62.030356 -152.784302)
		(size 0.508)
		(drill 0.254)
		(layers "F.Cu" "B.Cu")
		(net "GND")
	)
	(via
		(at 55.659274 -424.278044)
		(size 0.508)
		(drill 0.254)
		(layers "F.Cu" "B.Cu")
		(net "GND")
	)
	(via
		(at 62.792356 -152.784302)
		(size 0.508)
		(drill 0.254)
		(layers "F.Cu" "B.Cu")
		(net "GND")
	)
	(via
		(at 59.857386 -304.734214)
		(size 0.508)
		(drill 0.254)
		(layers "F.Cu" "B.Cu")
		(net "GND")
	)
	(via
		(at 25.220676 -454.646538)
		(size 0.508)
		(drill 0.254)
		(layers "F.Cu" "B.Cu")
		(net "GND")
	)
	(via
		(at 46.825662 -254.395224)
		(size 0.508)
		(drill 0.254)
		(layers "F.Cu" "B.Cu")
		(net "GND")
	)
	(via
		(at 63.168784 -130.377438)
		(size 0.508)
		(drill 0.254)
		(layers "F.Cu" "B.Cu")
		(net "GND")
	)
	(via
		(at 62.406784 -128.467612)
		(size 0.508)
		(drill 0.254)
		(layers "F.Cu" "B.Cu")
		(net "GND")
	)
	(via
		(at 62.409578 -435.706774)
		(size 0.508)
		(drill 0.254)
		(layers "F.Cu" "B.Cu")
		(net "GND")
	)
	(via
		(at 41.236392 -487.227118)
		(size 0.508)
		(drill 0.254)
		(layers "F.Cu" "B.Cu")
		(net "GND")
	)
	(via
		(at 102.238048 -232.945432)
		(size 0.508)
		(drill 0.254)
		(layers "F.Cu" "B.Cu")
		(net "GND")
	)
	(via
		(at 40.201342 -216.44991)
		(size 0.508)
		(drill 0.254)
		(layers "F.Cu" "B.Cu")
		(net "GND")
	)
	(via
		(at 61.178948 -71.747634)
		(size 0.508)
		(drill 0.254)
		(layers "F.Cu" "B.Cu")
		(net "GND")
	)
	(via
		(at 0.762254 -63.508636)
		(size 0.508)
		(drill 0.254)
		(layers "F.Cu" "B.Cu")
		(net "GND")
	)
	(via
		(at 89.253314 -340.411054)
		(size 0.508)
		(drill 0.254)
		(layers "F.Cu" "B.Cu")
		(net "GND")
	)
	(via
		(at 40.959278 -106.900726)
		(size 0.508)
		(drill 0.254)
		(layers "F.Cu" "B.Cu")
		(net "GND")
	)
	(via
		(at 92.244926 -343.079324)
		(size 0.508)
		(drill 0.254)
		(layers "F.Cu" "B.Cu")
		(net "GND")
	)
	(via
		(at 45.13199 -388.222998)
		(size 0.508)
		(drill 0.254)
		(layers "F.Cu" "B.Cu")
		(net "GND")
	)
	(via
		(at 102.238048 -17.045432)
		(size 0.508)
		(drill 0.254)
		(layers "F.Cu" "B.Cu")
		(net "GND")
	)
	(via
		(at 58.621168 -158.361126)
		(size 0.508)
		(drill 0.254)
		(layers "F.Cu" "B.Cu")
		(net "GND")
	)
	(via
		(at 45.220382 -71.854568)
		(size 0.508)
		(drill 0.254)
		(layers "F.Cu" "B.Cu")
		(net "GND")
	)
	(via
		(at 94.885256 -343.547192)
		(size 0.508)
		(drill 0.254)
		(layers "F.Cu" "B.Cu")
		(net "GND")
	)
	(via
		(at 19.105626 -4.763008)
		(size 0.508)
		(drill 0.254)
		(layers "F.Cu" "B.Cu")
		(net "GND")
	)
	(via
		(at 68.59778 -206.296768)
		(size 0.508)
		(drill 0.254)
		(layers "F.Cu" "B.Cu")
		(net "GND")
	)
	(via
		(at 102.238048 -334.545432)
		(size 0.508)
		(drill 0.254)
		(layers "F.Cu" "B.Cu")
		(net "GND")
	)
	(via
		(at 57.033922 -67.815968)
		(size 0.508)
		(drill 0.254)
		(layers "F.Cu" "B.Cu")
		(net "GND")
	)
	(via
		(at 20.415504 -456.225402)
		(size 0.508)
		(drill 0.254)
		(layers "F.Cu" "B.Cu")
		(net "GND")
	)
	(via
		(at 66.037714 -529.236178)
		(size 0.508)
		(drill 0.254)
		(layers "F.Cu" "B.Cu")
		(net "GND")
	)
	(via
		(at 41.030398 -384.536696)
		(size 0.508)
		(drill 0.254)
		(layers "F.Cu" "B.Cu")
		(net "GND")
	)
	(via
		(at 70.260718 -65.1256)
		(size 0.508)
		(drill 0.254)
		(layers "F.Cu" "B.Cu")
		(net "GND")
	)
	(via
		(at 89.916 -165.65118)
		(size 0.508)
		(drill 0.254)
		(layers "F.Cu" "B.Cu")
		(net "GND")
	)
	(via
		(at 59.274964 -69.70649)
		(size 0.508)
		(drill 0.254)
		(layers "F.Cu" "B.Cu")
		(net "GND")
	)
	(via
		(at 70.555104 -126.324614)
		(size 0.508)
		(drill 0.254)
		(layers "F.Cu" "B.Cu")
		(net "GND")
	)
	(via
		(at 81.78927 -20.009612)
		(size 0.508)
		(drill 0.254)
		(layers "F.Cu" "B.Cu")
		(net "GND")
	)
	(via
		(at 41.103804 -192.216278)
		(size 0.508)
		(drill 0.254)
		(layers "F.Cu" "B.Cu")
		(net "GND")
	)
	(via
		(at 20.202144 -174.17034)
		(size 0.508)
		(drill 0.254)
		(layers "F.Cu" "B.Cu")
		(net "GND")
	)
	(via
		(at 56.421274 -427.85411)
		(size 0.508)
		(drill 0.254)
		(layers "F.Cu" "B.Cu")
		(net "GND")
	)
	(via
		(at 82.752184 -295.215564)
		(size 0.508)
		(drill 0.254)
		(layers "F.Cu" "B.Cu")
		(net "GND")
	)
	(via
		(at 61.20257 -18.053812)
		(size 0.508)
		(drill 0.254)
		(layers "F.Cu" "B.Cu")
		(net "GND")
	)
	(via
		(at 69.774816 -437.691784)
		(size 0.508)
		(drill 0.254)
		(layers "F.Cu" "B.Cu")
		(net "GND")
	)
	(via
		(at 102.238048 -4.345432)
		(size 0.508)
		(drill 0.254)
		(layers "F.Cu" "B.Cu")
		(net "GND")
	)
	(via
		(at 73.199752 -287.311084)
		(size 0.508)
		(drill 0.254)
		(layers "F.Cu" "B.Cu")
		(net "GND")
	)
	(via
		(at 63.06312 -25.906476)
		(size 0.508)
		(drill 0.254)
		(layers "F.Cu" "B.Cu")
		(net "GND")
	)
	(via
		(at 69.726556 -170.736768)
		(size 0.508)
		(drill 0.254)
		(layers "F.Cu" "B.Cu")
		(net "GND")
	)
	(via
		(at 60.619386 -306.775358)
		(size 0.508)
		(drill 0.254)
		(layers "F.Cu" "B.Cu")
		(net "GND")
	)
	(via
		(at 40.201342 -214.559388)
		(size 0.508)
		(drill 0.254)
		(layers "F.Cu" "B.Cu")
		(net "GND")
	)
	(via
		(at 41.792906 -283.49829)
		(size 0.508)
		(drill 0.254)
		(layers "F.Cu" "B.Cu")
		(net "GND")
	)
	(via
		(at 38.58768 -483.276148)
		(size 0.508)
		(drill 0.254)
		(layers "F.Cu" "B.Cu")
		(net "GND")
	)
	(via
		(at 102.238048 -474.245432)
		(size 0.508)
		(drill 0.254)
		(layers "F.Cu" "B.Cu")
		(net "GND")
	)
	(via
		(at 72.802242 -464.6676)
		(size 0.508)
		(drill 0.254)
		(layers "F.Cu" "B.Cu")
		(net "GND")
	)
	(via
		(at 27.937714 -529.236178)
		(size 0.508)
		(drill 0.254)
		(layers "F.Cu" "B.Cu")
		(net "GND")
	)
	(via
		(at 57.795922 -71.747634)
		(size 0.508)
		(drill 0.254)
		(layers "F.Cu" "B.Cu")
		(net "GND")
	)
	(via
		(at 46.23308 -218.491054)
		(size 0.508)
		(drill 0.254)
		(layers "F.Cu" "B.Cu")
		(net "GND")
	)
	(via
		(at 39.100252 -388.222998)
		(size 0.508)
		(drill 0.254)
		(layers "F.Cu" "B.Cu")
		(net "GND")
	)
	(via
		(at 58.760106 -241.923316)
		(size 0.508)
		(drill 0.254)
		(layers "F.Cu" "B.Cu")
		(net "GND")
	)
	(via
		(at 102.238048 -144.045432)
		(size 0.508)
		(drill 0.254)
		(layers "F.Cu" "B.Cu")
		(net "GND")
	)
	(via
		(at 62.406784 -130.377438)
		(size 0.508)
		(drill 0.254)
		(layers "F.Cu" "B.Cu")
		(net "GND")
	)
	(via
		(at 61.2648 -124.535946)
		(size 0.508)
		(drill 0.254)
		(layers "F.Cu" "B.Cu")
		(net "GND")
	)
	(via
		(at 58.261758 -128.467612)
		(size 0.508)
		(drill 0.254)
		(layers "F.Cu" "B.Cu")
		(net "GND")
	)
	(via
		(at 24.773636 -186.752992)
		(size 0.508)
		(drill 0.254)
		(layers "F.Cu" "B.Cu")
		(net "GND")
	)
	(via
		(at 21.685504 -456.243944)
		(size 0.508)
		(drill 0.254)
		(layers "F.Cu" "B.Cu")
		(net "GND")
	)
	(via
		(at 42.088054 -216.44991)
		(size 0.508)
		(drill 0.254)
		(layers "F.Cu" "B.Cu")
		(net "GND")
	)
	(via
		(at 70.236842 -37.48659)
		(size 0.508)
		(drill 0.254)
		(layers "F.Cu" "B.Cu")
		(net "GND")
	)
	(via
		(at 45.687234 -300.66996)
		(size 0.508)
		(drill 0.254)
		(layers "F.Cu" "B.Cu")
		(net "GND")
	)
	(via
		(at 14.594332 -318.358012)
		(size 0.508)
		(drill 0.254)
		(layers "F.Cu" "B.Cu")
		(net "GND")
	)
	(via
		(at 67.101974 -215.227916)
		(size 0.508)
		(drill 0.254)
		(layers "F.Cu" "B.Cu")
		(net "GND")
	)
	(via
		(at 62.409578 -429.865282)
		(size 0.508)
		(drill 0.254)
		(layers "F.Cu" "B.Cu")
		(net "GND")
	)
	(via
		(at 24.754078 -94.464886)
		(size 0.508)
		(drill 0.254)
		(layers "F.Cu" "B.Cu")
		(net "GND")
	)
	(via
		(at 44.939712 -30.131004)
		(size 0.508)
		(drill 0.254)
		(layers "F.Cu" "B.Cu")
		(net "GND")
	)
	(via
		(at 64.652906 -160.40227)
		(size 0.508)
		(drill 0.254)
		(layers "F.Cu" "B.Cu")
		(net "GND")
	)
	(via
		(at 74.798682 -21.013928)
		(size 0.508)
		(drill 0.254)
		(layers "F.Cu" "B.Cu")
		(net "GND")
	)
	(via
		(at 102.238048 -67.845432)
		(size 0.508)
		(drill 0.254)
		(layers "F.Cu" "B.Cu")
		(net "GND")
	)
	(via
		(at 40.474392 -485.317292)
		(size 0.508)
		(drill 0.254)
		(layers "F.Cu" "B.Cu")
		(net "GND")
	)
	(via
		(at 57.970674 -306.775358)
		(size 0.508)
		(drill 0.254)
		(layers "F.Cu" "B.Cu")
		(net "GND")
	)
	(via
		(at 40.989758 -103.52405)
		(size 0.508)
		(drill 0.254)
		(layers "F.Cu" "B.Cu")
		(net "GND")
	)
	(via
		(at 92.244926 -349.55734)
		(size 0.508)
		(drill 0.254)
		(layers "F.Cu" "B.Cu")
		(net "GND")
	)
	(via
		(at 45.220382 -70.179438)
		(size 0.508)
		(drill 0.254)
		(layers "F.Cu" "B.Cu")
		(net "GND")
	)
	(via
		(at 44.8818 -304.356262)
		(size 0.508)
		(drill 0.254)
		(layers "F.Cu" "B.Cu")
		(net "GND")
	)
	(via
		(at 67.187064 -126.324614)
		(size 0.508)
		(drill 0.254)
		(layers "F.Cu" "B.Cu")
		(net "GND")
	)
	(via
		(at 63.606426 -253.275846)
		(size 0.508)
		(drill 0.254)
		(layers "F.Cu" "B.Cu")
		(net "GND")
	)
	(via
		(at 60.603384 -253.275846)
		(size 0.508)
		(drill 0.254)
		(layers "F.Cu" "B.Cu")
		(net "GND")
	)
	(via
		(at 58.264552 -431.755804)
		(size 0.508)
		(drill 0.254)
		(layers "F.Cu" "B.Cu")
		(net "GND")
	)
	(via
		(at 73.45934 -331.631036)
		(size 0.508)
		(drill 0.254)
		(layers "F.Cu" "B.Cu")
		(net "GND")
	)
	(via
		(at 59.743594 -429.865282)
		(size 0.508)
		(drill 0.254)
		(layers "F.Cu" "B.Cu")
		(net "GND")
	)
	(via
		(at 0.762254 -317.508636)
		(size 0.508)
		(drill 0.254)
		(layers "F.Cu" "B.Cu")
		(net "GND")
	)
	(via
		(at 58.261758 -130.377438)
		(size 0.508)
		(drill 0.254)
		(layers "F.Cu" "B.Cu")
		(net "GND")
	)
	(via
		(at 41.030398 -382.63576)
		(size 0.508)
		(drill 0.254)
		(layers "F.Cu" "B.Cu")
		(net "GND")
	)
	(via
		(at 57.839356 -64.129666)
		(size 0.508)
		(drill 0.254)
		(layers "F.Cu" "B.Cu")
		(net "GND")
	)
	(via
		(at 0.762254 -38.108636)
		(size 0.508)
		(drill 0.254)
		(layers "F.Cu" "B.Cu")
		(net "GND")
	)
	(via
		(at 24.636984 -365.50092)
		(size 0.508)
		(drill 0.254)
		(layers "F.Cu" "B.Cu")
		(net "GND")
	)
	(via
		(at 57.033922 -69.70649)
		(size 0.508)
		(drill 0.254)
		(layers "F.Cu" "B.Cu")
		(net "GND")
	)
	(via
		(at 70.877176 -158.655258)
		(size 0.508)
		(drill 0.254)
		(layers "F.Cu" "B.Cu")
		(net "GND")
	)
	(via
		(at 45.424852 -475.798388)
		(size 0.508)
		(drill 0.254)
		(layers "F.Cu" "B.Cu")
		(net "GND")
	)
	(via
		(at 92.244926 -345.450922)
		(size 0.508)
		(drill 0.254)
		(layers "F.Cu" "B.Cu")
		(net "GND")
	)
	(via
		(at 63.106554 -14.477746)
		(size 0.508)
		(drill 0.254)
		(layers "F.Cu" "B.Cu")
		(net "GND")
	)
	(via
		(at 44.134278 -39.649908)
		(size 0.508)
		(drill 0.254)
		(layers "F.Cu" "B.Cu")
		(net "GND")
	)
	(via
		(at 58.264552 -435.706774)
		(size 0.508)
		(drill 0.254)
		(layers "F.Cu" "B.Cu")
		(net "GND")
	)
	(via
		(at 41.279826 -475.798388)
		(size 0.508)
		(drill 0.254)
		(layers "F.Cu" "B.Cu")
		(net "GND")
	)
	(via
		(at 64.74841 -255.185672)
		(size 0.508)
		(drill 0.254)
		(layers "F.Cu" "B.Cu")
		(net "GND")
	)
	(via
		(at 61.691012 -426.17898)
		(size 0.508)
		(drill 0.254)
		(layers "F.Cu" "B.Cu")
		(net "GND")
	)
	(via
		(at 62.450218 -118.948708)
		(size 0.508)
		(drill 0.254)
		(layers "F.Cu" "B.Cu")
		(net "GND")
	)
	(via
		(at 39.34968 -483.276148)
		(size 0.508)
		(drill 0.254)
		(layers "F.Cu" "B.Cu")
		(net "GND")
	)
	(via
		(at 44.177712 -32.03194)
		(size 0.508)
		(drill 0.254)
		(layers "F.Cu" "B.Cu")
		(net "GND")
	)
	(via
		(at 45.687234 -302.34509)
		(size 0.508)
		(drill 0.254)
		(layers "F.Cu" "B.Cu")
		(net "GND")
	)
	(via
		(at 59.318398 -65.804796)
		(size 0.508)
		(drill 0.254)
		(layers "F.Cu" "B.Cu")
		(net "GND")
	)
	(via
		(at 58.621168 -160.40227)
		(size 0.508)
		(drill 0.254)
		(layers "F.Cu" "B.Cu")
		(net "GND")
	)
	(via
		(at 39.393114 -479.374454)
		(size 0.508)
		(drill 0.254)
		(layers "F.Cu" "B.Cu")
		(net "GND")
	)
	(via
		(at 45.175424 -382.63576)
		(size 0.508)
		(drill 0.254)
		(layers "F.Cu" "B.Cu")
		(net "GND")
	)
	(via
		(at 41.792398 -386.211826)
		(size 0.508)
		(drill 0.254)
		(layers "F.Cu" "B.Cu")
		(net "GND")
	)
	(via
		(at 46.276514 -212.548216)
		(size 0.508)
		(drill 0.254)
		(layers "F.Cu" "B.Cu")
		(net "GND")
	)
	(via
		(at 59.789314 -154.459432)
		(size 0.508)
		(drill 0.254)
		(layers "F.Cu" "B.Cu")
		(net "GND")
	)
	(via
		(at 45.687234 -298.769024)
		(size 0.508)
		(drill 0.254)
		(layers "F.Cu" "B.Cu")
		(net "GND")
	)
	(via
		(at 41.542208 -298.769024)
		(size 0.508)
		(drill 0.254)
		(layers "F.Cu" "B.Cu")
		(net "GND")
	)
	(via
		(at 58.305192 -122.524774)
		(size 0.508)
		(drill 0.254)
		(layers "F.Cu" "B.Cu")
		(net "GND")
	)
	(via
		(at 63.06312 -20.064984)
		(size 0.508)
		(drill 0.254)
		(layers "F.Cu" "B.Cu")
		(net "GND")
	)
	(via
		(at 43.520868 -477.699324)
		(size 0.508)
		(drill 0.254)
		(layers "F.Cu" "B.Cu")
		(net "GND")
	)
	(via
		(at 17.875504 -456.281282)
		(size 0.508)
		(drill 0.254)
		(layers "F.Cu" "B.Cu")
		(net "GND")
	)
	(via
		(at 13.853922 -329.314302)
		(size 0.508)
		(drill 0.254)
		(layers "F.Cu" "B.Cu")
		(net "GND")
	)
	(via
		(at 43.520868 -475.798388)
		(size 0.508)
		(drill 0.254)
		(layers "F.Cu" "B.Cu")
		(net "GND")
	)
	(via
		(at 41.030398 -386.211826)
		(size 0.508)
		(drill 0.254)
		(layers "F.Cu" "B.Cu")
		(net "GND")
	)
	(via
		(at 55.659274 -427.85411)
		(size 0.508)
		(drill 0.254)
		(layers "F.Cu" "B.Cu")
		(net "GND")
	)
	(via
		(at 61.647578 -435.706774)
		(size 0.508)
		(drill 0.254)
		(layers "F.Cu" "B.Cu")
		(net "GND")
	)
	(via
		(at 61.20257 -16.378682)
		(size 0.508)
		(drill 0.254)
		(layers "F.Cu" "B.Cu")
		(net "GND")
	)
	(via
		(at 41.792398 -380.802134)
		(size 0.508)
		(drill 0.254)
		(layers "F.Cu" "B.Cu")
		(net "GND")
	)
	(via
		(at 102.238048 -359.945432)
		(size 0.508)
		(drill 0.254)
		(layers "F.Cu" "B.Cu")
		(net "GND")
	)
	(via
		(at 45.47108 -218.491054)
		(size 0.508)
		(drill 0.254)
		(layers "F.Cu" "B.Cu")
		(net "GND")
	)
	(via
		(at 40.451786 -128.627886)
		(size 0.508)
		(drill 0.254)
		(layers "F.Cu" "B.Cu")
		(net "GND")
	)
	(via
		(at 43.567096 -218.491054)
		(size 0.508)
		(drill 0.254)
		(layers "F.Cu" "B.Cu")
		(net "GND")
	)
	(via
		(at 42.131488 -210.873086)
		(size 0.508)
		(drill 0.254)
		(layers "F.Cu" "B.Cu")
		(net "GND")
	)
	(via
		(at 62.453012 -424.278044)
		(size 0.508)
		(drill 0.254)
		(layers "F.Cu" "B.Cu")
		(net "GND")
	)
	(via
		(at 41.792398 -384.536696)
		(size 0.508)
		(drill 0.254)
		(layers "F.Cu" "B.Cu")
		(net "GND")
	)
	(via
		(at 41.542208 -300.66996)
		(size 0.508)
		(drill 0.254)
		(layers "F.Cu" "B.Cu")
		(net "GND")
	)
	(via
		(at 64.002412 -304.734214)
		(size 0.508)
		(drill 0.254)
		(layers "F.Cu" "B.Cu")
		(net "GND")
	)
	(via
		(at 61.365384 -251.234702)
		(size 0.508)
		(drill 0.254)
		(layers "F.Cu" "B.Cu")
		(net "GND")
	)
	(via
		(at 39.655496 -302.34509)
		(size 0.508)
		(drill 0.254)
		(layers "F.Cu" "B.Cu")
		(net "GND")
	)
	(via
		(at 43.61053 -212.548216)
		(size 0.508)
		(drill 0.254)
		(layers "F.Cu" "B.Cu")
		(net "GND")
	)
	(via
		(at 73.687178 -258.105148)
		(size 0.508)
		(drill 0.254)
		(layers "F.Cu" "B.Cu")
		(net "GND")
	)
	(via
		(at 65.51041 -255.185672)
		(size 0.508)
		(drill 0.254)
		(layers "F.Cu" "B.Cu")
		(net "GND")
	)
	(via
		(at 25.90546 -108.230416)
		(size 0.508)
		(drill 0.254)
		(layers "F.Cu" "B.Cu")
		(net "GND")
	)
	(via
		(at 40.637714 -529.236178)
		(size 0.508)
		(drill 0.254)
		(layers "F.Cu" "B.Cu")
		(net "GND")
	)
	(via
		(at 55.61584 -431.755804)
		(size 0.508)
		(drill 0.254)
		(layers "F.Cu" "B.Cu")
		(net "GND")
	)
	(via
		(at 44.896278 -37.608764)
		(size 0.508)
		(drill 0.254)
		(layers "F.Cu" "B.Cu")
		(net "GND")
	)
	(via
		(at 19.145504 -456.243944)
		(size 0.508)
		(drill 0.254)
		(layers "F.Cu" "B.Cu")
		(net "GND")
	)
	(via
		(at 43.053 -30.131004)
		(size 0.508)
		(drill 0.254)
		(layers "F.Cu" "B.Cu")
		(net "GND")
	)
	(via
		(at 44.925234 -302.34509)
		(size 0.508)
		(drill 0.254)
		(layers "F.Cu" "B.Cu")
		(net "GND")
	)
	(via
		(at 70.85457 -170.736768)
		(size 0.508)
		(drill 0.254)
		(layers "F.Cu" "B.Cu")
		(net "GND")
	)
	(via
		(at 72.478392 -155.07716)
		(size 0.508)
		(drill 0.254)
		(layers "F.Cu" "B.Cu")
		(net "GND")
	)
	(via
		(at 43.02125 -298.769024)
		(size 0.508)
		(drill 0.254)
		(layers "F.Cu" "B.Cu")
		(net "GND")
	)
	(via
		(at 102.238048 -486.945432)
		(size 0.508)
		(drill 0.254)
		(layers "F.Cu" "B.Cu")
		(net "GND")
	)
	(via
		(at 43.053 -28.297378)
		(size 0.508)
		(drill 0.254)
		(layers "F.Cu" "B.Cu")
		(net "GND")
	)
	(via
		(at 60.603384 -255.185672)
		(size 0.508)
		(drill 0.254)
		(layers "F.Cu" "B.Cu")
		(net "GND")
	)
	(via
		(at 43.990006 -390.11352)
		(size 0.508)
		(drill 0.254)
		(layers "F.Cu" "B.Cu")
		(net "GND")
	)
	(via
		(at 62.860428 -306.775358)
		(size 0.508)
		(drill 0.254)
		(layers "F.Cu" "B.Cu")
		(net "GND")
	)
	(via
		(at 60.505594 -435.706774)
		(size 0.508)
		(drill 0.254)
		(layers "F.Cu" "B.Cu")
		(net "GND")
	)
	(via
		(at 0.762254 -241.308636)
		(size 0.508)
		(drill 0.254)
		(layers "F.Cu" "B.Cu")
		(net "GND")
	)
	(via
		(at 60.5028 -128.467612)
		(size 0.508)
		(drill 0.254)
		(layers "F.Cu" "B.Cu")
		(net "GND")
	)
	(via
		(at 0.762254 -355.608636)
		(size 0.508)
		(drill 0.254)
		(layers "F.Cu" "B.Cu")
		(net "GND")
	)
	(via
		(at 42.088054 -220.40088)
		(size 0.508)
		(drill 0.254)
		(layers "F.Cu" "B.Cu")
		(net "GND")
	)
	(via
		(at 0.762254 -469.908636)
		(size 0.508)
		(drill 0.254)
		(layers "F.Cu" "B.Cu")
		(net "GND")
	)
	(via
		(at 44.37253 -210.873086)
		(size 0.508)
		(drill 0.254)
		(layers "F.Cu" "B.Cu")
		(net "GND")
	)
	(via
		(at 102.238048 -105.945432)
		(size 0.508)
		(drill 0.254)
		(layers "F.Cu" "B.Cu")
		(net "GND")
	)
	(via
		(at 59.522106 -243.756942)
		(size 0.508)
		(drill 0.254)
		(layers "F.Cu" "B.Cu")
		(net "GND")
	)
	(via
		(at 38.893496 -296.935398)
		(size 0.508)
		(drill 0.254)
		(layers "F.Cu" "B.Cu")
		(net "GND")
	)
	(via
		(at 44.458382 -70.179438)
		(size 0.508)
		(drill 0.254)
		(layers "F.Cu" "B.Cu")
		(net "GND")
	)
	(via
		(at 59.478672 -249.34418)
		(size 0.508)
		(drill 0.254)
		(layers "F.Cu" "B.Cu")
		(net "GND")
	)
	(via
		(at 57.795922 -69.70649)
		(size 0.508)
		(drill 0.254)
		(layers "F.Cu" "B.Cu")
		(net "GND")
	)
	(via
		(at 59.067192 -118.948708)
		(size 0.508)
		(drill 0.254)
		(layers "F.Cu" "B.Cu")
		(net "GND")
	)
	(via
		(at 43.228006 -388.222998)
		(size 0.508)
		(drill 0.254)
		(layers "F.Cu" "B.Cu")
		(net "GND")
	)
	(via
		(at 39.143686 -382.63576)
		(size 0.508)
		(drill 0.254)
		(layers "F.Cu" "B.Cu")
		(net "GND")
	)
	(via
		(at 68.639436 -376.62104)
		(size 0.508)
		(drill 0.254)
		(layers "F.Cu" "B.Cu")
		(net "GND")
	)
	(via
		(at 59.857386 -306.775358)
		(size 0.508)
		(drill 0.254)
		(layers "F.Cu" "B.Cu")
		(net "GND")
	)
	(via
		(at 44.939712 -28.297378)
		(size 0.508)
		(drill 0.254)
		(layers "F.Cu" "B.Cu")
		(net "GND")
	)
	(via
		(at 20.19808 -173.339506)
		(size 0.508)
		(drill 0.254)
		(layers "F.Cu" "B.Cu")
		(net "GND")
	)
	(via
		(at 42.247566 -41.559734)
		(size 0.508)
		(drill 0.254)
		(layers "F.Cu" "B.Cu")
		(net "GND")
	)
	(via
		(at 44.134278 -35.718242)
		(size 0.508)
		(drill 0.254)
		(layers "F.Cu" "B.Cu")
		(net "GND")
	)
	(via
		(at 46.23308 -216.44991)
		(size 0.508)
		(drill 0.254)
		(layers "F.Cu" "B.Cu")
		(net "GND")
	)
	(via
		(at 45.176948 -73.86574)
		(size 0.508)
		(drill 0.254)
		(layers "F.Cu" "B.Cu")
		(net "GND")
	)
	(via
		(at 44.458382 -68.278502)
		(size 0.508)
		(drill 0.254)
		(layers "F.Cu" "B.Cu")
		(net "GND")
	)
	(via
		(at 41.748964 -388.222998)
		(size 0.508)
		(drill 0.254)
		(layers "F.Cu" "B.Cu")
		(net "GND")
	)
	(via
		(at 38.631114 -473.964762)
		(size 0.508)
		(drill 0.254)
		(layers "F.Cu" "B.Cu")
		(net "GND")
	)
	(via
		(at 67.867276 -302.711358)
		(size 0.508)
		(drill 0.254)
		(layers "F.Cu" "B.Cu")
		(net "GND")
	)
	(via
		(at 61.159136 -21.955506)
		(size 0.508)
		(drill 0.254)
		(layers "F.Cu" "B.Cu")
		(net "GND")
	)
	(via
		(at 42.758868 -477.699324)
		(size 0.508)
		(drill 0.254)
		(layers "F.Cu" "B.Cu")
		(net "GND")
	)
	(via
		(at 64.74841 -251.234702)
		(size 0.508)
		(drill 0.254)
		(layers "F.Cu" "B.Cu")
		(net "GND")
	)
	(via
		(at 41.245536 -14.412976)
		(size 0.508)
		(drill 0.254)
		(layers "F.Cu" "B.Cu")
		(net "GND")
	)
	(via
		(at 102.238048 -347.245432)
		(size 0.508)
		(drill 0.254)
		(layers "F.Cu" "B.Cu")
		(net "GND")
	)
	(via
		(at 60.619386 -304.734214)
		(size 0.508)
		(drill 0.254)
		(layers "F.Cu" "B.Cu")
		(net "GND")
	)
	(via
		(at 62.450218 -122.524774)
		(size 0.508)
		(drill 0.254)
		(layers "F.Cu" "B.Cu")
		(net "GND")
	)
	(via
		(at 25.113742 -452.257668)
		(size 0.508)
		(drill 0.254)
		(layers "F.Cu" "B.Cu")
		(net "GND")
	)
	(via
		(at 74.804524 -81.962752)
		(size 0.508)
		(drill 0.254)
		(layers "F.Cu" "B.Cu")
		(net "GND")
	)
	(via
		(at 39.905686 -380.802134)
		(size 0.508)
		(drill 0.254)
		(layers "F.Cu" "B.Cu")
		(net "GND")
	)
	(via
		(at 41.427146 -370.099336)
		(size 0.508)
		(drill 0.254)
		(layers "F.Cu" "B.Cu")
		(net "GND")
	)
	(via
		(at 67.92468 -37.47516)
		(size 0.508)
		(drill 0.254)
		(layers "F.Cu" "B.Cu")
		(net "GND")
	)
	(via
		(at 0.762254 -381.008636)
		(size 0.508)
		(drill 0.254)
		(layers "F.Cu" "B.Cu")
		(net "GND")
	)
	(via
		(at 55.659274 -426.17898)
		(size 0.508)
		(drill 0.254)
		(layers "F.Cu" "B.Cu")
		(net "GND")
	)
	(via
		(at 26.78557 -374.115076)
		(size 0.508)
		(drill 0.254)
		(layers "F.Cu" "B.Cu")
		(net "GND")
	)
	(via
		(at 102.238048 -42.445432)
		(size 0.508)
		(drill 0.254)
		(layers "F.Cu" "B.Cu")
		(net "GND")
	)
	(via
		(at 62.30112 -25.906476)
		(size 0.508)
		(drill 0.254)
		(layers "F.Cu" "B.Cu")
		(net "GND")
	)
	(via
		(at 78.737714 -529.236178)
		(size 0.508)
		(drill 0.254)
		(layers "F.Cu" "B.Cu")
		(net "GND")
	)
	(via
		(at 42.977816 -304.356262)
		(size 0.508)
		(drill 0.254)
		(layers "F.Cu" "B.Cu")
		(net "GND")
	)
	(via
		(at 40.244776 -208.97215)
		(size 0.508)
		(drill 0.254)
		(layers "F.Cu" "B.Cu")
		(net "GND")
	)
	(via
		(at 45.381418 -483.276148)
		(size 0.508)
		(drill 0.254)
		(layers "F.Cu" "B.Cu")
		(net "GND")
	)
	(via
		(at 60.546234 -120.849644)
		(size 0.508)
		(drill 0.254)
		(layers "F.Cu" "B.Cu")
		(net "GND")
	)
	(via
		(at 61.365384 -253.275846)
		(size 0.508)
		(drill 0.254)
		(layers "F.Cu" "B.Cu")
		(net "GND")
	)
	(via
		(at 0.762254 -25.408636)
		(size 0.508)
		(drill 0.254)
		(layers "F.Cu" "B.Cu")
		(net "GND")
	)
	(via
		(at 69.41947 -215.198198)
		(size 0.508)
		(drill 0.254)
		(layers "F.Cu" "B.Cu")
		(net "GND")
	)
	(via
		(at 58.732674 -306.775358)
		(size 0.508)
		(drill 0.254)
		(layers "F.Cu" "B.Cu")
		(net "GND")
	)
	(via
		(at 60.397136 -23.99665)
		(size 0.508)
		(drill 0.254)
		(layers "F.Cu" "B.Cu")
		(net "GND")
	)
	(via
		(at 43.739816 -304.356262)
		(size 0.508)
		(drill 0.254)
		(layers "F.Cu" "B.Cu")
		(net "GND")
	)
	(via
		(at 56.37784 -435.706774)
		(size 0.508)
		(drill 0.254)
		(layers "F.Cu" "B.Cu")
		(net "GND")
	)
	(via
		(at 55.61584 -435.706774)
		(size 0.508)
		(drill 0.254)
		(layers "F.Cu" "B.Cu")
		(net "GND")
	)
	(via
		(at 58.664602 -150.883366)
		(size 0.508)
		(drill 0.254)
		(layers "F.Cu" "B.Cu")
		(net "GND")
	)
	(via
		(at 40.517826 -475.798388)
		(size 0.508)
		(drill 0.254)
		(layers "F.Cu" "B.Cu")
		(net "GND")
	)
	(via
		(at 102.238048 -321.845432)
		(size 0.508)
		(drill 0.254)
		(layers "F.Cu" "B.Cu")
		(net "GND")
	)
	(via
		(at 60.44057 -18.053812)
		(size 0.508)
		(drill 0.254)
		(layers "F.Cu" "B.Cu")
		(net "GND")
	)
	(via
		(at 62.748922 -158.361126)
		(size 0.508)
		(drill 0.254)
		(layers "F.Cu" "B.Cu")
		(net "GND")
	)
	(via
		(at 24.740362 -361.78236)
		(size 0.508)
		(drill 0.254)
		(layers "F.Cu" "B.Cu")
		(net "GND")
	)
	(via
		(at 61.159136 -25.906476)
		(size 0.508)
		(drill 0.254)
		(layers "F.Cu" "B.Cu")
		(net "GND")
	)
	(via
		(at 59.74588 -158.361126)
		(size 0.508)
		(drill 0.254)
		(layers "F.Cu" "B.Cu")
		(net "GND")
	)
	(via
		(at 41.326054 -220.40088)
		(size 0.508)
		(drill 0.254)
		(layers "F.Cu" "B.Cu")
		(net "GND")
	)
	(via
		(at 14.108176 -449.79209)
		(size 0.508)
		(drill 0.254)
		(layers "F.Cu" "B.Cu")
		(net "GND")
	)
	(via
		(at 40.780208 -300.66996)
		(size 0.508)
		(drill 0.254)
		(layers "F.Cu" "B.Cu")
		(net "GND")
	)
	(via
		(at 0.762254 -444.508636)
		(size 0.508)
		(drill 0.254)
		(layers "F.Cu" "B.Cu")
		(net "GND")
	)
	(via
		(at 66.823844 -37.50945)
		(size 0.508)
		(drill 0.254)
		(layers "F.Cu" "B.Cu")
		(net "GND")
	)
	(via
		(at 44.662852 -479.374454)
		(size 0.508)
		(drill 0.254)
		(layers "F.Cu" "B.Cu")
		(net "GND")
	)
	(via
		(at 45.89399 -390.11352)
		(size 0.508)
		(drill 0.254)
		(layers "F.Cu" "B.Cu")
		(net "GND")
	)
	(via
		(at 62.844426 -251.234702)
		(size 0.508)
		(drill 0.254)
		(layers "F.Cu" "B.Cu")
		(net "GND")
	)
	(via
		(at 62.30112 -21.955506)
		(size 0.508)
		(drill 0.254)
		(layers "F.Cu" "B.Cu")
		(net "GND")
	)
	(via
		(at 46.276514 -210.873086)
		(size 0.508)
		(drill 0.254)
		(layers "F.Cu" "B.Cu")
		(net "GND")
	)
	(via
		(at 38.893496 -300.66996)
		(size 0.508)
		(drill 0.254)
		(layers "F.Cu" "B.Cu")
		(net "GND")
	)
	(via
		(at 13.74902 -333.695802)
		(size 0.508)
		(drill 0.254)
		(layers "F.Cu" "B.Cu")
		(net "GND")
	)
	(via
		(at 60.551314 -150.883366)
		(size 0.508)
		(drill 0.254)
		(layers "F.Cu" "B.Cu")
		(net "GND")
	)
	(via
		(at 39.393114 -477.699324)
		(size 0.508)
		(drill 0.254)
		(layers "F.Cu" "B.Cu")
		(net "GND")
	)
	(via
		(at 0.762254 -304.808636)
		(size 0.508)
		(drill 0.254)
		(layers "F.Cu" "B.Cu")
		(net "GND")
	)
	(via
		(at 0.762254 -508.008636)
		(size 0.508)
		(drill 0.254)
		(layers "F.Cu" "B.Cu")
		(net "GND")
	)
	(via
		(at 43.567096 -220.40088)
		(size 0.508)
		(drill 0.254)
		(layers "F.Cu" "B.Cu")
		(net "GND")
	)
	(via
		(at 39.689786 -126.586742)
		(size 0.508)
		(drill 0.254)
		(layers "F.Cu" "B.Cu")
		(net "GND")
	)
	(via
		(at 44.329096 -216.44991)
		(size 0.508)
		(drill 0.254)
		(layers "F.Cu" "B.Cu")
		(net "GND")
	)
	(via
		(at 73.909936 -154.23261)
		(size 0.508)
		(drill 0.254)
		(layers "F.Cu" "B.Cu")
		(net "GND")
	)
	(via
		(at 57.970674 -304.734214)
		(size 0.508)
		(drill 0.254)
		(layers "F.Cu" "B.Cu")
		(net "GND")
	)
	(via
		(at 57.077356 -62.22873)
		(size 0.508)
		(drill 0.254)
		(layers "F.Cu" "B.Cu")
		(net "GND")
	)
	(via
		(at 43.009566 -37.608764)
		(size 0.508)
		(drill 0.254)
		(layers "F.Cu" "B.Cu")
		(net "GND")
	)
	(via
		(at 45.176948 -79.707232)
		(size 0.508)
		(drill 0.254)
		(layers "F.Cu" "B.Cu")
		(net "GND")
	)
	(via
		(at 13.99032 -447.797428)
		(size 0.508)
		(drill 0.254)
		(layers "F.Cu" "B.Cu")
		(net "GND")
	)
	(via
		(at 59.067192 -120.849644)
		(size 0.508)
		(drill 0.254)
		(layers "F.Cu" "B.Cu")
		(net "GND")
	)
	(via
		(at 90.015314 -343.079324)
		(size 0.508)
		(drill 0.254)
		(layers "F.Cu" "B.Cu")
		(net "GND")
	)
	(via
		(at 59.067192 -117.115082)
		(size 0.508)
		(drill 0.254)
		(layers "F.Cu" "B.Cu")
		(net "GND")
	)
	(via
		(at 0.762254 -127.008636)
		(size 0.508)
		(drill 0.254)
		(layers "F.Cu" "B.Cu")
		(net "GND")
	)
	(via
		(at 39.143686 -384.536696)
		(size 0.508)
		(drill 0.254)
		(layers "F.Cu" "B.Cu")
		(net "GND")
	)
	(via
		(at 71.044562 -437.743092)
		(size 0.508)
		(drill 0.254)
		(layers "F.Cu" "B.Cu")
		(net "GND")
	)
	(via
		(at 62.844426 -249.34418)
		(size 0.508)
		(drill 0.254)
		(layers "F.Cu" "B.Cu")
		(net "GND")
	)
	(via
		(at 60.44057 -16.378682)
		(size 0.508)
		(drill 0.254)
		(layers "F.Cu" "B.Cu")
		(net "GND")
	)
	(via
		(at 41.030398 -380.802134)
		(size 0.508)
		(drill 0.254)
		(layers "F.Cu" "B.Cu")
		(net "GND")
	)
	(via
		(at 63.106554 -18.053812)
		(size 0.508)
		(drill 0.254)
		(layers "F.Cu" "B.Cu")
		(net "GND")
	)
	(via
		(at 102.238048 -194.845432)
		(size 0.508)
		(drill 0.254)
		(layers "F.Cu" "B.Cu")
		(net "GND")
	)
	(via
		(at 60.036964 -67.815968)
		(size 0.508)
		(drill 0.254)
		(layers "F.Cu" "B.Cu")
		(net "GND")
	)
	(via
		(at 102.238048 -423.445432)
		(size 0.508)
		(drill 0.254)
		(layers "F.Cu" "B.Cu")
		(net "GND")
	)
	(via
		(at 102.238048 -55.145432)
		(size 0.508)
		(drill 0.254)
		(layers "F.Cu" "B.Cu")
		(net "GND")
	)
	(via
		(at 64.764412 -308.685184)
		(size 0.508)
		(drill 0.254)
		(layers "F.Cu" "B.Cu")
		(net "GND")
	)
	(via
		(at 58.716672 -253.275846)
		(size 0.508)
		(drill 0.254)
		(layers "F.Cu" "B.Cu")
		(net "GND")
	)
	(via
		(at 60.549028 -427.85411)
		(size 0.508)
		(drill 0.254)
		(layers "F.Cu" "B.Cu")
		(net "GND")
	)
	(via
		(at 0.762254 -431.808636)
		(size 0.508)
		(drill 0.254)
		(layers "F.Cu" "B.Cu")
		(net "GND")
	)
	(via
		(at 93.006926 -337.740244)
		(size 0.508)
		(drill 0.254)
		(layers "F.Cu" "B.Cu")
		(net "GND")
	)
	(via
		(at 57.859168 -162.312096)
		(size 0.508)
		(drill 0.254)
		(layers "F.Cu" "B.Cu")
		(net "GND")
	)
	(via
		(at 21.891498 -172.90034)
		(size 0.508)
		(drill 0.254)
		(layers "F.Cu" "B.Cu")
		(net "GND")
	)
	(via
		(at 41.082468 -18.414238)
		(size 0.508)
		(drill 0.254)
		(layers "F.Cu" "B.Cu")
		(net "GND")
	)
	(via
		(at 79.729076 -384.526282)
		(size 0.508)
		(drill 0.254)
		(layers "F.Cu" "B.Cu")
		(net "GND")
	)
	(via
		(at 58.716672 -249.34418)
		(size 0.508)
		(drill 0.254)
		(layers "F.Cu" "B.Cu")
		(net "GND")
	)
	(via
		(at 46.23308 -220.40088)
		(size 0.508)
		(drill 0.254)
		(layers "F.Cu" "B.Cu")
		(net "GND")
	)
	(via
		(at 62.748922 -156.470604)
		(size 0.508)
		(drill 0.254)
		(layers "F.Cu" "B.Cu")
		(net "GND")
	)
	(via
		(at 38.893496 -298.769024)
		(size 0.508)
		(drill 0.254)
		(layers "F.Cu" "B.Cu")
		(net "GND")
	)
	(via
		(at 64.002412 -306.775358)
		(size 0.508)
		(drill 0.254)
		(layers "F.Cu" "B.Cu")
		(net "GND")
	)
	(via
		(at 61.408818 -247.333008)
		(size 0.508)
		(drill 0.254)
		(layers "F.Cu" "B.Cu")
		(net "GND")
	)
	(via
		(at 65.553844 -247.333008)
		(size 0.508)
		(drill 0.254)
		(layers "F.Cu" "B.Cu")
		(net "GND")
	)
	(via
		(at 58.664602 -152.784302)
		(size 0.508)
		(drill 0.254)
		(layers "F.Cu" "B.Cu")
		(net "GND")
	)
	(via
		(at 58.732674 -304.734214)
		(size 0.508)
		(drill 0.254)
		(layers "F.Cu" "B.Cu")
		(net "GND")
	)
	(via
		(at 4.204208 -416.05327)
		(size 0.508)
		(drill 0.254)
		(layers "F.Cu" "B.Cu")
		(net "GND")
	)
	(via
		(at 44.458382 -71.854568)
		(size 0.508)
		(drill 0.254)
		(layers "F.Cu" "B.Cu")
		(net "GND")
	)
	(via
		(at 24.743918 -9.509252)
		(size 0.508)
		(drill 0.254)
		(layers "F.Cu" "B.Cu")
		(net "GND")
	)
	(via
		(at 24.774144 -95.65132)
		(size 0.508)
		(drill 0.254)
		(layers "F.Cu" "B.Cu")
		(net "GND")
	)
	(via
		(at 61.986922 -158.361126)
		(size 0.508)
		(drill 0.254)
		(layers "F.Cu" "B.Cu")
		(net "GND")
	)
	(via
		(at 102.238048 -220.245432)
		(size 0.508)
		(drill 0.254)
		(layers "F.Cu" "B.Cu")
		(net "GND")
	)
	(via
		(at 60.036964 -71.747634)
		(size 0.508)
		(drill 0.254)
		(layers "F.Cu" "B.Cu")
		(net "GND")
	)
	(via
		(at 59.74588 -160.40227)
		(size 0.508)
		(drill 0.254)
		(layers "F.Cu" "B.Cu")
		(net "GND")
	)
	(via
		(at 59.067192 -122.524774)
		(size 0.508)
		(drill 0.254)
		(layers "F.Cu" "B.Cu")
		(net "GND")
	)
	(via
		(at 59.74588 -156.470604)
		(size 0.508)
		(drill 0.254)
		(layers "F.Cu" "B.Cu")
		(net "GND")
	)
	(via
		(at 62.30112 -23.99665)
		(size 0.508)
		(drill 0.254)
		(layers "F.Cu" "B.Cu")
		(net "GND")
	)
	(via
		(at 0.762254 -50.808636)
		(size 0.508)
		(drill 0.254)
		(layers "F.Cu" "B.Cu")
		(net "GND")
	)
	(via
		(at 57.902602 -150.883366)
		(size 0.508)
		(drill 0.254)
		(layers "F.Cu" "B.Cu")
		(net "GND")
	)
	(via
		(at 24.801322 -100.590096)
		(size 0.508)
		(drill 0.254)
		(layers "F.Cu" "B.Cu")
		(net "GND")
	)
	(via
		(at 38.58768 -481.385626)
		(size 0.508)
		(drill 0.254)
		(layers "F.Cu" "B.Cu")
		(net "GND")
	)
	(via
		(at 57.859168 -160.40227)
		(size 0.508)
		(drill 0.254)
		(layers "F.Cu" "B.Cu")
		(net "GND")
	)
	(via
		(at 0.762254 -482.608636)
		(size 0.508)
		(drill 0.254)
		(layers "F.Cu" "B.Cu")
		(net "GND")
	)
	(via
		(at 57.545986 -424.278044)
		(size 0.508)
		(drill 0.254)
		(layers "F.Cu" "B.Cu")
		(net "GND")
	)
	(via
		(at 0.762254 -520.708636)
		(size 0.508)
		(drill 0.254)
		(layers "F.Cu" "B.Cu")
		(net "GND")
	)
	(via
		(at 73.963276 -242.936268)
		(size 0.508)
		(drill 0.254)
		(layers "F.Cu" "B.Cu")
		(net "GND")
	)
	(via
		(at 58.305192 -118.948708)
		(size 0.508)
		(drill 0.254)
		(layers "F.Cu" "B.Cu")
		(net "GND")
	)
	(via
		(at 69.370956 -199.635872)
		(size 0.508)
		(drill 0.254)
		(layers "F.Cu" "B.Cu")
		(net "GND")
	)
	(via
		(at 102.238048 -93.245432)
		(size 0.508)
		(drill 0.254)
		(layers "F.Cu" "B.Cu")
		(net "GND")
	)
	(via
		(at 61.178948 -69.70649)
		(size 0.508)
		(drill 0.254)
		(layers "F.Cu" "B.Cu")
		(net "GND")
	)
	(via
		(at 60.50788 -156.470604)
		(size 0.508)
		(drill 0.254)
		(layers "F.Cu" "B.Cu")
		(net "GND")
	)
	(via
		(at 39.655496 -296.935398)
		(size 0.508)
		(drill 0.254)
		(layers "F.Cu" "B.Cu")
		(net "GND")
	)
	(via
		(at 0.762254 -13.216636)
		(size 0.508)
		(drill 0.254)
		(layers "F.Cu" "B.Cu")
		(net "GND")
	)
	(via
		(at 62.409578 -433.796948)
		(size 0.508)
		(drill 0.254)
		(layers "F.Cu" "B.Cu")
		(net "GND")
	)
	(via
		(at 102.238048 -525.045432)
		(size 0.508)
		(drill 0.254)
		(layers "F.Cu" "B.Cu")
		(net "GND")
	)
	(via
		(at 60.551314 -152.784302)
		(size 0.508)
		(drill 0.254)
		(layers "F.Cu" "B.Cu")
		(net "GND")
	)
	(via
		(at 69.108828 -302.711358)
		(size 0.508)
		(drill 0.254)
		(layers "F.Cu" "B.Cu")
		(net "GND")
	)
	(via
		(at 44.925234 -298.769024)
		(size 0.508)
		(drill 0.254)
		(layers "F.Cu" "B.Cu")
		(net "GND")
	)
	(via
		(at 44.177712 -30.131004)
		(size 0.508)
		(drill 0.254)
		(layers "F.Cu" "B.Cu")
		(net "GND")
	)
	(via
		(at 41.281096 -371.513354)
		(size 0.508)
		(drill 0.254)
		(layers "F.Cu" "B.Cu")
		(net "GND")
	)
	(via
		(at 61.2648 -126.426468)
		(size 0.508)
		(drill 0.254)
		(layers "F.Cu" "B.Cu")
		(net "GND")
	)
	(via
		(at 62.30112 -20.064984)
		(size 0.508)
		(drill 0.254)
		(layers "F.Cu" "B.Cu")
		(net "GND")
	)
	(via
		(at 55.659274 -422.444418)
		(size 0.508)
		(drill 0.254)
		(layers "F.Cu" "B.Cu")
		(net "GND")
	)
	(via
		(at 55.61584 -433.796948)
		(size 0.508)
		(drill 0.254)
		(layers "F.Cu" "B.Cu")
		(net "GND")
	)
	(via
		(at 59.522106 -247.333008)
		(size 0.508)
		(drill 0.254)
		(layers "F.Cu" "B.Cu")
		(net "GND")
	)
	(via
		(at 26.445464 -20.969478)
		(size 0.508)
		(drill 0.254)
		(layers "F.Cu" "B.Cu")
		(net "GND")
	)
	(via
		(at 42.715434 -481.385626)
		(size 0.508)
		(drill 0.254)
		(layers "F.Cu" "B.Cu")
		(net "GND")
	)
	(via
		(at 74.575924 -472.101672)
		(size 0.508)
		(drill 0.254)
		(layers "F.Cu" "B.Cu")
		(net "GND")
	)
	(via
		(at 41.542208 -296.935398)
		(size 0.508)
		(drill 0.254)
		(layers "F.Cu" "B.Cu")
		(net "GND")
	)
	(via
		(at 61.984382 -65.804796)
		(size 0.508)
		(drill 0.254)
		(layers "F.Cu" "B.Cu")
		(net "GND")
	)
	(via
		(at 43.27144 -384.536696)
		(size 0.508)
		(drill 0.254)
		(layers "F.Cu" "B.Cu")
		(net "GND")
	)
	(via
		(at 46.276514 -208.97215)
		(size 0.508)
		(drill 0.254)
		(layers "F.Cu" "B.Cu")
		(net "GND")
	)
	(via
		(at 16.017494 -329.263248)
		(size 0.508)
		(drill 0.254)
		(layers "F.Cu" "B.Cu")
		(net "GND")
	)
	(via
		(at 64.764412 -304.734214)
		(size 0.508)
		(drill 0.254)
		(layers "F.Cu" "B.Cu")
		(net "GND")
	)
	(via
		(at 63.06312 -23.99665)
		(size 0.508)
		(drill 0.254)
		(layers "F.Cu" "B.Cu")
		(net "GND")
	)
	(via
		(at 89.253314 -349.55734)
		(size 0.508)
		(drill 0.254)
		(layers "F.Cu" "B.Cu")
		(net "GND")
	)
	(via
		(at 59.743594 -431.755804)
		(size 0.508)
		(drill 0.254)
		(layers "F.Cu" "B.Cu")
		(net "GND")
	)
	(via
		(at 71.392796 -81.962752)
		(size 0.508)
		(drill 0.254)
		(layers "F.Cu" "B.Cu")
		(net "GND")
	)
	(via
		(at 59.787028 -427.85411)
		(size 0.508)
		(drill 0.254)
		(layers "F.Cu" "B.Cu")
		(net "GND")
	)
	(via
		(at 72.520302 -81.962752)
		(size 0.508)
		(drill 0.254)
		(layers "F.Cu" "B.Cu")
		(net "GND")
	)
	(via
		(at 40.244776 -212.548216)
		(size 0.508)
		(drill 0.254)
		(layers "F.Cu" "B.Cu")
		(net "GND")
	)
	(via
		(at 26.839926 -461.067658)
		(size 0.508)
		(drill 0.254)
		(layers "F.Cu" "B.Cu")
		(net "GND")
	)
	(via
		(at 62.344554 -14.477746)
		(size 0.508)
		(drill 0.254)
		(layers "F.Cu" "B.Cu")
		(net "GND")
	)
	(via
		(at 82.605626 -0.762508)
		(size 0.508)
		(drill 0.254)
		(layers "F.Cu" "B.Cu")
		(net "GND")
	)
	(via
		(at 4.059936 -147.027646)
		(size 0.508)
		(drill 0.254)
		(layers "F.Cu" "B.Cu")
		(net "GND")
	)
	(via
		(at 60.505594 -433.796948)
		(size 0.508)
		(drill 0.254)
		(layers "F.Cu" "B.Cu")
		(net "GND")
	)
	(via
		(at 57.970674 -308.685184)
		(size 0.508)
		(drill 0.254)
		(layers "F.Cu" "B.Cu")
		(net "GND")
	)
	(via
		(at 74.345292 -287.311084)
		(size 0.508)
		(drill 0.254)
		(layers "F.Cu" "B.Cu")
		(net "GND")
	)
	(via
		(at 42.247566 -39.649908)
		(size 0.508)
		(drill 0.254)
		(layers "F.Cu" "B.Cu")
		(net "GND")
	)
	(via
		(at 90.015314 -337.740244)
		(size 0.508)
		(drill 0.254)
		(layers "F.Cu" "B.Cu")
		(net "GND")
	)
	(via
		(at 40.451786 -124.69622)
		(size 0.508)
		(drill 0.254)
		(layers "F.Cu" "B.Cu")
		(net "GND")
	)
	(via
		(at 0.762254 -254.008636)
		(size 0.508)
		(drill 0.254)
		(layers "F.Cu" "B.Cu")
		(net "GND")
	)
	(via
		(at 39.73322 -117.275356)
		(size 0.508)
		(drill 0.254)
		(layers "F.Cu" "B.Cu")
		(net "GND")
	)
	(via
		(at 59.274964 -73.65746)
		(size 0.508)
		(drill 0.254)
		(layers "F.Cu" "B.Cu")
		(net "GND")
	)
	(via
		(at 60.619386 -308.685184)
		(size 0.508)
		(drill 0.254)
		(layers "F.Cu" "B.Cu")
		(net "GND")
	)
	(via
		(at 64.002412 -308.685184)
		(size 0.508)
		(drill 0.254)
		(layers "F.Cu" "B.Cu")
		(net "GND")
	)
	(via
		(at 63.64986 -243.756942)
		(size 0.508)
		(drill 0.254)
		(layers "F.Cu" "B.Cu")
		(net "GND")
	)
	(via
		(at 91.896946 -79.232252)
		(size 0.508)
		(drill 0.254)
		(layers "F.Cu" "B.Cu")
		(net "GND")
	)
	(via
		(at 60.080398 -64.129666)
		(size 0.508)
		(drill 0.254)
		(layers "F.Cu" "B.Cu")
		(net "GND")
	)
	(via
		(at 62.344554 -18.053812)
		(size 0.508)
		(drill 0.254)
		(layers "F.Cu" "B.Cu")
		(net "GND")
	)
	(via
		(at 41.748964 -390.11352)
		(size 0.508)
		(drill 0.254)
		(layers "F.Cu" "B.Cu")
		(net "GND")
	)
	(via
		(at 24.84755 -360.550968)
		(size 0.508)
		(drill 0.254)
		(layers "F.Cu" "B.Cu")
		(net "GND")
	)
	(via
		(at 59.274964 -67.815968)
		(size 0.508)
		(drill 0.254)
		(layers "F.Cu" "B.Cu")
		(net "GND")
	)
	(via
		(at 39.100252 -392.154664)
		(size 0.508)
		(drill 0.254)
		(layers "F.Cu" "B.Cu")
		(net "GND")
	)
	(via
		(at 63.890906 -156.470604)
		(size 0.508)
		(drill 0.254)
		(layers "F.Cu" "B.Cu")
		(net "GND")
	)
	(via
		(at 40.517826 -479.374454)
		(size 0.508)
		(drill 0.254)
		(layers "F.Cu" "B.Cu")
		(net "GND")
	)
	(via
		(at 43.477434 -481.385626)
		(size 0.508)
		(drill 0.254)
		(layers "F.Cu" "B.Cu")
		(net "GND")
	)
	(via
		(at 72.559164 -258.105148)
		(size 0.508)
		(drill 0.254)
		(layers "F.Cu" "B.Cu")
		(net "GND")
	)
	(via
		(at 0.762254 -165.108636)
		(size 0.508)
		(drill 0.254)
		(layers "F.Cu" "B.Cu")
		(net "GND")
	)
	(via
		(at 57.502552 -431.755804)
		(size 0.508)
		(drill 0.254)
		(layers "F.Cu" "B.Cu")
		(net "GND")
	)
	(via
		(at 44.619418 -485.317292)
		(size 0.508)
		(drill 0.254)
		(layers "F.Cu" "B.Cu")
		(net "GND")
	)
	(via
		(at 0.762254 -190.508636)
		(size 0.508)
		(drill 0.254)
		(layers "F.Cu" "B.Cu")
		(net "GND")
	)
	(via
		(at 56.37784 -431.755804)
		(size 0.508)
		(drill 0.254)
		(layers "F.Cu" "B.Cu")
		(net "GND")
	)
	(via
		(at 39.862252 -390.11352)
		(size 0.508)
		(drill 0.254)
		(layers "F.Cu" "B.Cu")
		(net "GND")
	)
	(via
		(at 61.2648 -130.377438)
		(size 0.508)
		(drill 0.254)
		(layers "F.Cu" "B.Cu")
		(net "GND")
	)
	(via
		(at 39.143686 -380.802134)
		(size 0.508)
		(drill 0.254)
		(layers "F.Cu" "B.Cu")
		(net "GND")
	)
	(via
		(at 15.719552 -169.167048)
		(size 0.508)
		(drill 0.254)
		(layers "F.Cu" "B.Cu")
		(net "GND")
	)
	(via
		(at 71.815198 -198.791322)
		(size 0.508)
		(drill 0.254)
		(layers "F.Cu" "B.Cu")
		(net "GND")
	)
	(via
		(at 44.329096 -214.559388)
		(size 0.508)
		(drill 0.254)
		(layers "F.Cu" "B.Cu")
		(net "GND")
	)
	(via
		(at 65.553844 -245.657878)
		(size 0.508)
		(drill 0.254)
		(layers "F.Cu" "B.Cu")
		(net "GND")
	)
	(via
		(at 43.990006 -388.222998)
		(size 0.508)
		(drill 0.254)
		(layers "F.Cu" "B.Cu")
		(net "GND")
	)
	(via
		(at 102.238048 -245.645432)
		(size 0.508)
		(drill 0.254)
		(layers "F.Cu" "B.Cu")
		(net "GND")
	)
	(via
		(at 64.69634 -154.459432)
		(size 0.508)
		(drill 0.254)
		(layers "F.Cu" "B.Cu")
		(net "GND")
	)
	(via
		(at 61.20257 -14.477746)
		(size 0.508)
		(drill 0.254)
		(layers "F.Cu" "B.Cu")
		(net "GND")
	)
	(via
		(at 22.014942 -174.17034)
		(size 0.508)
		(drill 0.254)
		(layers "F.Cu" "B.Cu")
		(net "GND")
	)
	(via
		(at 63.890906 -162.312096)
		(size 0.508)
		(drill 0.254)
		(layers "F.Cu" "B.Cu")
		(net "GND")
	)
	(via
		(at 39.905686 -382.63576)
		(size 0.508)
		(drill 0.254)
		(layers "F.Cu" "B.Cu")
		(net "GND")
	)
	(via
		(at 60.50788 -162.312096)
		(size 0.508)
		(drill 0.254)
		(layers "F.Cu" "B.Cu")
		(net "GND")
	)
	(via
		(at 58.261758 -124.535946)
		(size 0.508)
		(drill 0.254)
		(layers "F.Cu" "B.Cu")
		(net "GND")
	)
	(via
		(at 23.817834 -444.049658)
		(size 0.508)
		(drill 0.254)
		(layers "F.Cu" "B.Cu")
		(net "GND")
	)
	(via
		(at 45.47108 -216.44991)
		(size 0.508)
		(drill 0.254)
		(layers "F.Cu" "B.Cu")
		(net "GND")
	)
	(via
		(at 45.220382 -66.444876)
		(size 0.508)
		(drill 0.254)
		(layers "F.Cu" "B.Cu")
		(net "GND")
	)
	(via
		(at 38.631114 -477.699324)
		(size 0.508)
		(drill 0.254)
		(layers "F.Cu" "B.Cu")
		(net "GND")
	)
	(via
		(at 39.34968 -481.385626)
		(size 0.508)
		(drill 0.254)
		(layers "F.Cu" "B.Cu")
		(net "GND")
	)
	(via
		(at 59.478672 -255.185672)
		(size 0.508)
		(drill 0.254)
		(layers "F.Cu" "B.Cu")
		(net "GND")
	)
	(via
		(at 39.73322 -119.108982)
		(size 0.508)
		(drill 0.254)
		(layers "F.Cu" "B.Cu")
		(net "GND")
	)
	(via
		(at 43.02125 -302.34509)
		(size 0.508)
		(drill 0.254)
		(layers "F.Cu" "B.Cu")
		(net "GND")
	)
	(via
		(at 46.765972 -258.89712)
		(size 0.508)
		(drill 0.254)
		(layers "F.Cu" "B.Cu")
		(net "GND")
	)
	(via
		(at 41.369488 -210.873086)
		(size 0.508)
		(drill 0.254)
		(layers "F.Cu" "B.Cu")
		(net "GND")
	)
	(via
		(at 41.18356 -459.16596)
		(size 0.508)
		(drill 0.254)
		(layers "F.Cu" "B.Cu")
		(net "GND")
	)
	(via
		(at 44.619418 -487.227118)
		(size 0.508)
		(drill 0.254)
		(layers "F.Cu" "B.Cu")
		(net "GND")
	)
	(via
		(at 75.151996 -242.936268)
		(size 0.508)
		(drill 0.254)
		(layers "F.Cu" "B.Cu")
		(net "GND")
	)
	(via
		(at 41.279826 -479.374454)
		(size 0.508)
		(drill 0.254)
		(layers "F.Cu" "B.Cu")
		(net "GND")
	)
	(via
		(at 62.88786 -247.333008)
		(size 0.508)
		(drill 0.254)
		(layers "F.Cu" "B.Cu")
		(net "GND")
	)
	(via
		(at 42.088054 -214.559388)
		(size 0.508)
		(drill 0.254)
		(layers "F.Cu" "B.Cu")
		(net "GND")
	)
	(via
		(at 62.88786 -243.756942)
		(size 0.508)
		(drill 0.254)
		(layers "F.Cu" "B.Cu")
		(net "GND")
	)
	(via
		(at 40.986964 -390.11352)
		(size 0.508)
		(drill 0.254)
		(layers "F.Cu" "B.Cu")
		(net "GND")
	)
	(via
		(at 89.493598 -479.37039)
		(size 0.508)
		(drill 0.254)
		(layers "F.Cu" "B.Cu")
		(net "GND")
	)
	(via
		(at 57.545986 -427.85411)
		(size 0.508)
		(drill 0.254)
		(layers "F.Cu" "B.Cu")
		(net "GND")
	)
	(via
		(at 44.329096 -220.40088)
		(size 0.508)
		(drill 0.254)
		(layers "F.Cu" "B.Cu")
		(net "GND")
	)
	(via
		(at 102.238048 -156.745432)
		(size 0.508)
		(drill 0.254)
		(layers "F.Cu" "B.Cu")
		(net "GND")
	)
	(via
		(at 56.37784 -429.865282)
		(size 0.508)
		(drill 0.254)
		(layers "F.Cu" "B.Cu")
		(net "GND")
	)
	(via
		(at 64.791844 -243.756942)
		(size 0.508)
		(drill 0.254)
		(layers "F.Cu" "B.Cu")
		(net "GND")
	)
	(via
		(at 24.923496 -189.265306)
		(size 0.508)
		(drill 0.254)
		(layers "F.Cu" "B.Cu")
		(net "GND")
	)
	(via
		(at 61.984382 -62.22873)
		(size 0.508)
		(drill 0.254)
		(layers "F.Cu" "B.Cu")
		(net "GND")
	)
	(via
		(at 58.760106 -243.756942)
		(size 0.508)
		(drill 0.254)
		(layers "F.Cu" "B.Cu")
		(net "GND")
	)
	(via
		(at 41.209468 -373.73052)
		(size 0.508)
		(drill 0.254)
		(layers "F.Cu" "B.Cu")
		(net "GND")
	)
	(via
		(at 40.986964 -392.154664)
		(size 0.508)
		(drill 0.254)
		(layers "F.Cu" "B.Cu")
		(net "GND")
	)
	(via
		(at 38.850062 -304.356262)
		(size 0.508)
		(drill 0.254)
		(layers "F.Cu" "B.Cu")
		(net "GND")
	)
	(via
		(at 43.990006 -392.154664)
		(size 0.508)
		(drill 0.254)
		(layers "F.Cu" "B.Cu")
		(net "GND")
	)
	(via
		(at 102.238048 -372.645432)
		(size 0.508)
		(drill 0.254)
		(layers "F.Cu" "B.Cu")
		(net "GND")
	)
	(via
		(at 66.689986 -302.711358)
		(size 0.508)
		(drill 0.254)
		(layers "F.Cu" "B.Cu")
		(net "GND")
	)
	(via
		(at 64.791844 -245.657878)
		(size 0.508)
		(drill 0.254)
		(layers "F.Cu" "B.Cu")
		(net "GND")
	)
	(via
		(at 71.871332 -288.155634)
		(size 0.508)
		(drill 0.254)
		(layers "F.Cu" "B.Cu")
		(net "GND")
	)
	(via
		(at 64.652906 -158.361126)
		(size 0.508)
		(drill 0.254)
		(layers "F.Cu" "B.Cu")
		(net "GND")
	)
	(via
		(at 60.549028 -424.278044)
		(size 0.508)
		(drill 0.254)
		(layers "F.Cu" "B.Cu")
		(net "GND")
	)
	(via
		(at 44.134278 -41.559734)
		(size 0.508)
		(drill 0.254)
		(layers "F.Cu" "B.Cu")
		(net "GND")
	)
	(via
		(at 90.015314 -345.450922)
		(size 0.508)
		(drill 0.254)
		(layers "F.Cu" "B.Cu")
		(net "GND")
	)
	(via
		(at 39.439342 -220.40088)
		(size 0.508)
		(drill 0.254)
		(layers "F.Cu" "B.Cu")
		(net "GND")
	)
	(via
		(at 91.437714 -529.236178)
		(size 0.508)
		(drill 0.254)
		(layers "F.Cu" "B.Cu")
		(net "GND")
	)
	(via
		(at 69.905626 -0.762508)
		(size 0.508)
		(drill 0.254)
		(layers "F.Cu" "B.Cu")
		(net "GND")
	)
	(via
		(at 58.621168 -156.470604)
		(size 0.508)
		(drill 0.254)
		(layers "F.Cu" "B.Cu")
		(net "GND")
	)
	(via
		(at 25.172162 -448.493388)
		(size 0.508)
		(drill 0.254)
		(layers "F.Cu" "B.Cu")
		(net "GND")
	)
	(via
		(at 0.762254 -228.608636)
		(size 0.508)
		(drill 0.254)
		(layers "F.Cu" "B.Cu")
		(net "GND")
	)
	(via
		(at 62.344554 -16.378682)
		(size 0.508)
		(drill 0.254)
		(layers "F.Cu" "B.Cu")
		(net "GND")
	)
	(via
		(at 57.502552 -429.865282)
		(size 0.508)
		(drill 0.254)
		(layers "F.Cu" "B.Cu")
		(net "GND")
	)
	(via
		(at 39.100252 -394.06449)
		(size 0.508)
		(drill 0.254)
		(layers "F.Cu" "B.Cu")
		(net "GND")
	)
	(via
		(at 61.647578 -433.796948)
		(size 0.508)
		(drill 0.254)
		(layers "F.Cu" "B.Cu")
		(net "GND")
	)
	(via
		(at 22.524974 -178.843432)
		(size 0.508)
		(drill 0.254)
		(layers "F.Cu" "B.Cu")
		(net "GND")
	)
	(via
		(at 40.49522 -117.275356)
		(size 0.508)
		(drill 0.254)
		(layers "F.Cu" "B.Cu")
		(net "GND")
	)
	(via
		(at 44.619418 -483.276148)
		(size 0.508)
		(drill 0.254)
		(layers "F.Cu" "B.Cu")
		(net "GND")
	)
	(via
		(at 72.087232 -332.475586)
		(size 0.508)
		(drill 0.254)
		(layers "F.Cu" "B.Cu")
		(net "GND")
	)
	(via
		(at 62.748922 -162.312096)
		(size 0.508)
		(drill 0.254)
		(layers "F.Cu" "B.Cu")
		(net "GND")
	)
	(via
		(at 0.762254 -393.708636)
		(size 0.508)
		(drill 0.254)
		(layers "F.Cu" "B.Cu")
		(net "GND")
	)
	(via
		(at 45.937424 -384.536696)
		(size 0.508)
		(drill 0.254)
		(layers "F.Cu" "B.Cu")
		(net "GND")
	)
	(via
		(at 60.505594 -431.755804)
		(size 0.508)
		(drill 0.254)
		(layers "F.Cu" "B.Cu")
		(net "GND")
	)
	(via
		(at 102.238048 -398.045432)
		(size 0.508)
		(drill 0.254)
		(layers "F.Cu" "B.Cu")
		(net "GND")
	)
	(via
		(at 41.542208 -302.34509)
		(size 0.508)
		(drill 0.254)
		(layers "F.Cu" "B.Cu")
		(net "GND")
	)
	(via
		(at 62.792356 -150.883366)
		(size 0.508)
		(drill 0.254)
		(layers "F.Cu" "B.Cu")
		(net "GND")
	)
	(via
		(at 61.159136 -23.99665)
		(size 0.508)
		(drill 0.254)
		(layers "F.Cu" "B.Cu")
		(net "GND")
	)
	(via
		(at 40.451786 -126.586742)
		(size 0.508)
		(drill 0.254)
		(layers "F.Cu" "B.Cu")
		(net "GND")
	)
	(via
		(at 58.307986 -424.278044)
		(size 0.508)
		(drill 0.254)
		(layers "F.Cu" "B.Cu")
		(net "GND")
	)
	(via
		(at 61.308234 -122.524774)
		(size 0.508)
		(drill 0.254)
		(layers "F.Cu" "B.Cu")
		(net "GND")
	)
	(via
		(at 0.762254 -177.808636)
		(size 0.508)
		(drill 0.254)
		(layers "F.Cu" "B.Cu")
		(net "GND")
	)
	(via
		(at 24.750522 -187.950348)
		(size 0.508)
		(drill 0.254)
		(layers "F.Cu" "B.Cu")
		(net "GND")
	)
	(via
		(at 43.228006 -390.11352)
		(size 0.508)
		(drill 0.254)
		(layers "F.Cu" "B.Cu")
		(net "GND")
	)
	(via
		(at 38.58768 -485.317292)
		(size 0.508)
		(drill 0.254)
		(layers "F.Cu" "B.Cu")
		(net "GND")
	)
	(via
		(at 24.613616 -271.14881)
		(size 0.508)
		(drill 0.254)
		(layers "F.Cu" "B.Cu")
		(net "GND")
	)
	(via
		(at 57.077356 -64.129666)
		(size 0.508)
		(drill 0.254)
		(layers "F.Cu" "B.Cu")
		(net "GND")
	)
	(via
		(at 40.451786 -130.537712)
		(size 0.508)
		(drill 0.254)
		(layers "F.Cu" "B.Cu")
		(net "GND")
	)
	(via
		(at 71.423022 -65.182496)
		(size 0.508)
		(drill 0.254)
		(layers "F.Cu" "B.Cu")
		(net "GND")
	)
	(via
		(at 61.986922 -160.40227)
		(size 0.508)
		(drill 0.254)
		(layers "F.Cu" "B.Cu")
		(net "GND")
	)
	(via
		(at 79.524606 -20.009612)
		(size 0.508)
		(drill 0.254)
		(layers "F.Cu" "B.Cu")
		(net "GND")
	)
	(via
		(at 0.762254 -203.208636)
		(size 0.508)
		(drill 0.254)
		(layers "F.Cu" "B.Cu")
		(net "GND")
	)
	(via
		(at 62.748922 -160.40227)
		(size 0.508)
		(drill 0.254)
		(layers "F.Cu" "B.Cu")
		(net "GND")
	)
	(via
		(at 43.61053 -210.873086)
		(size 0.508)
		(drill 0.254)
		(layers "F.Cu" "B.Cu")
		(net "GND")
	)
	(via
		(at 81.29143 -509.32461)
		(size 0.508)
		(drill 0.254)
		(layers "F.Cu" "B.Cu")
		(net "GND")
	)
	(via
		(at 45.424852 -477.699324)
		(size 0.508)
		(drill 0.254)
		(layers "F.Cu" "B.Cu")
		(net "GND")
	)
	(via
		(at 58.664602 -154.459432)
		(size 0.508)
		(drill 0.254)
		(layers "F.Cu" "B.Cu")
		(net "GND")
	)
	(via
		(at 59.743594 -433.796948)
		(size 0.508)
		(drill 0.254)
		(layers "F.Cu" "B.Cu")
		(net "GND")
	)
	(via
		(at 57.545986 -422.444418)
		(size 0.508)
		(drill 0.254)
		(layers "F.Cu" "B.Cu")
		(net "GND")
	)
	(via
		(at 40.49522 -122.685048)
		(size 0.508)
		(drill 0.254)
		(layers "F.Cu" "B.Cu")
		(net "GND")
	)
	(via
		(at 39.482776 -210.873086)
		(size 0.508)
		(drill 0.254)
		(layers "F.Cu" "B.Cu")
		(net "GND")
	)
	(via
		(at 45.13199 -394.06449)
		(size 0.508)
		(drill 0.254)
		(layers "F.Cu" "B.Cu")
		(net "GND")
	)
	(via
		(at 58.307986 -422.444418)
		(size 0.508)
		(drill 0.254)
		(layers "F.Cu" "B.Cu")
		(net "GND")
	)
	(via
		(at 59.857386 -308.685184)
		(size 0.508)
		(drill 0.254)
		(layers "F.Cu" "B.Cu")
		(net "GND")
	)
	(via
		(at 26.843736 -285.983426)
		(size 0.508)
		(drill 0.254)
		(layers "F.Cu" "B.Cu")
		(net "GND")
	)
	(via
		(at 44.939712 -32.03194)
		(size 0.508)
		(drill 0.254)
		(layers "F.Cu" "B.Cu")
		(net "GND")
	)
	(via
		(at 2.772156 -147.027392)
		(size 0.508)
		(drill 0.254)
		(layers "F.Cu" "B.Cu")
		(net "GND")
	)
	(via
		(at 102.238048 -169.445432)
		(size 0.508)
		(drill 0.254)
		(layers "F.Cu" "B.Cu")
		(net "GND")
	)
	(via
		(at 58.732674 -308.685184)
		(size 0.508)
		(drill 0.254)
		(layers "F.Cu" "B.Cu")
		(net "GND")
	)
	(via
		(at 71.390764 -465.980526)
		(size 0.508)
		(drill 0.254)
		(layers "F.Cu" "B.Cu")
		(net "GND")
	)
	(via
		(at 31.805626 -0.762508)
		(size 0.508)
		(drill 0.254)
		(layers "F.Cu" "B.Cu")
		(net "GND")
	)
	(via
		(at 64.652906 -156.470604)
		(size 0.508)
		(drill 0.254)
		(layers "F.Cu" "B.Cu")
		(net "GND")
	)
	(via
		(at 70.115176 -158.655258)
		(size 0.508)
		(drill 0.254)
		(layers "F.Cu" "B.Cu")
		(net "GND")
	)
	(via
		(at 74.0537 -464.780884)
		(size 0.508)
		(drill 0.254)
		(layers "F.Cu" "B.Cu")
		(net "GND")
	)
	(via
		(at 93.006926 -345.450922)
		(size 0.508)
		(drill 0.254)
		(layers "F.Cu" "B.Cu")
		(net "GND")
	)
	(via
		(at 42.291 -32.03194)
		(size 0.508)
		(drill 0.254)
		(layers "F.Cu" "B.Cu")
		(net "GND")
	)
	(via
		(at 45.514514 -208.97215)
		(size 0.508)
		(drill 0.254)
		(layers "F.Cu" "B.Cu")
		(net "GND")
	)
	(via
		(at 41.326054 -214.559388)
		(size 0.508)
		(drill 0.254)
		(layers "F.Cu" "B.Cu")
		(net "GND")
	)
	(via
		(at 45.89399 -394.06449)
		(size 0.508)
		(drill 0.254)
		(layers "F.Cu" "B.Cu")
		(net "GND")
	)
	(via
		(at 39.612062 -304.356262)
		(size 0.508)
		(drill 0.254)
		(layers "F.Cu" "B.Cu")
		(net "GND")
	)
	(via
		(at 102.238048 -461.545432)
		(size 0.508)
		(drill 0.254)
		(layers "F.Cu" "B.Cu")
		(net "GND")
	)
	(via
		(at 68.727066 -349.155004)
		(size 0.508)
		(drill 0.254)
		(layers "F.Cu" "B.Cu")
		(net "GND")
	)
	(via
		(at 64.764412 -306.775358)
		(size 0.508)
		(drill 0.254)
		(layers "F.Cu" "B.Cu")
		(net "GND")
	)
	(via
		(at 77.43698 -391.975594)
		(size 0.508)
		(drill 0.254)
		(layers "F.Cu" "B.Cu")
		(net "GND")
	)
	(via
		(at 44.03344 -384.536696)
		(size 0.508)
		(drill 0.254)
		(layers "F.Cu" "B.Cu")
		(net "GND")
	)
	(via
		(at 23.23084 -448.325748)
		(size 0.508)
		(drill 0.254)
		(layers "F.Cu" "B.Cu")
		(net "GND")
	)
	(via
		(at 58.621168 -162.312096)
		(size 0.508)
		(drill 0.254)
		(layers "F.Cu" "B.Cu")
		(net "GND")
	)
	(via
		(at 60.397136 -20.064984)
		(size 0.508)
		(drill 0.254)
		(layers "F.Cu" "B.Cu")
		(net "GND")
	)
	(via
		(at 59.787028 -424.278044)
		(size 0.508)
		(drill 0.254)
		(layers "F.Cu" "B.Cu")
		(net "GND")
	)
	(via
		(at 24.625046 -276.12213)
		(size 0.508)
		(drill 0.254)
		(layers "F.Cu" "B.Cu")
		(net "GND")
	)
	(via
		(at 62.406784 -124.535946)
		(size 0.508)
		(drill 0.254)
		(layers "F.Cu" "B.Cu")
		(net "GND")
	)
	(via
		(at 0.762254 -330.208636)
		(size 0.508)
		(drill 0.254)
		(layers "F.Cu" "B.Cu")
		(net "GND")
	)
	(via
		(at 79.898748 -510.308098)
		(size 0.508)
		(drill 0.254)
		(layers "F.Cu" "B.Cu")
		(net "GND")
	)
	(via
		(at 41.369488 -208.97215)
		(size 0.508)
		(drill 0.254)
		(layers "F.Cu" "B.Cu")
		(net "GND")
	)
	(via
		(at 62.098428 -308.685184)
		(size 0.508)
		(drill 0.254)
		(layers "F.Cu" "B.Cu")
		(net "GND")
	)
	(via
		(at 61.308234 -118.948708)
		(size 0.508)
		(drill 0.254)
		(layers "F.Cu" "B.Cu")
		(net "GND")
	)
	(via
		(at 82.499962 -509.339088)
		(size 0.508)
		(drill 0.254)
		(layers "F.Cu" "B.Cu")
		(net "GND")
	)
	(via
		(at 62.098428 -306.775358)
		(size 0.508)
		(drill 0.254)
		(layers "F.Cu" "B.Cu")
		(net "GND")
	)
	(via
		(at 63.168784 -126.426468)
		(size 0.508)
		(drill 0.254)
		(layers "F.Cu" "B.Cu")
		(net "GND")
	)
	(via
		(at 0.762254 -76.208636)
		(size 0.508)
		(drill 0.254)
		(layers "F.Cu" "B.Cu")
		(net "GND")
	)
	(via
		(at 58.264552 -429.865282)
		(size 0.508)
		(drill 0.254)
		(layers "F.Cu" "B.Cu")
		(net "GND")
	)
	(via
		(at 41.792398 -382.63576)
		(size 0.508)
		(drill 0.254)
		(layers "F.Cu" "B.Cu")
		(net "GND")
	)
	(via
		(at 89.253314 -347.413834)
		(size 0.508)
		(drill 0.254)
		(layers "F.Cu" "B.Cu")
		(net "GND")
	)
	(via
		(at 38.893496 -302.34509)
		(size 0.508)
		(drill 0.254)
		(layers "F.Cu" "B.Cu")
		(net "GND")
	)
	(via
		(at 61.408818 -245.657878)
		(size 0.508)
		(drill 0.254)
		(layers "F.Cu" "B.Cu")
		(net "GND")
	)
	(via
		(at 0.762254 -88.908636)
		(size 0.508)
		(drill 0.254)
		(layers "F.Cu" "B.Cu")
		(net "GND")
	)
	(via
		(at 0.762254 -139.708636)
		(size 0.508)
		(drill 0.254)
		(layers "F.Cu" "B.Cu")
		(net "GND")
	)
	(via
		(at 102.238048 -448.845432)
		(size 0.508)
		(drill 0.254)
		(layers "F.Cu" "B.Cu")
		(net "GND")
	)
	(via
		(at 61.222382 -62.22873)
		(size 0.508)
		(drill 0.254)
		(layers "F.Cu" "B.Cu")
		(net "GND")
	)
	(via
		(at 0.762254 -114.308636)
		(size 0.508)
		(drill 0.254)
		(layers "F.Cu" "B.Cu")
		(net "GND")
	)
	(via
		(at 43.02125 -300.66996)
		(size 0.508)
		(drill 0.254)
		(layers "F.Cu" "B.Cu")
		(net "GND")
	)
	(via
		(at 63.890906 -158.361126)
		(size 0.508)
		(drill 0.254)
		(layers "F.Cu" "B.Cu")
		(net "GND")
	)
	(via
		(at 89.253314 -337.740244)
		(size 0.508)
		(drill 0.254)
		(layers "F.Cu" "B.Cu")
		(net "GND")
	)
	(via
		(at 57.033922 -71.747634)
		(size 0.508)
		(drill 0.254)
		(layers "F.Cu" "B.Cu")
		(net "GND")
	)
	(via
		(at 65.51041 -251.234702)
		(size 0.508)
		(drill 0.254)
		(layers "F.Cu" "B.Cu")
		(net "GND")
	)
	(via
		(at 39.655496 -300.66996)
		(size 0.508)
		(drill 0.254)
		(layers "F.Cu" "B.Cu")
		(net "GND")
	)
	(via
		(at 45.937424 -382.63576)
		(size 0.508)
		(drill 0.254)
		(layers "F.Cu" "B.Cu")
		(net "GND")
	)
	(via
		(at 60.5028 -126.426468)
		(size 0.508)
		(drill 0.254)
		(layers "F.Cu" "B.Cu")
		(net "GND")
	)
	(via
		(at 61.2648 -128.467612)
		(size 0.508)
		(drill 0.254)
		(layers "F.Cu" "B.Cu")
		(net "GND")
	)
	(via
		(at 58.760106 -247.333008)
		(size 0.508)
		(drill 0.254)
		(layers "F.Cu" "B.Cu")
		(net "GND")
	)
	(via
		(at 59.478672 -253.275846)
		(size 0.508)
		(drill 0.254)
		(layers "F.Cu" "B.Cu")
		(net "GND")
	)
	(via
		(at 42.247566 -37.608764)
		(size 0.508)
		(drill 0.254)
		(layers "F.Cu" "B.Cu")
		(net "GND")
	)
	(via
		(at 41.748964 -392.154664)
		(size 0.508)
		(drill 0.254)
		(layers "F.Cu" "B.Cu")
		(net "GND")
	)
	(via
		(at 63.93434 -150.883366)
		(size 0.508)
		(drill 0.254)
		(layers "F.Cu" "B.Cu")
		(net "GND")
	)
	(via
		(at 41.236392 -481.385626)
		(size 0.508)
		(drill 0.254)
		(layers "F.Cu" "B.Cu")
		(net "GND")
	)
	(via
		(at 62.860428 -304.734214)
		(size 0.508)
		(drill 0.254)
		(layers "F.Cu" "B.Cu")
		(net "GND")
	)
	(via
		(at 44.03344 -386.211826)
		(size 0.508)
		(drill 0.254)
		(layers "F.Cu" "B.Cu")
		(net "GND")
	)
	(via
		(at 59.789314 -152.784302)
		(size 0.508)
		(drill 0.254)
		(layers "F.Cu" "B.Cu")
		(net "GND")
	)
	(via
		(at 74.709782 -331.631036)
		(size 0.508)
		(drill 0.254)
		(layers "F.Cu" "B.Cu")
		(net "GND")
	)
	(via
		(at 41.326054 -216.44991)
		(size 0.508)
		(drill 0.254)
		(layers "F.Cu" "B.Cu")
		(net "GND")
	)
	(via
		(at 62.450218 -120.849644)
		(size 0.508)
		(drill 0.254)
		(layers "F.Cu" "B.Cu")
		(net "GND")
	)
	(via
		(at 60.50788 -160.40227)
		(size 0.508)
		(drill 0.254)
		(layers "F.Cu" "B.Cu")
		(net "GND")
	)
	(via
		(at 43.477434 -485.317292)
		(size 0.508)
		(drill 0.254)
		(layers "F.Cu" "B.Cu")
		(net "GND")
	)
	(via
		(at 69.863208 -349.17761)
		(size 0.508)
		(drill 0.254)
		(layers "F.Cu" "B.Cu")
		(net "GND")
	)
	(via
		(at 46.785784 -245.712234)
		(size 0.508)
		(drill 0.254)
		(layers "F.Cu" "B.Cu")
		(net "GND")
	)
	(via
		(at 59.023758 -126.426468)
		(size 0.508)
		(drill 0.254)
		(layers "F.Cu" "B.Cu")
		(net "GND")
	)
	(via
		(at 102.238048 -283.745432)
		(size 0.508)
		(drill 0.254)
		(layers "F.Cu" "B.Cu")
		(net "GND")
	)
	(via
		(at 43.61053 -208.97215)
		(size 0.508)
		(drill 0.254)
		(layers "F.Cu" "B.Cu")
		(net "GND")
	)
	(via
		(at 57.077356 -60.395104)
		(size 0.508)
		(drill 0.254)
		(layers "F.Cu" "B.Cu")
		(net "GND")
	)
	(via
		(at 64.74841 -253.275846)
		(size 0.508)
		(drill 0.254)
		(layers "F.Cu" "B.Cu")
		(net "GND")
	)
	(via
		(at 71.518526 -110.786926)
		(size 0.508)
		(drill 0.254)
		(layers "F.Cu" "B.Cu")
		(net "GND")
	)
	(via
		(at 20.717002 -179.180998)
		(size 0.508)
		(drill 0.254)
		(layers "F.Cu" "B.Cu")
		(net "GND")
	)
	(via
		(at 61.408818 -243.756942)
		(size 0.508)
		(drill 0.254)
		(layers "F.Cu" "B.Cu")
		(net "GND")
	)
	(via
		(at 0.762254 -152.408636)
		(size 0.508)
		(drill 0.254)
		(layers "F.Cu" "B.Cu")
		(net "GND")
	)
	(via
		(at 27.00909 -5.73532)
		(size 0.508)
		(drill 0.254)
		(layers "F.Cu" "B.Cu")
		(net "GND")
	)
	(via
		(at 44.505626 -0.762508)
		(size 0.508)
		(drill 0.254)
		(layers "F.Cu" "B.Cu")
		(net "GND")
	)
	(via
		(at 42.758868 -479.374454)
		(size 0.508)
		(drill 0.254)
		(layers "F.Cu" "B.Cu")
		(net "GND")
	)
	(via
		(at 43.009566 -39.649908)
		(size 0.508)
		(drill 0.254)
		(layers "F.Cu" "B.Cu")
		(net "GND")
	)
	(via
		(at 3.414014 -125.974094)
		(size 0.508)
		(drill 0.254)
		(layers "F.Cu" "B.Cu")
		(net "GND")
	)
	(via
		(at 41.498774 -304.356262)
		(size 0.508)
		(drill 0.254)
		(layers "F.Cu" "B.Cu")
		(net "GND")
	)
	(via
		(at 46.23308 -214.559388)
		(size 0.508)
		(drill 0.254)
		(layers "F.Cu" "B.Cu")
		(net "GND")
	)
	(via
		(at 65.51041 -249.34418)
		(size 0.508)
		(drill 0.254)
		(layers "F.Cu" "B.Cu")
		(net "GND")
	)
	(via
		(at 45.514514 -212.548216)
		(size 0.508)
		(drill 0.254)
		(layers "F.Cu" "B.Cu")
		(net "GND")
	)
	(via
		(at 24.580596 -272.345404)
		(size 0.508)
		(drill 0.254)
		(layers "F.Cu" "B.Cu")
		(net "GND")
	)
	(via
		(at 65.553844 -243.756942)
		(size 0.508)
		(drill 0.254)
		(layers "F.Cu" "B.Cu")
		(net "GND")
	)
	(via
		(at 62.88786 -245.657878)
		(size 0.508)
		(drill 0.254)
		(layers "F.Cu" "B.Cu")
		(net "GND")
	)
	(via
		(at 45.47108 -214.559388)
		(size 0.508)
		(drill 0.254)
		(layers "F.Cu" "B.Cu")
		(net "GND")
	)
	(via
		(at 64.69634 -150.883366)
		(size 0.508)
		(drill 0.254)
		(layers "F.Cu" "B.Cu")
		(net "GND")
	)
	(via
		(at 42.291 -28.297378)
		(size 0.508)
		(drill 0.254)
		(layers "F.Cu" "B.Cu")
		(net "GND")
	)
	(via
		(at 42.131488 -208.97215)
		(size 0.508)
		(drill 0.254)
		(layers "F.Cu" "B.Cu")
		(net "GND")
	)
	(via
		(at 41.236392 -483.276148)
		(size 0.508)
		(drill 0.254)
		(layers "F.Cu" "B.Cu")
		(net "GND")
	)
	(via
		(at 56.37784 -433.796948)
		(size 0.508)
		(drill 0.254)
		(layers "F.Cu" "B.Cu")
		(net "GND")
	)
	(via
		(at 69.073522 -37.49802)
		(size 0.508)
		(drill 0.254)
		(layers "F.Cu" "B.Cu")
		(net "GND")
	)
	(via
		(at 59.743594 -435.706774)
		(size 0.508)
		(drill 0.254)
		(layers "F.Cu" "B.Cu")
		(net "GND")
	)
	(via
		(at 45.381418 -487.227118)
		(size 0.508)
		(drill 0.254)
		(layers "F.Cu" "B.Cu")
		(net "GND")
	)
	(via
		(at 2.832862 -416.16249)
		(size 0.508)
		(drill 0.254)
		(layers "F.Cu" "B.Cu")
		(net "GND")
	)
	(via
		(at 57.859168 -156.470604)
		(size 0.508)
		(drill 0.254)
		(layers "F.Cu" "B.Cu")
		(net "GND")
	)
	(via
		(at 56.421274 -422.444418)
		(size 0.508)
		(drill 0.254)
		(layers "F.Cu" "B.Cu")
		(net "GND")
	)
	(via
		(at 43.477434 -487.227118)
		(size 0.508)
		(drill 0.254)
		(layers "F.Cu" "B.Cu")
		(net "GND")
	)
	(via
		(at 93.006926 -347.413834)
		(size 0.508)
		(drill 0.254)
		(layers "F.Cu" "B.Cu")
		(net "GND")
	)
	(via
		(at 62.844426 -255.185672)
		(size 0.508)
		(drill 0.254)
		(layers "F.Cu" "B.Cu")
		(net "GND")
	)
	(via
		(at 45.424852 -479.374454)
		(size 0.508)
		(drill 0.254)
		(layers "F.Cu" "B.Cu")
		(net "GND")
	)
	(via
		(at 74.69886 -420.765732)
		(size 0.508)
		(drill 0.254)
		(layers "F.Cu" "B.Cu")
		(net "GND")
	)
	(via
		(at 45.220382 -68.278502)
		(size 0.508)
		(drill 0.254)
		(layers "F.Cu" "B.Cu")
		(net "GND")
	)
	(via
		(at 43.228006 -392.154664)
		(size 0.508)
		(drill 0.254)
		(layers "F.Cu" "B.Cu")
		(net "GND")
	)
	(via
		(at 25.035256 -181.847998)
		(size 0.508)
		(drill 0.254)
		(layers "F.Cu" "B.Cu")
		(net "GND")
	)
	(via
		(at 45.175424 -386.211826)
		(size 0.508)
		(drill 0.254)
		(layers "F.Cu" "B.Cu")
		(net "GND")
	)
	(via
		(at 102.238048 -118.645432)
		(size 0.508)
		(drill 0.254)
		(layers "F.Cu" "B.Cu")
		(net "GND")
	)
	(via
		(at 40.474392 -483.276148)
		(size 0.508)
		(drill 0.254)
		(layers "F.Cu" "B.Cu")
		(net "GND")
	)
	(via
		(at 60.036964 -73.65746)
		(size 0.508)
		(drill 0.254)
		(layers "F.Cu" "B.Cu")
		(net "GND")
	)
	(via
		(at 43.990006 -394.06449)
		(size 0.508)
		(drill 0.254)
		(layers "F.Cu" "B.Cu")
		(net "GND")
	)
	(via
		(at 61.647578 -429.865282)
		(size 0.508)
		(drill 0.254)
		(layers "F.Cu" "B.Cu")
		(net "GND")
	)
	(via
		(at 72.157844 -421.610282)
		(size 0.508)
		(drill 0.254)
		(layers "F.Cu" "B.Cu")
		(net "GND")
	)
	(via
		(at 42.715434 -483.276148)
		(size 0.508)
		(drill 0.254)
		(layers "F.Cu" "B.Cu")
		(net "GND")
	)
	(via
		(at 44.414948 -75.756262)
		(size 0.508)
		(drill 0.254)
		(layers "F.Cu" "B.Cu")
		(net "GND")
	)
	(via
		(at 0.765048 -408.98191)
		(size 0.508)
		(drill 0.254)
		(layers "F.Cu" "B.Cu")
		(net "GND")
	)
	(via
		(at 39.862252 -394.06449)
		(size 0.508)
		(drill 0.254)
		(layers "F.Cu" "B.Cu")
		(net "GND")
	)
	(via
		(at 46.896528 -249.789442)
		(size 0.508)
		(drill 0.254)
		(layers "F.Cu" "B.Cu")
		(net "GND")
	)
	(via
		(at 0.762254 -457.208636)
		(size 0.508)
		(drill 0.254)
		(layers "F.Cu" "B.Cu")
		(net "GND")
	)
	(via
		(at 61.940948 -69.70649)
		(size 0.508)
		(drill 0.254)
		(layers "F.Cu" "B.Cu")
		(net "GND")
	)
	(via
		(at 61.365384 -255.185672)
		(size 0.508)
		(drill 0.254)
		(layers "F.Cu" "B.Cu")
		(net "GND")
	)
	(via
		(at 71.405496 -258.105148)
		(size 0.508)
		(drill 0.254)
		(layers "F.Cu" "B.Cu")
		(net "GND")
	)
	(via
		(at 39.100252 -390.11352)
		(size 0.508)
		(drill 0.254)
		(layers "F.Cu" "B.Cu")
		(net "GND")
	)
	(via
		(at 38.58768 -487.227118)
		(size 0.508)
		(drill 0.254)
		(layers "F.Cu" "B.Cu")
		(net "GND")
	)
	(via
		(at 59.522106 -241.923316)
		(size 0.508)
		(drill 0.254)
		(layers "F.Cu" "B.Cu")
		(net "GND")
	)
	(via
		(at 44.03344 -382.63576)
		(size 0.508)
		(drill 0.254)
		(layers "F.Cu" "B.Cu")
		(net "GND")
	)
	(via
		(at 102.238048 -385.345432)
		(size 0.508)
		(drill 0.254)
		(layers "F.Cu" "B.Cu")
		(net "GND")
	)
	(via
		(at 78.397354 -20.009612)
		(size 0.508)
		(drill 0.254)
		(layers "F.Cu" "B.Cu")
		(net "GND")
	)
	(via
		(at 62.030356 -150.883366)
		(size 0.508)
		(drill 0.254)
		(layers "F.Cu" "B.Cu")
		(net "GND")
	)
	(via
		(at 41.057576 -194.114674)
		(size 0.508)
		(drill 0.254)
		(layers "F.Cu" "B.Cu")
		(net "GND")
	)
	(via
		(at 58.716672 -251.234702)
		(size 0.508)
		(drill 0.254)
		(layers "F.Cu" "B.Cu")
		(net "GND")
	)
	(via
		(at 24.624792 -277.377144)
		(size 0.508)
		(drill 0.254)
		(layers "F.Cu" "B.Cu")
		(net "GND")
	)
	(via
		(at 57.859168 -158.361126)
		(size 0.508)
		(drill 0.254)
		(layers "F.Cu" "B.Cu")
		(net "GND")
	)
	(via
		(at 40.49522 -121.009918)
		(size 0.508)
		(drill 0.254)
		(layers "F.Cu" "B.Cu")
		(net "GND")
	)
	(via
		(at 102.238048 -296.445432)
		(size 0.508)
		(drill 0.254)
		(layers "F.Cu" "B.Cu")
		(net "GND")
	)
	(via
		(at 42.291 -33.70707)
		(size 0.508)
		(drill 0.254)
		(layers "F.Cu" "B.Cu")
		(net "GND")
	)
	(via
		(at 43.228006 -394.06449)
		(size 0.508)
		(drill 0.254)
		(layers "F.Cu" "B.Cu")
		(net "GND")
	)
	(via
		(at 68.246244 -215.261952)
		(size 0.508)
		(drill 0.254)
		(layers "F.Cu" "B.Cu")
		(net "GND")
	)
	(via
		(at 40.201342 -220.40088)
		(size 0.508)
		(drill 0.254)
		(layers "F.Cu" "B.Cu")
		(net "GND")
	)
	(via
		(at 44.37253 -212.548216)
		(size 0.508)
		(drill 0.254)
		(layers "F.Cu" "B.Cu")
		(net "GND")
	)
	(via
		(at 40.780208 -298.769024)
		(size 0.508)
		(drill 0.254)
		(layers "F.Cu" "B.Cu")
		(net "GND")
	)
	(via
		(at 0.762254 -215.908636)
		(size 0.508)
		(drill 0.254)
		(layers "F.Cu" "B.Cu")
		(net "GND")
	)
	(via
		(at 62.409578 -431.755804)
		(size 0.508)
		(drill 0.254)
		(layers "F.Cu" "B.Cu")
		(net "GND")
	)
	(via
		(at 2.931414 -396.83182)
		(size 0.508)
		(drill 0.254)
		(layers "F.Cu" "B.Cu")
		(net "GND")
	)
	(via
		(at 40.244776 -210.873086)
		(size 0.508)
		(drill 0.254)
		(layers "F.Cu" "B.Cu")
		(net "GND")
	)
	(via
		(at 39.34968 -485.317292)
		(size 0.508)
		(drill 0.254)
		(layers "F.Cu" "B.Cu")
		(net "GND")
	)
	(via
		(at 41.296844 -17.30502)
		(size 0.508)
		(drill 0.254)
		(layers "F.Cu" "B.Cu")
		(net "GND")
	)
	(via
		(at 45.47108 -220.40088)
		(size 0.508)
		(drill 0.254)
		(layers "F.Cu" "B.Cu")
		(net "GND")
	)
	(via
		(at 6.405626 -4.763008)
		(size 0.508)
		(drill 0.254)
		(layers "F.Cu" "B.Cu")
		(net "GND")
	)
	(via
		(at 58.261758 -126.426468)
		(size 0.508)
		(drill 0.254)
		(layers "F.Cu" "B.Cu")
		(net "GND")
	)
	(via
		(at 89.253314 -343.079324)
		(size 0.508)
		(drill 0.254)
		(layers "F.Cu" "B.Cu")
		(net "GND")
	)
	(via
		(at 40.986964 -388.222998)
		(size 0.508)
		(drill 0.254)
		(layers "F.Cu" "B.Cu")
		(net "GND")
	)
	(via
		(at 59.274964 -71.747634)
		(size 0.508)
		(drill 0.254)
		(layers "F.Cu" "B.Cu")
		(net "GND")
	)
	(via
		(at 74.832718 -258.105148)
		(size 0.508)
		(drill 0.254)
		(layers "F.Cu" "B.Cu")
		(net "GND")
	)
	(via
		(at 44.329096 -218.491054)
		(size 0.508)
		(drill 0.254)
		(layers "F.Cu" "B.Cu")
		(net "GND")
	)
	(via
		(at 73.512934 -420.765732)
		(size 0.508)
		(drill 0.254)
		(layers "F.Cu" "B.Cu")
		(net "GND")
	)
	(via
		(at 76.120498 -20.009612)
		(size 0.508)
		(drill 0.254)
		(layers "F.Cu" "B.Cu")
		(net "GND")
	)
	(via
		(at 45.381418 -481.385626)
		(size 0.508)
		(drill 0.254)
		(layers "F.Cu" "B.Cu")
		(net "GND")
	)
	(via
		(at 67.977258 -29.351986)
		(size 0.508)
		(drill 0.254)
		(layers "F.Cu" "B.Cu")
		(net "GND")
	)
	(via
		(at 59.318398 -64.129666)
		(size 0.508)
		(drill 0.254)
		(layers "F.Cu" "B.Cu")
		(net "GND")
	)
	(via
		(at 63.168784 -128.467612)
		(size 0.508)
		(drill 0.254)
		(layers "F.Cu" "B.Cu")
		(net "GND")
	)
	(via
		(at 102.238048 -410.745432)
		(size 0.508)
		(drill 0.254)
		(layers "F.Cu" "B.Cu")
		(net "GND")
	)
	(via
		(at 60.646818 -241.923316)
		(size 0.508)
		(drill 0.254)
		(layers "F.Cu" "B.Cu")
		(net "GND")
	)
	(via
		(at 63.212218 -118.948708)
		(size 0.508)
		(drill 0.254)
		(layers "F.Cu" "B.Cu")
		(net "GND")
	)
	(via
		(at 72.19696 -349.134176)
		(size 0.508)
		(drill 0.254)
		(layers "F.Cu" "B.Cu")
		(net "GND")
	)
	(via
		(at 40.201342 -218.491054)
		(size 0.508)
		(drill 0.254)
		(layers "F.Cu" "B.Cu")
		(net "GND")
	)
	(via
		(at 69.549518 -482.175058)
		(size 0.508)
		(drill 0.254)
		(layers "F.Cu" "B.Cu")
		(net "GND")
	)
	(via
		(at 93.006926 -349.55734)
		(size 0.508)
		(drill 0.254)
		(layers "F.Cu" "B.Cu")
		(net "GND")
	)
	(via
		(at 43.567096 -216.44991)
		(size 0.508)
		(drill 0.254)
		(layers "F.Cu" "B.Cu")
		(net "GND")
	)
	(via
		(at 39.482776 -212.548216)
		(size 0.508)
		(drill 0.254)
		(layers "F.Cu" "B.Cu")
		(net "GND")
	)
	(via
		(at 44.896278 -39.649908)
		(size 0.508)
		(drill 0.254)
		(layers "F.Cu" "B.Cu")
		(net "GND")
	)
	(via
		(at 60.551314 -154.459432)
		(size 0.508)
		(drill 0.254)
		(layers "F.Cu" "B.Cu")
		(net "GND")
	)
	(via
		(at 63.212218 -120.849644)
		(size 0.508)
		(drill 0.254)
		(layers "F.Cu" "B.Cu")
		(net "GND")
	)
	(via
		(at 57.795922 -67.815968)
		(size 0.508)
		(drill 0.254)
		(layers "F.Cu" "B.Cu")
		(net "GND")
	)
	(via
		(at 61.986922 -156.470604)
		(size 0.508)
		(drill 0.254)
		(layers "F.Cu" "B.Cu")
		(net "GND")
	)
	(via
		(at 40.474392 -481.385626)
		(size 0.508)
		(drill 0.254)
		(layers "F.Cu" "B.Cu")
		(net "GND")
	)
	(via
		(at 45.13199 -390.11352)
		(size 0.508)
		(drill 0.254)
		(layers "F.Cu" "B.Cu")
		(net "GND")
	)
	(via
		(at 58.760106 -245.657878)
		(size 0.508)
		(drill 0.254)
		(layers "F.Cu" "B.Cu")
		(net "GND")
	)
	(via
		(at 41.236392 -485.317292)
		(size 0.508)
		(drill 0.254)
		(layers "F.Cu" "B.Cu")
		(net "GND")
	)
	(via
		(at 61.647578 -431.755804)
		(size 0.508)
		(drill 0.254)
		(layers "F.Cu" "B.Cu")
		(net "GND")
	)
	(via
		(at 75.10145 -391.975594)
		(size 0.508)
		(drill 0.254)
		(layers "F.Cu" "B.Cu")
		(net "GND")
	)
	(via
		(at 39.439342 -216.44991)
		(size 0.508)
		(drill 0.254)
		(layers "F.Cu" "B.Cu")
		(net "GND")
	)
	(via
		(at 65.51041 -253.275846)
		(size 0.508)
		(drill 0.254)
		(layers "F.Cu" "B.Cu")
		(net "GND")
	)
	(via
		(at 53.337714 -529.236178)
		(size 0.508)
		(drill 0.254)
		(layers "F.Cu" "B.Cu")
		(net "GND")
	)
	(via
		(at 43.27144 -382.63576)
		(size 0.508)
		(drill 0.254)
		(layers "F.Cu" "B.Cu")
		(net "GND")
	)
	(via
		(at 6.815582 -525.237964)
		(size 0.508)
		(drill 0.254)
		(layers "F.Cu" "B.Cu")
		(net "GND")
	)
	(via
		(at 70.678548 -482.175058)
		(size 0.508)
		(drill 0.254)
		(layers "F.Cu" "B.Cu")
		(net "GND")
	)
	(via
		(at 44.896278 -35.718242)
		(size 0.508)
		(drill 0.254)
		(layers "F.Cu" "B.Cu")
		(net "GND")
	)
	(via
		(at 61.940948 -67.815968)
		(size 0.508)
		(drill 0.254)
		(layers "F.Cu" "B.Cu")
		(net "GND")
	)
	(via
		(at 64.74841 -249.34418)
		(size 0.508)
		(drill 0.254)
		(layers "F.Cu" "B.Cu")
		(net "GND")
	)
	(via
		(at 59.023758 -130.377438)
		(size 0.508)
		(drill 0.254)
		(layers "F.Cu" "B.Cu")
		(net "GND")
	)
	(via
		(at 44.177712 -33.70707)
		(size 0.508)
		(drill 0.254)
		(layers "F.Cu" "B.Cu")
		(net "GND")
	)
	(via
		(at 90.015314 -340.411054)
		(size 0.508)
		(drill 0.254)
		(layers "F.Cu" "B.Cu")
		(net "GND")
	)
	(via
		(at 42.088054 -218.491054)
		(size 0.508)
		(drill 0.254)
		(layers "F.Cu" "B.Cu")
		(net "GND")
	)
	(via
		(at 60.603384 -251.234702)
		(size 0.508)
		(drill 0.254)
		(layers "F.Cu" "B.Cu")
		(net "GND")
	)
	(via
		(at 56.421274 -424.278044)
		(size 0.508)
		(drill 0.254)
		(layers "F.Cu" "B.Cu")
		(net "GND")
	)
	(via
		(at 62.098428 -304.734214)
		(size 0.508)
		(drill 0.254)
		(layers "F.Cu" "B.Cu")
		(net "GND")
	)
	(via
		(at 41.326054 -218.491054)
		(size 0.508)
		(drill 0.254)
		(layers "F.Cu" "B.Cu")
		(net "GND")
	)
	(via
		(at 62.860428 -308.685184)
		(size 0.508)
		(drill 0.254)
		(layers "F.Cu" "B.Cu")
		(net "GND")
	)
	(via
		(at 57.077356 -65.804796)
		(size 0.508)
		(drill 0.254)
		(layers "F.Cu" "B.Cu")
		(net "GND")
	)
	(via
		(at 47.84979 -259.28574)
		(size 0.508)
		(drill 0.254)
		(layers "F.Cu" "B.Cu")
		(net "GND")
	)
	(via
		(at 25.163272 -447.250058)
		(size 0.508)
		(drill 0.254)
		(layers "F.Cu" "B.Cu")
		(net "GND")
	)
	(via
		(at 61.222382 -64.129666)
		(size 0.508)
		(drill 0.254)
		(layers "F.Cu" "B.Cu")
		(net "GND")
	)
	(via
		(at 44.177712 -28.297378)
		(size 0.508)
		(drill 0.254)
		(layers "F.Cu" "B.Cu")
		(net "GND")
	)
	(via
		(at 59.789314 -150.883366)
		(size 0.508)
		(drill 0.254)
		(layers "F.Cu" "B.Cu")
		(net "GND")
	)
	(via
		(at 58.307986 -426.17898)
		(size 0.508)
		(drill 0.254)
		(layers "F.Cu" "B.Cu")
		(net "GND")
	)
	(via
		(at 44.939712 -33.70707)
		(size 0.508)
		(drill 0.254)
		(layers "F.Cu" "B.Cu")
		(net "GND")
	)
	(via
		(at 44.134278 -37.608764)
		(size 0.508)
		(drill 0.254)
		(layers "F.Cu" "B.Cu")
		(net "GND")
	)
	(via
		(at 61.940948 -71.747634)
		(size 0.508)
		(drill 0.254)
		(layers "F.Cu" "B.Cu")
		(net "GND")
	)
	(via
		(at 60.397136 -25.906476)
		(size 0.508)
		(drill 0.254)
		(layers "F.Cu" "B.Cu")
		(net "GND")
	)
	(via
		(at 102.238048 -29.745432)
		(size 0.508)
		(drill 0.254)
		(layers "F.Cu" "B.Cu")
		(net "GND")
	)
	(via
		(at 39.862252 -392.154664)
		(size 0.508)
		(drill 0.254)
		(layers "F.Cu" "B.Cu")
		(net "GND")
	)
	(via
		(at 43.053 -33.70707)
		(size 0.508)
		(drill 0.254)
		(layers "F.Cu" "B.Cu")
		(net "GND")
	)
	(via
		(at 41.4655 -461.170274)
		(size 0.508)
		(drill 0.254)
		(layers "F.Cu" "B.Cu")
		(net "GND")
	)
	(via
		(at 40.780208 -296.935398)
		(size 0.508)
		(drill 0.254)
		(layers "F.Cu" "B.Cu")
		(net "GND")
	)
	(via
		(at 57.502552 -433.796948)
		(size 0.508)
		(drill 0.254)
		(layers "F.Cu" "B.Cu")
		(net "GND")
	)
	(via
		(at 43.520868 -479.374454)
		(size 0.508)
		(drill 0.254)
		(layers "F.Cu" "B.Cu")
		(net "GND")
	)
	(via
		(at 43.567096 -214.559388)
		(size 0.508)
		(drill 0.254)
		(layers "F.Cu" "B.Cu")
		(net "GND")
	)
	(via
		(at 63.64986 -247.333008)
		(size 0.508)
		(drill 0.254)
		(layers "F.Cu" "B.Cu")
		(net "GND")
	)
	(via
		(at 61.940948 -73.65746)
		(size 0.508)
		(drill 0.254)
		(layers "F.Cu" "B.Cu")
		(net "GND")
	)
	(via
		(at 102.238048 -182.145432)
		(size 0.508)
		(drill 0.254)
		(layers "F.Cu" "B.Cu")
		(net "GND")
	)
	(via
		(at 60.5028 -124.535946)
		(size 0.508)
		(drill 0.254)
		(layers "F.Cu" "B.Cu")
		(net "GND")
	)
	(via
		(at 0.762254 -101.608636)
		(size 0.508)
		(drill 0.254)
		(layers "F.Cu" "B.Cu")
		(net "GND")
	)
	(via
		(at 43.053 -32.03194)
		(size 0.508)
		(drill 0.254)
		(layers "F.Cu" "B.Cu")
		(net "GND")
	)
	(via
		(at 44.414948 -79.707232)
		(size 0.508)
		(drill 0.254)
		(layers "F.Cu" "B.Cu")
		(net "GND")
	)
	(via
		(at 40.474392 -487.227118)
		(size 0.508)
		(drill 0.254)
		(layers "F.Cu" "B.Cu")
		(net "GND")
	)
	(via
		(at 61.308234 -120.849644)
		(size 0.508)
		(drill 0.254)
		(layers "F.Cu" "B.Cu")
		(net "GND")
	)
	(via
		(at 90.015314 -349.55734)
		(size 0.508)
		(drill 0.254)
		(layers "F.Cu" "B.Cu")
		(net "GND")
	)
	(via
		(at 25.715976 -196.6214)
		(size 0.508)
		(drill 0.254)
		(layers "F.Cu" "B.Cu")
		(net "GND")
	)
	(via
		(at 41.279826 -477.699324)
		(size 0.508)
		(drill 0.254)
		(layers "F.Cu" "B.Cu")
		(net "GND")
	)
	(via
		(at 60.036964 -69.70649)
		(size 0.508)
		(drill 0.254)
		(layers "F.Cu" "B.Cu")
		(net "GND")
	)
	(via
		(at 44.414948 -77.797406)
		(size 0.508)
		(drill 0.254)
		(layers "F.Cu" "B.Cu")
		(net "GND")
	)
	(via
		(at 40.517826 -473.964762)
		(size 0.508)
		(drill 0.254)
		(layers "F.Cu" "B.Cu")
		(net "GND")
	)
	(via
		(at 19.515582 -525.237964)
		(size 0.508)
		(drill 0.254)
		(layers "F.Cu" "B.Cu")
		(net "GND")
	)
	(via
		(at 45.381418 -485.317292)
		(size 0.508)
		(drill 0.254)
		(layers "F.Cu" "B.Cu")
		(net "GND")
	)
	(via
		(at 61.691012 -424.278044)
		(size 0.508)
		(drill 0.254)
		(layers "F.Cu" "B.Cu")
		(net "GND")
	)
	(via
		(at 41.279826 -473.964762)
		(size 0.508)
		(drill 0.254)
		(layers "F.Cu" "B.Cu")
		(net "GND")
	)
	(via
		(at 44.662852 -477.699324)
		(size 0.508)
		(drill 0.254)
		(layers "F.Cu" "B.Cu")
		(net "GND")
	)
	(via
		(at 14.33195 -451.706234)
		(size 0.508)
		(drill 0.254)
		(layers "F.Cu" "B.Cu")
		(net "GND")
	)
	(via
		(at 92.244926 -337.740244)
		(size 0.508)
		(drill 0.254)
		(layers "F.Cu" "B.Cu")
		(net "GND")
	)
	(via
		(at 102.238048 -512.345432)
		(size 0.508)
		(drill 0.254)
		(layers "F.Cu" "B.Cu")
		(net "GND")
	)
	(via
		(at 22.564598 -449.860162)
		(size 0.508)
		(drill 0.254)
		(layers "F.Cu" "B.Cu")
		(net "GND")
	)
	(via
		(at 80.662018 -20.009612)
		(size 0.508)
		(drill 0.254)
		(layers "F.Cu" "B.Cu")
		(net "GND")
	)
	(via
		(at 67.927982 -158.577534)
		(size 0.508)
		(drill 0.254)
		(layers "F.Cu" "B.Cu")
		(net "GND")
	)
	(via
		(at 45.89399 -392.154664)
		(size 0.508)
		(drill 0.254)
		(layers "F.Cu" "B.Cu")
		(net "GND")
	)
	(via
		(at 44.458382 -66.444876)
		(size 0.508)
		(drill 0.254)
		(layers "F.Cu" "B.Cu")
		(net "GND")
	)
	(via
		(at 72.928734 -482.175058)
		(size 0.508)
		(drill 0.254)
		(layers "F.Cu" "B.Cu")
		(net "GND")
	)
	(via
		(at 63.606426 -249.34418)
		(size 0.508)
		(drill 0.254)
		(layers "F.Cu" "B.Cu")
		(net "GND")
	)
	(via
		(at 0.762254 -342.908636)
		(size 0.508)
		(drill 0.254)
		(layers "F.Cu" "B.Cu")
		(net "GND")
	)
	(via
		(at 60.5028 -130.377438)
		(size 0.508)
		(drill 0.254)
		(layers "F.Cu" "B.Cu")
		(net "GND")
	)
	(via
		(at 0.762254 -368.308636)
		(size 0.508)
		(drill 0.254)
		(layers "F.Cu" "B.Cu")
		(net "GND")
	)
	(via
		(at 24.75611 -367.771426)
		(size 0.508)
		(drill 0.254)
		(layers "F.Cu" "B.Cu")
		(net "GND")
	)
	(via
		(at 44.414948 -73.86574)
		(size 0.508)
		(drill 0.254)
		(layers "F.Cu" "B.Cu")
		(net "GND")
	)
	(via
		(at 45.89399 -388.222998)
		(size 0.508)
		(drill 0.254)
		(layers "F.Cu" "B.Cu")
		(net "GND")
	)
	(via
		(at 24.636222 -366.710722)
		(size 0.508)
		(drill 0.254)
		(layers "F.Cu" "B.Cu")
		(net "GND")
	)
	(via
		(at 59.74588 -162.312096)
		(size 0.508)
		(drill 0.254)
		(layers "F.Cu" "B.Cu")
		(net "GND")
	)
	(via
		(at 24.88819 -99.36988)
		(size 0.508)
		(drill 0.254)
		(layers "F.Cu" "B.Cu")
		(net "GND")
	)
	(via
		(at 68.310252 -126.324614)
		(size 0.508)
		(drill 0.254)
		(layers "F.Cu" "B.Cu")
		(net "GND")
	)
	(via
		(at 40.517826 -477.699324)
		(size 0.508)
		(drill 0.254)
		(layers "F.Cu" "B.Cu")
		(net "GND")
	)
	(via
		(at 0.763524 -405.028908)
		(size 0.508)
		(drill 0.254)
		(layers "F.Cu" "B.Cu")
		(net "GND")
	)
	(via
		(at 59.023758 -124.535946)
		(size 0.508)
		(drill 0.254)
		(layers "F.Cu" "B.Cu")
		(net "GND")
	)
	(via
		(at 93.006926 -340.411054)
		(size 0.508)
		(drill 0.254)
		(layers "F.Cu" "B.Cu")
		(net "GND")
	)
	(via
		(at 40.736774 -304.356262)
		(size 0.508)
		(drill 0.254)
		(layers "F.Cu" "B.Cu")
		(net "GND")
	)
	(via
		(at 73.532746 -437.82869)
		(size 0.508)
		(drill 0.254)
		(layers "F.Cu" "B.Cu")
		(net "GND")
	)
	(via
		(at 63.64986 -245.657878)
		(size 0.508)
		(drill 0.254)
		(layers "F.Cu" "B.Cu")
		(net "GND")
	)
	(via
		(at 70.558152 -215.198198)
		(size 0.508)
		(drill 0.254)
		(layers "F.Cu" "B.Cu")
		(net "GND")
	)
	(via
		(at 64.652906 -162.312096)
		(size 0.508)
		(drill 0.254)
		(layers "F.Cu" "B.Cu")
		(net "GND")
	)
	(via
		(at 63.212218 -122.524774)
		(size 0.508)
		(drill 0.254)
		(layers "F.Cu" "B.Cu")
		(net "GND")
	)
	(via
		(at 44.619418 -481.385626)
		(size 0.508)
		(drill 0.254)
		(layers "F.Cu" "B.Cu")
		(net "GND")
	)
	(via
		(at 44.662852 -475.798388)
		(size 0.508)
		(drill 0.254)
		(layers "F.Cu" "B.Cu")
		(net "GND")
	)
	(via
		(at 60.505594 -429.865282)
		(size 0.508)
		(drill 0.254)
		(layers "F.Cu" "B.Cu")
		(net "GND")
	)
	(via
		(at 63.890906 -160.40227)
		(size 0.508)
		(drill 0.254)
		(layers "F.Cu" "B.Cu")
		(net "GND")
	)
	(via
		(at 73.927716 -391.975594)
		(size 0.508)
		(drill 0.254)
		(layers "F.Cu" "B.Cu")
		(net "GND")
	)
	(via
		(at 95.305626 -0.762508)
		(size 0.508)
		(drill 0.254)
		(layers "F.Cu" "B.Cu")
		(net "GND")
	)
	(via
		(at 57.545986 -426.17898)
		(size 0.508)
		(drill 0.254)
		(layers "F.Cu" "B.Cu")
		(net "GND")
	)
	(via
		(at 102.238048 -499.645432)
		(size 0.508)
		(drill 0.254)
		(layers "F.Cu" "B.Cu")
		(net "GND")
	)
	(via
		(at 42.715434 -485.317292)
		(size 0.508)
		(drill 0.254)
		(layers "F.Cu" "B.Cu")
		(net "GND")
	)
	(via
		(at 61.222382 -65.804796)
		(size 0.508)
		(drill 0.254)
		(layers "F.Cu" "B.Cu")
		(net "GND")
	)
	(via
		(at 60.080398 -62.22873)
		(size 0.508)
		(drill 0.254)
		(layers "F.Cu" "B.Cu")
		(net "GND")
	)
	(via
		(at 58.305192 -120.849644)
		(size 0.508)
		(drill 0.254)
		(layers "F.Cu" "B.Cu")
		(net "GND")
	)
	(via
		(at 102.238048 -207.545432)
		(size 0.508)
		(drill 0.254)
		(layers "F.Cu" "B.Cu")
		(net "GND")
	)
	(via
		(at 39.73322 -122.685048)
		(size 0.508)
		(drill 0.254)
		(layers "F.Cu" "B.Cu")
		(net "GND")
	)
	(via
		(at 57.502552 -435.706774)
		(size 0.508)
		(drill 0.254)
		(layers "F.Cu" "B.Cu")
		(net "GND")
	)
	(via
		(at 60.397136 -21.955506)
		(size 0.508)
		(drill 0.254)
		(layers "F.Cu" "B.Cu")
		(net "GND")
	)
	(via
		(at 57.795922 -73.65746)
		(size 0.508)
		(drill 0.254)
		(layers "F.Cu" "B.Cu")
		(net "GND")
	)
	(via
		(at 93.006926 -343.079324)
		(size 0.508)
		(drill 0.254)
		(layers "F.Cu" "B.Cu")
		(net "GND")
	)
	(via
		(at 25.042114 -183.06923)
		(size 0.508)
		(drill 0.254)
		(layers "F.Cu" "B.Cu")
		(net "GND")
	)
	(via
		(at 43.78325 -298.769024)
		(size 0.508)
		(drill 0.254)
		(layers "F.Cu" "B.Cu")
		(net "GND")
	)
	(via
		(at 68.972938 -66.129662)
		(size 0.508)
		(drill 0.254)
		(layers "F.Cu" "B.Cu")
		(net "GND")
	)
	(via
		(at 59.318398 -62.22873)
		(size 0.508)
		(drill 0.254)
		(layers "F.Cu" "B.Cu")
		(net "GND")
	)
	(via
		(at 56.421274 -426.17898)
		(size 0.508)
		(drill 0.254)
		(layers "F.Cu" "B.Cu")
		(net "GND")
	)
	(via
		(at 92.244926 -340.411054)
		(size 0.508)
		(drill 0.254)
		(layers "F.Cu" "B.Cu")
		(net "GND")
	)
	(via
		(at 71.810118 -482.175058)
		(size 0.508)
		(drill 0.254)
		(layers "F.Cu" "B.Cu")
		(net "GND")
	)
	(via
		(at 68.607686 -170.736768)
		(size 0.508)
		(drill 0.254)
		(layers "F.Cu" "B.Cu")
		(net "GND")
	)
	(via
		(at 102.238048 -271.045432)
		(size 0.508)
		(drill 0.254)
		(layers "F.Cu" "B.Cu")
		(net "GND")
	)
	(via
		(at 70.997572 -349.133922)
		(size 0.508)
		(drill 0.254)
		(layers "F.Cu" "B.Cu")
		(net "GND")
	)
	(via
		(at 17.162272 -329.350116)
		(size 0.508)
		(drill 0.254)
		(layers "F.Cu" "B.Cu")
		(net "GND")
	)
	(via
		(at 27.452828 -9.880346)
		(size 0.508)
		(drill 0.254)
		(layers "F.Cu" "B.Cu")
		(net "GND")
	)
	(via
		(at 61.365384 -249.34418)
		(size 0.508)
		(drill 0.254)
		(layers "F.Cu" "B.Cu")
		(net "GND")
	)
	(via
		(at 43.78325 -300.66996)
		(size 0.508)
		(drill 0.254)
		(layers "F.Cu" "B.Cu")
		(net "GND")
	)
	(via
		(at 72.81291 -109.942376)
		(size 0.508)
		(drill 0.254)
		(layers "F.Cu" "B.Cu")
		(net "GND")
	)
	(via
		(at 61.984382 -64.129666)
		(size 0.508)
		(drill 0.254)
		(layers "F.Cu" "B.Cu")
		(net "GND")
	)
	(via
		(at 62.030356 -154.459432)
		(size 0.508)
		(drill 0.254)
		(layers "F.Cu" "B.Cu")
		(net "GND")
	)
	(via
		(at 39.73322 -121.009918)
		(size 0.508)
		(drill 0.254)
		(layers "F.Cu" "B.Cu")
		(net "GND")
	)
	(via
		(at 60.646818 -245.657878)
		(size 0.508)
		(drill 0.254)
		(layers "F.Cu" "B.Cu")
		(net "GND")
	)
	(via
		(at 69.44487 -126.324614)
		(size 0.508)
		(drill 0.254)
		(layers "F.Cu" "B.Cu")
		(net "GND")
	)
	(via
		(at 26.072084 -12.563094)
		(size 0.508)
		(drill 0.254)
		(layers "F.Cu" "B.Cu")
		(net "GND")
	)
	(via
		(at 44.896278 -41.559734)
		(size 0.508)
		(drill 0.254)
		(layers "F.Cu" "B.Cu")
		(net "GND")
	)
	(via
		(at 71.96836 -170.736768)
		(size 0.508)
		(drill 0.254)
		(layers "F.Cu" "B.Cu")
		(net "GND")
	)
	(via
		(at 62.792356 -154.459432)
		(size 0.508)
		(drill 0.254)
		(layers "F.Cu" "B.Cu")
		(net "GND")
	)
	(via
		(at 45.175424 -384.536696)
		(size 0.508)
		(drill 0.254)
		(layers "F.Cu" "B.Cu")
		(net "GND")
	)
	(via
		(at 39.905686 -384.536696)
		(size 0.508)
		(drill 0.254)
		(layers "F.Cu" "B.Cu")
		(net "GND")
	)
	(via
		(at 45.13199 -392.154664)
		(size 0.508)
		(drill 0.254)
		(layers "F.Cu" "B.Cu")
		(net "GND")
	)
	(via
		(at 71.11746 -375.77649)
		(size 0.508)
		(drill 0.254)
		(layers "F.Cu" "B.Cu")
		(net "GND")
	)
	(via
		(at 57.839356 -65.804796)
		(size 0.508)
		(drill 0.254)
		(layers "F.Cu" "B.Cu")
		(net "GND")
	)
	(via
		(at 40.780208 -302.34509)
		(size 0.508)
		(drill 0.254)
		(layers "F.Cu" "B.Cu")
		(net "GND")
	)
	(via
		(at 42.758868 -475.798388)
		(size 0.508)
		(drill 0.254)
		(layers "F.Cu" "B.Cu")
		(net "GND")
	)
	(via
		(at 64.791844 -247.333008)
		(size 0.508)
		(drill 0.254)
		(layers "F.Cu" "B.Cu")
		(net "GND")
	)
	(via
		(at 43.477434 -483.276148)
		(size 0.508)
		(drill 0.254)
		(layers "F.Cu" "B.Cu")
		(net "GND")
	)
	(via
		(at 63.93434 -154.459432)
		(size 0.508)
		(drill 0.254)
		(layers "F.Cu" "B.Cu")
		(net "GND")
	)
	(via
		(at 72.635364 -243.780818)
		(size 0.508)
		(drill 0.254)
		(layers "F.Cu" "B.Cu")
		(net "GND")
	)
	(via
		(at 45.176948 -77.797406)
		(size 0.508)
		(drill 0.254)
		(layers "F.Cu" "B.Cu")
		(net "GND")
	)
	(via
		(at 0.762254 -292.108636)
		(size 0.508)
		(drill 0.254)
		(layers "F.Cu" "B.Cu")
		(net "GND")
	)
	(via
		(at 43.009566 -35.718242)
		(size 0.508)
		(drill 0.254)
		(layers "F.Cu" "B.Cu")
		(net "GND")
	)
	(via
		(at 38.631114 -479.374454)
		(size 0.508)
		(drill 0.254)
		(layers "F.Cu" "B.Cu")
		(net "GND")
	)
	(via
		(at 38.631114 -475.798388)
		(size 0.508)
		(drill 0.254)
		(layers "F.Cu" "B.Cu")
		(net "GND")
	)
	(via
		(at 39.439342 -218.491054)
		(size 0.508)
		(drill 0.254)
		(layers "F.Cu" "B.Cu")
		(net "GND")
	)
	(via
		(at 41.748964 -394.06449)
		(size 0.508)
		(drill 0.254)
		(layers "F.Cu" "B.Cu")
		(net "GND")
	)
	(via
		(at 63.606426 -251.234702)
		(size 0.508)
		(drill 0.254)
		(layers "F.Cu" "B.Cu")
		(net "GND")
	)
	(via
		(at 25.057608 -278.486362)
		(size 0.508)
		(drill 0.254)
		(layers "F.Cu" "B.Cu")
		(net "GND")
	)
	(via
		(at 0.762254 -419.108636)
		(size 0.508)
		(drill 0.254)
		(layers "F.Cu" "B.Cu")
		(net "GND")
	)
	(via
		(at 73.63333 -81.962752)
		(size 0.508)
		(drill 0.254)
		(layers "F.Cu" "B.Cu")
		(net "GND")
	)
	(via
		(at 45.514514 -210.873086)
		(size 0.508)
		(drill 0.254)
		(layers "F.Cu" "B.Cu")
		(net "GND")
	)
	(via
		(at 63.606426 -255.185672)
		(size 0.508)
		(drill 0.254)
		(layers "F.Cu" "B.Cu")
		(net "GND")
	)
	(via
		(at 39.143686 -386.211826)
		(size 0.508)
		(drill 0.254)
		(layers "F.Cu" "B.Cu")
		(net "GND")
	)
	(via
		(at 60.546234 -118.948708)
		(size 0.508)
		(drill 0.254)
		(layers "F.Cu" "B.Cu")
		(net "GND")
	)
	(via
		(at 24.743918 -8.344662)
		(size 0.508)
		(drill 0.254)
		(layers "F.Cu" "B.Cu")
		(net "GND")
	)
	(via
		(at 55.61584 -429.865282)
		(size 0.508)
		(drill 0.254)
		(layers "F.Cu" "B.Cu")
		(net "GND")
	)
	(via
		(at 39.905686 -386.211826)
		(size 0.508)
		(drill 0.254)
		(layers "F.Cu" "B.Cu")
		(net "GND")
	)
	(via
		(at 39.655496 -298.769024)
		(size 0.508)
		(drill 0.254)
		(layers "F.Cu" "B.Cu")
		(net "GND")
	)
	(via
		(at 39.689786 -128.627886)
		(size 0.508)
		(drill 0.254)
		(layers "F.Cu" "B.Cu")
		(net "GND")
	)
	(via
		(at 40.927274 -196.819012)
		(size 0.508)
		(drill 0.254)
		(layers "F.Cu" "B.Cu")
		(net "GND")
	)
	(via
		(at 59.478672 -251.234702)
		(size 0.508)
		(drill 0.254)
		(layers "F.Cu" "B.Cu")
		(net "GND")
	)
	(via
		(at 45.176948 -75.756262)
		(size 0.508)
		(drill 0.254)
		(layers "F.Cu" "B.Cu")
		(net "GND")
	)
	(via
		(at 61.691012 -427.85411)
		(size 0.508)
		(drill 0.254)
		(layers "F.Cu" "B.Cu")
		(net "GND")
	)
	(via
		(at 102.238048 -309.145432)
		(size 0.508)
		(drill 0.254)
		(layers "F.Cu" "B.Cu")
		(net "GND")
	)
	(via
		(at 39.393114 -475.798388)
		(size 0.508)
		(drill 0.254)
		(layers "F.Cu" "B.Cu")
		(net "GND")
	)
	(via
		(at 76.299568 -391.975594)
		(size 0.508)
		(drill 0.254)
		(layers "F.Cu" "B.Cu")
		(net "GND")
	)
	(via
		(at 45.6438 -304.356262)
		(size 0.508)
		(drill 0.254)
		(layers "F.Cu" "B.Cu")
		(net "GND")
	)
	(via
		(at 39.689786 -130.537712)
		(size 0.508)
		(drill 0.254)
		(layers "F.Cu" "B.Cu")
		(net "GND")
	)
	(via
		(at 46.808136 -240.876074)
		(size 0.508)
		(drill 0.254)
		(layers "F.Cu" "B.Cu")
		(net "GND")
	)
	(via
		(at 72.284082 -437.76011)
		(size 0.508)
		(drill 0.254)
		(layers "F.Cu" "B.Cu")
		(net "GND")
	)
	(via
		(at 40.986964 -394.06449)
		(size 0.508)
		(drill 0.254)
		(layers "F.Cu" "B.Cu")
		(net "GND")
	)
	(via
		(at 43.27144 -386.211826)
		(size 0.508)
		(drill 0.254)
		(layers "F.Cu" "B.Cu")
		(net "GND")
	)
	(via
		(at 57.902602 -152.784302)
		(size 0.508)
		(drill 0.254)
		(layers "F.Cu" "B.Cu")
		(net "GND")
	)
	(via
		(at 102.238048 -80.545432)
		(size 0.508)
		(drill 0.254)
		(layers "F.Cu" "B.Cu")
		(net "GND")
	)
	(via
		(at 57.902602 -154.459432)
		(size 0.508)
		(drill 0.254)
		(layers "F.Cu" "B.Cu")
		(net "GND")
	)
	(via
		(at 62.453012 -426.17898)
		(size 0.508)
		(drill 0.254)
		(layers "F.Cu" "B.Cu")
		(net "GND")
	)
	(via
		(at 63.106554 -16.378682)
		(size 0.508)
		(drill 0.254)
		(layers "F.Cu" "B.Cu")
		(net "GND")
	)
	(via
		(at 89.253314 -345.450922)
		(size 0.508)
		(drill 0.254)
		(layers "F.Cu" "B.Cu")
		(net "GND")
	)
	(via
		(at 63.93434 -152.784302)
		(size 0.508)
		(drill 0.254)
		(layers "F.Cu" "B.Cu")
		(net "GND")
	)
	(via
		(at 39.439342 -214.559388)
		(size 0.508)
		(drill 0.254)
		(layers "F.Cu" "B.Cu")
		(net "GND")
	)
	(via
		(at 39.482776 -208.97215)
		(size 0.508)
		(drill 0.254)
		(layers "F.Cu" "B.Cu")
		(net "GND")
	)
	(via
		(at 42.715434 -487.227118)
		(size 0.508)
		(drill 0.254)
		(layers "F.Cu" "B.Cu")
		(net "GND")
	)
	(via
		(at 39.862252 -388.222998)
		(size 0.508)
		(drill 0.254)
		(layers "F.Cu" "B.Cu")
		(net "GND")
	)
	(segment
		(start 48.728884 -195.776596)
		(end 48.728884 -196.729604)
		(width 0.6604)
		(layer "B.Cu")
		(net "GND")
	)
	(segment
		(start 48.804322 -417.68395)
		(end 48.804322 -418.636958)
		(width 0.6604)
		(layer "B.Cu")
		(net "GND")
	)
	(segment
		(start 48.668178 -439.763154)
		(end 49.621186 -439.763154)
		(width 0.6604)
		(layer "B.Cu")
		(net "GND")
	)
	(segment
		(start 48.804322 -418.636958)
		(end 48.804322 -419.589966)
		(width 0.6604)
		(layer "B.Cu")
		(net "GND")
	)
	(segment
		(start 47.695612 -463.099658)
		(end 48.64862 -463.099658)
		(width 0.6604)
		(layer "B.Cu")
		(net "GND")
	)
	(segment
		(start 48.199548 -17.615662)
		(end 48.199548 -18.56867)
		(width 0.6604)
		(layer "B.Cu")
		(net "GND")
	)
	(segment
		(start 47.624492 -285.205424)
		(end 48.5775 -285.205424)
		(width 0.6604)
		(layer "B.Cu")
		(net "GND")
	)
	(segment
		(start 47.581058 -395.548358)
		(end 48.534066 -395.548358)
		(width 0.6604)
		(layer "B.Cu")
		(net "GND")
	)
	(segment
		(start 48.79975 -506.724412)
		(end 48.79975 -507.67742)
		(width 0.6604)
		(layer "B.Cu")
		(net "GND")
	)
	(segment
		(start 48.64862 -463.099658)
		(end 48.64862 -464.052666)
		(width 0.6604)
		(layer "B.Cu")
		(net "GND")
	)
	(segment
		(start 48.64862 -519.020552)
		(end 49.601628 -519.020552)
		(width 0.6604)
		(layer "B.Cu")
		(net "GND")
	)
	(segment
		(start 89.403682 -479.280474)
		(end 89.493598 -479.37039)
		(width 0.3556)
		(layer "B.Cu")
		(net "GND")
	)
	(segment
		(start 48.728884 -329.972416)
		(end 49.681892 -329.972416)
		(width 0.6604)
		(layer "B.Cu")
		(net "GND")
	)
	(segment
		(start 48.64862 -518.067544)
		(end 48.64862 -519.020552)
		(width 0.6604)
		(layer "B.Cu")
		(net "GND")
	)
	(segment
		(start 48.79975 -507.67742)
		(end 48.79975 -508.630428)
		(width 0.6604)
		(layer "B.Cu")
		(net "GND")
	)
	(segment
		(start 48.534066 -394.59535)
		(end 48.534066 -395.548358)
		(width 0.6604)
		(layer "B.Cu")
		(net "GND")
	)
	(segment
		(start 48.199294 -107.119928)
		(end 48.199294 -108.072936)
		(width 0.6604)
		(layer "B.Cu")
		(net "GND")
	)
	(segment
		(start 48.199548 -18.56867)
		(end 48.199548 -19.521678)
		(width 0.6604)
		(layer "B.Cu")
		(net "GND")
	)
	(segment
		(start 48.400208 -350.765364)
		(end 48.400208 -351.718372)
		(width 0.6604)
		(layer "B.Cu")
		(net "GND")
	)
	(segment
		(start 48.993552 -151.92502)
		(end 48.993552 -152.878028)
		(width 0.6604)
		(layer "B.Cu")
		(net "GND")
	)
	(segment
		(start 47.170594 -374.437148)
		(end 48.123602 -374.437148)
		(width 0.6604)
		(layer "B.Cu")
		(net "GND")
	)
	(segment
		(start 48.600868 -305.430174)
		(end 48.600868 -306.383182)
		(width 0.6604)
		(layer "B.Cu")
		(net "GND")
	)
	(segment
		(start 48.728884 -329.972416)
		(end 48.728884 -330.925424)
		(width 0.6604)
		(layer "B.Cu")
		(net "GND")
	)
	(segment
		(start 48.600868 -306.383182)
		(end 48.600868 -307.33619)
		(width 0.6604)
		(layer "B.Cu")
		(net "GND")
	)
	(segment
		(start 48.123602 -374.437148)
		(end 49.07661 -374.437148)
		(width 0.6604)
		(layer "B.Cu")
		(net "GND")
	)
	(segment
		(start 48.667924 -216.532968)
		(end 48.667924 -217.485976)
		(width 0.6604)
		(layer "B.Cu")
		(net "GND")
	)
	(segment
		(start 48.199548 -18.56867)
		(end 49.152556 -18.56867)
		(width 0.6604)
		(layer "B.Cu")
		(net "GND")
	)
	(segment
		(start 48.64862 -462.14665)
		(end 48.64862 -463.099658)
		(width 0.6604)
		(layer "B.Cu")
		(net "GND")
	)
	(segment
		(start 48.123602 -373.48414)
		(end 48.123602 -374.437148)
		(width 0.6604)
		(layer "B.Cu")
		(net "GND")
	)
	(segment
		(start 48.804322 -418.636958)
		(end 49.75733 -418.636958)
		(width 0.6604)
		(layer "B.Cu")
		(net "GND")
	)
	(segment
		(start 49.862994 -239.6363)
		(end 49.862994 -240.589308)
		(width 0.6604)
		(layer "B.Cu")
		(net "GND")
	)
	(segment
		(start 89.916 -166.874444)
		(end 89.916 -165.65118)
		(width 0.3556)
		(layer "B.Cu")
		(net "GND")
	)
	(segment
		(start 49.661064 -262.266176)
		(end 50.614072 -262.266176)
		(width 0.6604)
		(layer "B.Cu")
		(net "GND")
	)
	(segment
		(start 47.24654 -18.56867)
		(end 48.199548 -18.56867)
		(width 0.6604)
		(layer "B.Cu")
		(net "GND")
	)
	(segment
		(start 48.909986 -240.589308)
		(end 49.862994 -240.589308)
		(width 0.6604)
		(layer "B.Cu")
		(net "GND")
	)
	(segment
		(start 48.993552 -151.92502)
		(end 49.94656 -151.92502)
		(width 0.6604)
		(layer "B.Cu")
		(net "GND")
	)
	(segment
		(start 48.350678 -61.929264)
		(end 48.350678 -62.882272)
		(width 0.6604)
		(layer "B.Cu")
		(net "GND")
	)
	(segment
		(start 49.862994 -240.589308)
		(end 50.816002 -240.589308)
		(width 0.6604)
		(layer "B.Cu")
		(net "GND")
	)
	(segment
		(start 48.5775 -285.205424)
		(end 48.5775 -286.158432)
		(width 0.6604)
		(layer "B.Cu")
		(net "GND")
	)
	(segment
		(start 48.708056 -262.266176)
		(end 49.661064 -262.266176)
		(width 0.6604)
		(layer "B.Cu")
		(net "GND")
	)
	(segment
		(start 48.199294 -107.119928)
		(end 49.152302 -107.119928)
		(width 0.6604)
		(layer "B.Cu")
		(net "GND")
	)
	(segment
		(start 48.668178 -439.763154)
		(end 48.668178 -440.716162)
		(width 0.6604)
		(layer "B.Cu")
		(net "GND")
	)
	(segment
		(start 48.333406 -482.70668)
		(end 49.286414 -482.70668)
		(width 0.6604)
		(layer "B.Cu")
		(net "GND")
	)
	(segment
		(start 91.357958 -78.693264)
		(end 91.896946 -79.232252)
		(width 0.3556)
		(layer "B.Cu")
		(net "GND")
	)
	(segment
		(start 91.357958 -77.950314)
		(end 91.357958 -78.693264)
		(width 0.3556)
		(layer "B.Cu")
		(net "GND")
	)
	(segment
		(start 47.71517 -439.763154)
		(end 48.668178 -439.763154)
		(width 0.6604)
		(layer "B.Cu")
		(net "GND")
	)
	(segment
		(start 47.695612 -519.020552)
		(end 48.64862 -519.020552)
		(width 0.6604)
		(layer "B.Cu")
		(net "GND")
	)
	(segment
		(start 48.199294 -106.16692)
		(end 48.199294 -107.119928)
		(width 0.6604)
		(layer "B.Cu")
		(net "GND")
	)
	(segment
		(start 48.350678 -62.882272)
		(end 48.350678 -63.83528)
		(width 0.6604)
		(layer "B.Cu")
		(net "GND")
	)
	(segment
		(start 47.246286 -107.119928)
		(end 48.199294 -107.119928)
		(width 0.6604)
		(layer "B.Cu")
		(net "GND")
	)
	(segment
		(start 48.467264 -173.13783)
		(end 48.467264 -174.090838)
		(width 0.6604)
		(layer "B.Cu")
		(net "GND")
	)
	(segment
		(start 47.846742 -507.67742)
		(end 48.79975 -507.67742)
		(width 0.6604)
		(layer "B.Cu")
		(net "GND")
	)
	(segment
		(start 48.400208 -350.765364)
		(end 49.353216 -350.765364)
		(width 0.6604)
		(layer "B.Cu")
		(net "GND")
	)
	(segment
		(start 47.775876 -329.972416)
		(end 48.728884 -329.972416)
		(width 0.6604)
		(layer "B.Cu")
		(net "GND")
	)
	(segment
		(start 47.714916 -217.485976)
		(end 48.667924 -217.485976)
		(width 0.6604)
		(layer "B.Cu")
		(net "GND")
	)
	(segment
		(start 48.400462 -128.655318)
		(end 49.35347 -128.655318)
		(width 0.6604)
		(layer "B.Cu")
		(net "GND")
	)
	(segment
		(start 94.518988 -343.180924)
		(end 94.885256 -343.547192)
		(width 0.3556)
		(layer "B.Cu")
		(net "GND")
	)
	(segment
		(start 48.467518 -84.273644)
		(end 49.420526 -84.273644)
		(width 0.6604)
		(layer "B.Cu")
		(net "GND")
	)
	(segment
		(start 48.333406 -38.6207)
		(end 49.286414 -38.6207)
		(width 0.6604)
		(layer "B.Cu")
		(net "GND")
	)
	(segment
		(start 47.380398 -482.70668)
		(end 48.333406 -482.70668)
		(width 0.6604)
		(layer "B.Cu")
		(net "GND")
	)
	(segment
		(start 48.400208 -349.812356)
		(end 48.400208 -350.765364)
		(width 0.6604)
		(layer "B.Cu")
		(net "GND")
	)
	(segment
		(start 48.667924 -217.485976)
		(end 49.620932 -217.485976)
		(width 0.6604)
		(layer "B.Cu")
		(net "GND")
	)
	(segment
		(start 47.39767 -62.882272)
		(end 48.350678 -62.882272)
		(width 0.6604)
		(layer "B.Cu")
		(net "GND")
	)
	(segment
		(start 48.400462 -127.70231)
		(end 48.400462 -128.655318)
		(width 0.6604)
		(layer "B.Cu")
		(net "GND")
	)
	(segment
		(start 48.5775 -285.205424)
		(end 49.530508 -285.205424)
		(width 0.6604)
		(layer "B.Cu")
		(net "GND")
	)
	(segment
		(start 94.518988 -342.20277)
		(end 94.518988 -343.180924)
		(width 0.3556)
		(layer "B.Cu")
		(net "GND")
	)
	(segment
		(start 48.333406 -481.753672)
		(end 48.333406 -482.70668)
		(width 0.6604)
		(layer "B.Cu")
		(net "GND")
	)
	(segment
		(start 48.467264 -172.184822)
		(end 48.467264 -173.13783)
		(width 0.6604)
		(layer "B.Cu")
		(net "GND")
	)
	(segment
		(start 48.467518 -84.273644)
		(end 48.467518 -85.226652)
		(width 0.6604)
		(layer "B.Cu")
		(net "GND")
	)
	(segment
		(start 47.775876 -196.729604)
		(end 48.728884 -196.729604)
		(width 0.6604)
		(layer "B.Cu")
		(net "GND")
	)
	(segment
		(start 89.403682 -478.029524)
		(end 89.403682 -479.280474)
		(width 0.3556)
		(layer "B.Cu")
		(net "GND")
	)
	(segment
		(start 48.333406 -482.70668)
		(end 48.333406 -483.659688)
		(width 0.6604)
		(layer "B.Cu")
		(net "GND")
	)
	(segment
		(start 48.123602 -374.437148)
		(end 48.123602 -375.390156)
		(width 0.6604)
		(layer "B.Cu")
		(net "GND")
	)
	(segment
		(start 49.661064 -261.313168)
		(end 49.661064 -262.266176)
		(width 0.6604)
		(layer "B.Cu")
		(net "GND")
	)
	(segment
		(start 48.79975 -507.67742)
		(end 49.752758 -507.67742)
		(width 0.6604)
		(layer "B.Cu")
		(net "GND")
	)
	(segment
		(start 48.64862 -519.020552)
		(end 48.64862 -519.97356)
		(width 0.6604)
		(layer "B.Cu")
		(net "GND")
	)
	(segment
		(start 48.64862 -463.099658)
		(end 49.601628 -463.099658)
		(width 0.6604)
		(layer "B.Cu")
		(net "GND")
	)
	(segment
		(start 48.667924 -217.485976)
		(end 48.667924 -218.438984)
		(width 0.6604)
		(layer "B.Cu")
		(net "GND")
	)
	(segment
		(start 47.64786 -306.383182)
		(end 48.600868 -306.383182)
		(width 0.6604)
		(layer "B.Cu")
		(net "GND")
	)
	(segment
		(start 47.447454 -128.655318)
		(end 48.400462 -128.655318)
		(width 0.6604)
		(layer "B.Cu")
		(net "GND")
	)
	(segment
		(start 47.380398 -38.6207)
		(end 48.333406 -38.6207)
		(width 0.6604)
		(layer "B.Cu")
		(net "GND")
	)
	(segment
		(start 48.400462 -128.655318)
		(end 48.400462 -129.608326)
		(width 0.6604)
		(layer "B.Cu")
		(net "GND")
	)
	(segment
		(start 49.862994 -240.589308)
		(end 49.862994 -241.542316)
		(width 0.6604)
		(layer "B.Cu")
		(net "GND")
	)
	(segment
		(start 48.467264 -173.13783)
		(end 49.420272 -173.13783)
		(width 0.6604)
		(layer "B.Cu")
		(net "GND")
	)
	(segment
		(start 48.728884 -196.729604)
		(end 48.728884 -197.682612)
		(width 0.6604)
		(layer "B.Cu")
		(net "GND")
	)
	(segment
		(start 48.600868 -306.383182)
		(end 49.553876 -306.383182)
		(width 0.6604)
		(layer "B.Cu")
		(net "GND")
	)
	(segment
		(start 48.333406 -37.667692)
		(end 48.333406 -38.6207)
		(width 0.6604)
		(layer "B.Cu")
		(net "GND")
	)
	(segment
		(start 48.333406 -38.6207)
		(end 48.333406 -39.573708)
		(width 0.6604)
		(layer "B.Cu")
		(net "GND")
	)
	(segment
		(start 48.5775 -284.252416)
		(end 48.5775 -285.205424)
		(width 0.6604)
		(layer "B.Cu")
		(net "GND")
	)
	(segment
		(start 48.040544 -151.92502)
		(end 48.993552 -151.92502)
		(width 0.6604)
		(layer "B.Cu")
		(net "GND")
	)
	(segment
		(start 47.51451 -84.273644)
		(end 48.467518 -84.273644)
		(width 0.6604)
		(layer "B.Cu")
		(net "GND")
	)
	(segment
		(start 48.467518 -83.320636)
		(end 48.467518 -84.273644)
		(width 0.6604)
		(layer "B.Cu")
		(net "GND")
	)
	(segment
		(start 48.534066 -395.548358)
		(end 48.534066 -396.501366)
		(width 0.6604)
		(layer "B.Cu")
		(net "GND")
	)
	(segment
		(start 47.4472 -350.765364)
		(end 48.400208 -350.765364)
		(width 0.6604)
		(layer "B.Cu")
		(net "GND")
	)
	(segment
		(start 47.514256 -173.13783)
		(end 48.467264 -173.13783)
		(width 0.6604)
		(layer "B.Cu")
		(net "GND")
	)
	(segment
		(start 48.668178 -438.810146)
		(end 48.668178 -439.763154)
		(width 0.6604)
		(layer "B.Cu")
		(net "GND")
	)
	(segment
		(start 47.851314 -418.636958)
		(end 48.804322 -418.636958)
		(width 0.6604)
		(layer "B.Cu")
		(net "GND")
	)
	(segment
		(start 48.993552 -150.972012)
		(end 48.993552 -151.92502)
		(width 0.6604)
		(layer "B.Cu")
		(net "GND")
	)
	(segment
		(start 49.661064 -262.266176)
		(end 49.661064 -263.219184)
		(width 0.6604)
		(layer "B.Cu")
		(net "GND")
	)
	(segment
		(start 48.350678 -62.882272)
		(end 49.303686 -62.882272)
		(width 0.6604)
		(layer "B.Cu")
		(net "GND")
	)
	(segment
		(start 48.728884 -196.729604)
		(end 49.681892 -196.729604)
		(width 0.6604)
		(layer "B.Cu")
		(net "GND")
	)
	(segment
		(start 48.728884 -329.019408)
		(end 48.728884 -329.972416)
		(width 0.6604)
		(layer "B.Cu")
		(net "GND")
	)
	(segment
		(start 48.534066 -395.548358)
		(end 49.487074 -395.548358)
		(width 0.6604)
		(layer "B.Cu")
		(net "GND")
	)
	(segment
		(start 48.467518 -84.273644)
		(end 49.420526 -84.273644)
		(width 0.635)
		(layer "In5.Cu")
		(net "GND")
	)
	(segment
		(start 48.040544 -151.92502)
		(end 48.993552 -151.92502)
		(width 0.635)
		(layer "In5.Cu")
		(net "GND")
	)
	(segment
		(start 48.728884 -329.019408)
		(end 48.728884 -329.972416)
		(width 0.635)
		(layer "In5.Cu")
		(net "GND")
	)
	(segment
		(start 48.333406 -481.753672)
		(end 48.333406 -482.70668)
		(width 0.635)
		(layer "In5.Cu")
		(net "GND")
	)
	(segment
		(start 47.695612 -463.099658)
		(end 48.64862 -463.099658)
		(width 0.635)
		(layer "In5.Cu")
		(net "GND")
	)
	(segment
		(start 48.804322 -418.636958)
		(end 48.804322 -419.589966)
		(width 0.635)
		(layer "In5.Cu")
		(net "GND")
	)
	(segment
		(start 48.79975 -507.67742)
		(end 48.79975 -508.630428)
		(width 0.635)
		(layer "In5.Cu")
		(net "GND")
	)
	(segment
		(start 47.39767 -62.882272)
		(end 48.350678 -62.882272)
		(width 0.635)
		(layer "In5.Cu")
		(net "GND")
	)
	(segment
		(start 48.400462 -128.655318)
		(end 48.400462 -129.608326)
		(width 0.635)
		(layer "In5.Cu")
		(net "GND")
	)
	(segment
		(start 48.123602 -374.437148)
		(end 49.07661 -374.437148)
		(width 0.635)
		(layer "In5.Cu")
		(net "GND")
	)
	(segment
		(start 48.79975 -506.724412)
		(end 48.79975 -507.67742)
		(width 0.635)
		(layer "In5.Cu")
		(net "GND")
	)
	(segment
		(start 47.624492 -285.205424)
		(end 48.5775 -285.205424)
		(width 0.635)
		(layer "In5.Cu")
		(net "GND")
	)
	(segment
		(start 47.380398 -38.6207)
		(end 48.333406 -38.6207)
		(width 0.635)
		(layer "In5.Cu")
		(net "GND")
	)
	(segment
		(start 48.5775 -285.205424)
		(end 49.530508 -285.205424)
		(width 0.635)
		(layer "In5.Cu")
		(net "GND")
	)
	(segment
		(start 48.333406 -482.70668)
		(end 49.286414 -482.70668)
		(width 0.635)
		(layer "In5.Cu")
		(net "GND")
	)
	(segment
		(start 48.667924 -217.485976)
		(end 48.667924 -218.438984)
		(width 0.635)
		(layer "In5.Cu")
		(net "GND")
	)
	(segment
		(start 49.862994 -240.589308)
		(end 49.862994 -241.542316)
		(width 0.635)
		(layer "In5.Cu")
		(net "GND")
	)
	(segment
		(start 48.534066 -395.548358)
		(end 48.534066 -396.501366)
		(width 0.635)
		(layer "In5.Cu")
		(net "GND")
	)
	(segment
		(start 47.380398 -482.70668)
		(end 48.333406 -482.70668)
		(width 0.635)
		(layer "In5.Cu")
		(net "GND")
	)
	(segment
		(start 47.581058 -395.548358)
		(end 48.534066 -395.548358)
		(width 0.635)
		(layer "In5.Cu")
		(net "GND")
	)
	(segment
		(start 47.514256 -173.13783)
		(end 48.467264 -173.13783)
		(width 0.635)
		(layer "In5.Cu")
		(net "GND")
	)
	(segment
		(start 48.600868 -306.383182)
		(end 48.600868 -307.33619)
		(width 0.635)
		(layer "In5.Cu")
		(net "GND")
	)
	(segment
		(start 47.851314 -418.636958)
		(end 48.804322 -418.636958)
		(width 0.635)
		(layer "In5.Cu")
		(net "GND")
	)
	(segment
		(start 48.199294 -106.16692)
		(end 48.199294 -107.119928)
		(width 0.635)
		(layer "In5.Cu")
		(net "GND")
	)
	(segment
		(start 48.199548 -18.56867)
		(end 48.199548 -19.521678)
		(width 0.635)
		(layer "In5.Cu")
		(net "GND")
	)
	(segment
		(start 47.24654 -18.56867)
		(end 48.199548 -18.56867)
		(width 0.635)
		(layer "In5.Cu")
		(net "GND")
	)
	(segment
		(start 48.64862 -462.14665)
		(end 48.64862 -463.099658)
		(width 0.635)
		(layer "In5.Cu")
		(net "GND")
	)
	(segment
		(start 48.534066 -394.59535)
		(end 48.534066 -395.548358)
		(width 0.635)
		(layer "In5.Cu")
		(net "GND")
	)
	(segment
		(start 47.170594 -374.437148)
		(end 48.123602 -374.437148)
		(width 0.635)
		(layer "In5.Cu")
		(net "GND")
	)
	(segment
		(start 48.728884 -196.729604)
		(end 48.728884 -197.682612)
		(width 0.635)
		(layer "In5.Cu")
		(net "GND")
	)
	(segment
		(start 48.350678 -62.882272)
		(end 49.303686 -62.882272)
		(width 0.635)
		(layer "In5.Cu")
		(net "GND")
	)
	(segment
		(start 47.714916 -217.485976)
		(end 48.667924 -217.485976)
		(width 0.635)
		(layer "In5.Cu")
		(net "GND")
	)
	(segment
		(start 48.350678 -61.929264)
		(end 48.350678 -62.882272)
		(width 0.635)
		(layer "In5.Cu")
		(net "GND")
	)
	(segment
		(start 48.333406 -37.667692)
		(end 48.333406 -38.6207)
		(width 0.635)
		(layer "In5.Cu")
		(net "GND")
	)
	(segment
		(start 48.467518 -83.320636)
		(end 48.467518 -84.273644)
		(width 0.635)
		(layer "In5.Cu")
		(net "GND")
	)
	(segment
		(start 48.400462 -128.655318)
		(end 49.35347 -128.655318)
		(width 0.635)
		(layer "In5.Cu")
		(net "GND")
	)
	(segment
		(start 47.695612 -519.020552)
		(end 48.64862 -519.020552)
		(width 0.635)
		(layer "In5.Cu")
		(net "GND")
	)
	(segment
		(start 47.846742 -507.67742)
		(end 48.79975 -507.67742)
		(width 0.635)
		(layer "In5.Cu")
		(net "GND")
	)
	(segment
		(start 48.668178 -439.763154)
		(end 49.621186 -439.763154)
		(width 0.635)
		(layer "In5.Cu")
		(net "GND")
	)
	(segment
		(start 48.5775 -284.252416)
		(end 48.5775 -285.205424)
		(width 0.635)
		(layer "In5.Cu")
		(net "GND")
	)
	(segment
		(start 48.467264 -173.13783)
		(end 48.467264 -174.090838)
		(width 0.635)
		(layer "In5.Cu")
		(net "GND")
	)
	(segment
		(start 47.447454 -128.655318)
		(end 48.400462 -128.655318)
		(width 0.635)
		(layer "In5.Cu")
		(net "GND")
	)
	(segment
		(start 48.123602 -374.437148)
		(end 48.123602 -375.390156)
		(width 0.635)
		(layer "In5.Cu")
		(net "GND")
	)
	(segment
		(start 48.600868 -305.430174)
		(end 48.600868 -306.383182)
		(width 0.635)
		(layer "In5.Cu")
		(net "GND")
	)
	(segment
		(start 48.668178 -438.810146)
		(end 48.668178 -439.763154)
		(width 0.635)
		(layer "In5.Cu")
		(net "GND")
	)
	(segment
		(start 48.400208 -350.765364)
		(end 49.353216 -350.765364)
		(width 0.635)
		(layer "In5.Cu")
		(net "GND")
	)
	(segment
		(start 47.4472 -350.765364)
		(end 48.400208 -350.765364)
		(width 0.635)
		(layer "In5.Cu")
		(net "GND")
	)
	(segment
		(start 48.64862 -519.020552)
		(end 48.64862 -519.97356)
		(width 0.635)
		(layer "In5.Cu")
		(net "GND")
	)
	(segment
		(start 48.199294 -107.119928)
		(end 48.199294 -108.072936)
		(width 0.635)
		(layer "In5.Cu")
		(net "GND")
	)
	(segment
		(start 47.775876 -196.729604)
		(end 48.728884 -196.729604)
		(width 0.635)
		(layer "In5.Cu")
		(net "GND")
	)
	(segment
		(start 49.862994 -239.6363)
		(end 49.862994 -240.589308)
		(width 0.635)
		(layer "In5.Cu")
		(net "GND")
	)
	(segment
		(start 47.71517 -439.763154)
		(end 48.668178 -439.763154)
		(width 0.635)
		(layer "In5.Cu")
		(net "GND")
	)
	(segment
		(start 48.199548 -17.615662)
		(end 48.199548 -18.56867)
		(width 0.635)
		(layer "In5.Cu")
		(net "GND")
	)
	(segment
		(start 47.51451 -84.273644)
		(end 48.467518 -84.273644)
		(width 0.635)
		(layer "In5.Cu")
		(net "GND")
	)
	(segment
		(start 48.64862 -519.020552)
		(end 49.601628 -519.020552)
		(width 0.635)
		(layer "In5.Cu")
		(net "GND")
	)
	(segment
		(start 48.728884 -195.776596)
		(end 48.728884 -196.729604)
		(width 0.635)
		(layer "In5.Cu")
		(net "GND")
	)
	(segment
		(start 48.728884 -196.729604)
		(end 49.681892 -196.729604)
		(width 0.635)
		(layer "In5.Cu")
		(net "GND")
	)
	(segment
		(start 48.400208 -349.812356)
		(end 48.400208 -350.765364)
		(width 0.635)
		(layer "In5.Cu")
		(net "GND")
	)
	(segment
		(start 48.993552 -151.92502)
		(end 49.94656 -151.92502)
		(width 0.635)
		(layer "In5.Cu")
		(net "GND")
	)
	(segment
		(start 48.534066 -395.548358)
		(end 49.487074 -395.548358)
		(width 0.635)
		(layer "In5.Cu")
		(net "GND")
	)
	(segment
		(start 48.667924 -217.485976)
		(end 49.620932 -217.485976)
		(width 0.635)
		(layer "In5.Cu")
		(net "GND")
	)
	(segment
		(start 48.400208 -350.765364)
		(end 48.400208 -351.718372)
		(width 0.635)
		(layer "In5.Cu")
		(net "GND")
	)
	(segment
		(start 48.333406 -38.6207)
		(end 49.286414 -38.6207)
		(width 0.635)
		(layer "In5.Cu")
		(net "GND")
	)
	(segment
		(start 48.333406 -38.6207)
		(end 48.333406 -39.573708)
		(width 0.635)
		(layer "In5.Cu")
		(net "GND")
	)
	(segment
		(start 48.467264 -172.184822)
		(end 48.467264 -173.13783)
		(width 0.635)
		(layer "In5.Cu")
		(net "GND")
	)
	(segment
		(start 48.5775 -285.205424)
		(end 48.5775 -286.158432)
		(width 0.635)
		(layer "In5.Cu")
		(net "GND")
	)
	(segment
		(start 48.467518 -84.273644)
		(end 48.467518 -85.226652)
		(width 0.635)
		(layer "In5.Cu")
		(net "GND")
	)
	(segment
		(start 48.804322 -417.68395)
		(end 48.804322 -418.636958)
		(width 0.635)
		(layer "In5.Cu")
		(net "GND")
	)
	(segment
		(start 48.400462 -127.70231)
		(end 48.400462 -128.655318)
		(width 0.635)
		(layer "In5.Cu")
		(net "GND")
	)
	(segment
		(start 48.64862 -518.067544)
		(end 48.64862 -519.020552)
		(width 0.635)
		(layer "In5.Cu")
		(net "GND")
	)
	(segment
		(start 48.600868 -306.383182)
		(end 49.553876 -306.383182)
		(width 0.635)
		(layer "In5.Cu")
		(net "GND")
	)
	(segment
		(start 47.64786 -306.383182)
		(end 48.600868 -306.383182)
		(width 0.635)
		(layer "In5.Cu")
		(net "GND")
	)
	(segment
		(start 48.993552 -150.972012)
		(end 48.993552 -151.92502)
		(width 0.635)
		(layer "In5.Cu")
		(net "GND")
	)
	(segment
		(start 48.909986 -240.589308)
		(end 49.862994 -240.589308)
		(width 0.635)
		(layer "In5.Cu")
		(net "GND")
	)
	(segment
		(start 48.123602 -373.48414)
		(end 48.123602 -374.437148)
		(width 0.635)
		(layer "In5.Cu")
		(net "GND")
	)
	(segment
		(start 48.728884 -329.972416)
		(end 48.728884 -330.925424)
		(width 0.635)
		(layer "In5.Cu")
		(net "GND")
	)
	(segment
		(start 48.668178 -439.763154)
		(end 48.668178 -440.716162)
		(width 0.635)
		(layer "In5.Cu")
		(net "GND")
	)
	(segment
		(start 47.775876 -329.972416)
		(end 48.728884 -329.972416)
		(width 0.635)
		(layer "In5.Cu")
		(net "GND")
	)
	(segment
		(start 48.64862 -463.099658)
		(end 48.64862 -464.052666)
		(width 0.635)
		(layer "In5.Cu")
		(net "GND")
	)
	(segment
		(start 49.862994 -240.589308)
		(end 50.816002 -240.589308)
		(width 0.635)
		(layer "In5.Cu")
		(net "GND")
	)
	(segment
		(start 48.993552 -151.92502)
		(end 48.993552 -152.878028)
		(width 0.635)
		(layer "In5.Cu")
		(net "GND")
	)
	(segment
		(start 48.804322 -418.636958)
		(end 49.75733 -418.636958)
		(width 0.635)
		(layer "In5.Cu")
		(net "GND")
	)
	(segment
		(start 48.79975 -507.67742)
		(end 49.752758 -507.67742)
		(width 0.635)
		(layer "In5.Cu")
		(net "GND")
	)
	(segment
		(start 48.728884 -329.972416)
		(end 49.681892 -329.972416)
		(width 0.635)
		(layer "In5.Cu")
		(net "GND")
	)
	(segment
		(start 48.199548 -18.56867)
		(end 49.152556 -18.56867)
		(width 0.635)
		(layer "In5.Cu")
		(net "GND")
	)
	(segment
		(start 48.350678 -62.882272)
		(end 48.350678 -63.83528)
		(width 0.635)
		(layer "In5.Cu")
		(net "GND")
	)
	(segment
		(start 48.667924 -216.532968)
		(end 48.667924 -217.485976)
		(width 0.635)
		(layer "In5.Cu")
		(net "GND")
	)
	(segment
		(start 48.467264 -173.13783)
		(end 49.420272 -173.13783)
		(width 0.635)
		(layer "In5.Cu")
		(net "GND")
	)
	(segment
		(start 47.246286 -107.119928)
		(end 48.199294 -107.119928)
		(width 0.635)
		(layer "In5.Cu")
		(net "GND")
	)
	(segment
		(start 48.199294 -107.119928)
		(end 49.152302 -107.119928)
		(width 0.635)
		(layer "In5.Cu")
		(net "GND")
	)
	(segment
		(start 48.333406 -482.70668)
		(end 48.333406 -483.659688)
		(width 0.635)
		(layer "In5.Cu")
		(net "GND")
	)
	(segment
		(start 48.64862 -463.099658)
		(end 49.601628 -463.099658)
		(width 0.635)
		(layer "In5.Cu")
		(net "GND")
	)
	(segment
		(start 38.871144 -375.989596)
		(end 39.577264 -375.989596)
		(width 0.1524)
		(layer "F.Cu")
		(net "PSU5_REMOTE_P")
	)
	(segment
		(start 35.53968 -375.970038)
		(end 37.555932 -375.970038)
		(width 0.1524)
		(layer "F.Cu")
		(net "PSU5_REMOTE_P")
	)
	(segment
		(start 37.784532 -376.198638)
		(end 38.662102 -376.198638)
		(width 0.1524)
		(layer "F.Cu")
		(net "PSU5_REMOTE_P")
	)
	(segment
		(start 38.662102 -376.198638)
		(end 38.871144 -375.989596)
		(width 0.1524)
		(layer "F.Cu")
		(net "PSU5_REMOTE_P")
	)
	(segment
		(start 37.555932 -375.970038)
		(end 37.784532 -376.198638)
		(width 0.1524)
		(layer "F.Cu")
		(net "PSU5_REMOTE_P")
	)
	(segment
		(start 35.53968 -287.56991)
		(end 39.454836 -287.56991)
		(width 0.508)
		(layer "F.Cu")
		(net "PSU4_REMOTE_P")
	)
	(segment
		(start 39.454836 -287.56991)
		(end 39.458138 -287.573212)
		(width 0.508)
		(layer "F.Cu")
		(net "PSU4_REMOTE_P")
	)
	(segment
		(start 39.903908 -369.11153)
		(end 40.434768 -368.58067)
		(width 0.1524)
		(layer "F.Cu")
		(net "PSU5_RETURN")
	)
	(segment
		(start 39.903908 -370.099336)
		(end 39.903908 -369.11153)
		(width 0.1524)
		(layer "F.Cu")
		(net "PSU5_RETURN")
	)
	(segment
		(start 35.53968 -365.810038)
		(end 37.664136 -365.810038)
		(width 0.1524)
		(layer "F.Cu")
		(net "PSU5_RETURN")
	)
	(segment
		(start 37.664136 -365.810038)
		(end 40.434768 -368.58067)
		(width 0.1524)
		(layer "F.Cu")
		(net "PSU5_RETURN")
	)
	(via
		(at 40.434768 -368.58067)
		(size 0.508)
		(drill 0.254)
		(layers "F.Cu" "B.Cu")
		(net "PSU5_RETURN")
	)
	(segment
		(start 39.459916 -199.170036)
		(end 39.460424 -199.169528)
		(width 0.508)
		(layer "F.Cu")
		(net "PSU3_REMOTE_P")
	)
	(segment
		(start 35.53968 -199.170036)
		(end 39.459916 -199.170036)
		(width 0.508)
		(layer "F.Cu")
		(net "PSU3_REMOTE_P")
	)
	(via
		(at 79.988156 -60.493148)
		(size 0.508)
		(drill 0.254)
		(layers "F.Cu" "B.Cu")
		(net "T2_BLAD3_TXD")
	)
	(segment
		(start 25.442164 -115.976908)
		(end 19.832574 -110.367318)
		(width 0.127)
		(layer "In5.Cu")
		(net "T2_BLAD3_TXD")
	)
	(segment
		(start 19.832574 -110.367318)
		(end 19.832574 -93.280738)
		(width 0.127)
		(layer "In5.Cu")
		(net "T2_BLAD3_TXD")
	)
	(segment
		(start 84.758276 -55.723028)
		(end 84.758276 -51.606704)
		(width 0.127)
		(layer "In5.Cu")
		(net "T2_BLAD3_TXD")
	)
	(segment
		(start 8.099552 -221.419166)
		(end 9.750806 -221.419166)
		(width 0.127)
		(layer "In5.Cu")
		(net "T2_BLAD3_TXD")
	)
	(segment
		(start 10.129774 -221.040198)
		(end 10.129774 -203.450698)
		(width 0.127)
		(layer "In5.Cu")
		(net "T2_BLAD3_TXD")
	)
	(segment
		(start 15.136114 -198.444358)
		(end 15.136114 -173.90745)
		(width 0.127)
		(layer "In5.Cu")
		(net "T2_BLAD3_TXD")
	)
	(segment
		(start 78.21676 -62.264544)
		(end 79.988156 -60.493148)
		(width 0.127)
		(layer "In5.Cu")
		(net "T2_BLAD3_TXD")
	)
	(segment
		(start 77.406754 -62.264544)
		(end 78.21676 -62.264544)
		(width 0.127)
		(layer "In5.Cu")
		(net "T2_BLAD3_TXD")
	)
	(segment
		(start 1.948942 -222.670624)
		(end 1.951736 -222.66783)
		(width 0.127)
		(layer "In5.Cu")
		(net "T2_BLAD3_TXD")
	)
	(segment
		(start 4.64058 -222.442278)
		(end 7.07644 -222.442278)
		(width 0.127)
		(layer "In5.Cu")
		(net "T2_BLAD3_TXD")
	)
	(segment
		(start 19.832574 -93.280738)
		(end 25.294082 -87.81923)
		(width 0.127)
		(layer "In5.Cu")
		(net "T2_BLAD3_TXD")
	)
	(segment
		(start 1.951736 -222.66783)
		(end 4.415028 -222.66783)
		(width 0.127)
		(layer "In5.Cu")
		(net "T2_BLAD3_TXD")
	)
	(segment
		(start 10.129774 -203.450698)
		(end 15.136114 -198.444358)
		(width 0.127)
		(layer "In5.Cu")
		(net "T2_BLAD3_TXD")
	)
	(segment
		(start 9.750806 -221.419166)
		(end 10.129774 -221.040198)
		(width 0.127)
		(layer "In5.Cu")
		(net "T2_BLAD3_TXD")
	)
	(segment
		(start 7.07644 -222.442278)
		(end 8.099552 -221.419166)
		(width 0.127)
		(layer "In5.Cu")
		(net "T2_BLAD3_TXD")
	)
	(segment
		(start 25.294082 -87.81923)
		(end 51.852068 -87.81923)
		(width 0.127)
		(layer "In5.Cu")
		(net "T2_BLAD3_TXD")
	)
	(segment
		(start 51.852068 -87.81923)
		(end 77.406754 -62.264544)
		(width 0.127)
		(layer "In5.Cu")
		(net "T2_BLAD3_TXD")
	)
	(segment
		(start 25.442164 -163.6014)
		(end 25.442164 -115.976908)
		(width 0.127)
		(layer "In5.Cu")
		(net "T2_BLAD3_TXD")
	)
	(segment
		(start 4.415028 -222.66783)
		(end 4.64058 -222.442278)
		(width 0.127)
		(layer "In5.Cu")
		(net "T2_BLAD3_TXD")
	)
	(segment
		(start 79.988156 -60.493148)
		(end 84.758276 -55.723028)
		(width 0.127)
		(layer "In5.Cu")
		(net "T2_BLAD3_TXD")
	)
	(segment
		(start 84.758276 -51.606704)
		(end 85.63991 -50.72507)
		(width 0.127)
		(layer "In5.Cu")
		(net "T2_BLAD3_TXD")
	)
	(segment
		(start 15.136114 -173.90745)
		(end 25.442164 -163.6014)
		(width 0.127)
		(layer "In5.Cu")
		(net "T2_BLAD3_TXD")
	)
	(segment
		(start 39.454074 -110.769908)
		(end 39.458392 -110.774226)
		(width 0.4572)
		(layer "F.Cu")
		(net "PSU2_REMOTE_P")
	)
	(segment
		(start 35.53968 -110.769908)
		(end 39.454074 -110.769908)
		(width 0.4572)
		(layer "F.Cu")
		(net "PSU2_REMOTE_P")
	)
	(via
		(at 82.476086 -58.82132)
		(size 0.508)
		(drill 0.254)
		(layers "F.Cu" "B.Cu")
		(net "T2_BLAD3_RXD")
	)
	(segment
		(start 78.604872 -62.692534)
		(end 78.048358 -62.692534)
		(width 0.127)
		(layer "In5.Cu")
		(net "T2_BLAD3_RXD")
	)
	(segment
		(start 25.783794 -115.634008)
		(end 25.783794 -163.726876)
		(width 0.127)
		(layer "In5.Cu")
		(net "T2_BLAD3_RXD")
	)
	(segment
		(start 10.483342 -203.74737)
		(end 10.483342 -221.186502)
		(width 0.127)
		(layer "In5.Cu")
		(net "T2_BLAD3_RXD")
	)
	(segment
		(start 86.538816 -52.836572)
		(end 86.083394 -52.38115)
		(width 0.127)
		(layer "In5.Cu")
		(net "T2_BLAD3_RXD")
	)
	(segment
		(start 78.048358 -62.692534)
		(end 77.150214 -63.590678)
		(width 0.127)
		(layer "In5.Cu")
		(net "T2_BLAD3_RXD")
	)
	(segment
		(start 82.476086 -58.82132)
		(end 78.604872 -62.692534)
		(width 0.127)
		(layer "In5.Cu")
		(net "T2_BLAD3_RXD")
	)
	(segment
		(start 77.150214 -63.590678)
		(end 77.150214 -64.147192)
		(width 0.127)
		(layer "In5.Cu")
		(net "T2_BLAD3_RXD")
	)
	(segment
		(start 20.220432 -110.070646)
		(end 25.783794 -115.634008)
		(width 0.127)
		(layer "In5.Cu")
		(net "T2_BLAD3_RXD")
	)
	(segment
		(start 25.5651 -88.161622)
		(end 20.220432 -93.50629)
		(width 0.127)
		(layer "In5.Cu")
		(net "T2_BLAD3_RXD")
	)
	(segment
		(start 7.222998 -222.795592)
		(end 4.823968 -222.795592)
		(width 0.127)
		(layer "In5.Cu")
		(net "T2_BLAD3_RXD")
	)
	(segment
		(start 86.083394 -51.504596)
		(end 86.90991 -50.67808)
		(width 0.127)
		(layer "In5.Cu")
		(net "T2_BLAD3_RXD")
	)
	(segment
		(start 86.90991 -50.67808)
		(end 86.90991 -49.45507)
		(width 0.127)
		(layer "In5.Cu")
		(net "T2_BLAD3_RXD")
	)
	(segment
		(start 86.083394 -52.38115)
		(end 86.083394 -51.504596)
		(width 0.127)
		(layer "In5.Cu")
		(net "T2_BLAD3_RXD")
	)
	(segment
		(start 16.27886 -173.23181)
		(end 16.27886 -197.951852)
		(width 0.127)
		(layer "In5.Cu")
		(net "T2_BLAD3_RXD")
	)
	(segment
		(start 4.823968 -222.795592)
		(end 3.948938 -223.670622)
		(width 0.127)
		(layer "In5.Cu")
		(net "T2_BLAD3_RXD")
	)
	(segment
		(start 16.27886 -197.951852)
		(end 10.483342 -203.74737)
		(width 0.127)
		(layer "In5.Cu")
		(net "T2_BLAD3_RXD")
	)
	(segment
		(start 9.897364 -221.77248)
		(end 8.24611 -221.77248)
		(width 0.127)
		(layer "In5.Cu")
		(net "T2_BLAD3_RXD")
	)
	(segment
		(start 20.220432 -93.50629)
		(end 20.220432 -110.070646)
		(width 0.127)
		(layer "In5.Cu")
		(net "T2_BLAD3_RXD")
	)
	(segment
		(start 25.783794 -163.726876)
		(end 16.27886 -173.23181)
		(width 0.127)
		(layer "In5.Cu")
		(net "T2_BLAD3_RXD")
	)
	(segment
		(start 86.538816 -54.75859)
		(end 86.538816 -52.836572)
		(width 0.127)
		(layer "In5.Cu")
		(net "T2_BLAD3_RXD")
	)
	(segment
		(start 8.24611 -221.77248)
		(end 7.222998 -222.795592)
		(width 0.127)
		(layer "In5.Cu")
		(net "T2_BLAD3_RXD")
	)
	(segment
		(start 10.483342 -221.186502)
		(end 9.897364 -221.77248)
		(width 0.127)
		(layer "In5.Cu")
		(net "T2_BLAD3_RXD")
	)
	(segment
		(start 82.476086 -58.82132)
		(end 86.538816 -54.75859)
		(width 0.127)
		(layer "In5.Cu")
		(net "T2_BLAD3_RXD")
	)
	(segment
		(start 77.150214 -64.147192)
		(end 53.135784 -88.161622)
		(width 0.127)
		(layer "In5.Cu")
		(net "T2_BLAD3_RXD")
	)
	(segment
		(start 53.135784 -88.161622)
		(end 25.5651 -88.161622)
		(width 0.127)
		(layer "In5.Cu")
		(net "T2_BLAD3_RXD")
	)
	(via
		(at 81.524094 -63.52667)
		(size 0.508)
		(drill 0.254)
		(layers "F.Cu" "B.Cu")
		(net "T2_BLAD3_EN")
	)
	(segment
		(start 8.099044 -231.463088)
		(end 7.137146 -232.424986)
		(width 0.127)
		(layer "In2.Cu")
		(net "T2_BLAD3_EN")
	)
	(segment
		(start 28.642818 -99.804982)
		(end 27.98699 -100.46081)
		(width 0.127)
		(layer "In2.Cu")
		(net "T2_BLAD3_EN")
	)
	(segment
		(start 4.703318 -232.424986)
		(end 3.948938 -231.670606)
		(width 0.127)
		(layer "In2.Cu")
		(net "T2_BLAD3_EN")
	)
	(segment
		(start 11.264138 -231.463088)
		(end 8.099044 -231.463088)
		(width 0.127)
		(layer "In2.Cu")
		(net "T2_BLAD3_EN")
	)
	(segment
		(start 28.642818 -92.565474)
		(end 28.642818 -99.804982)
		(width 0.127)
		(layer "In2.Cu")
		(net "T2_BLAD3_EN")
	)
	(segment
		(start 88.978486 -52.827428)
		(end 88.600026 -52.448968)
		(width 0.127)
		(layer "In2.Cu")
		(net "T2_BLAD3_EN")
	)
	(segment
		(start 27.98699 -100.46081)
		(end 27.98699 -105.427272)
		(width 0.127)
		(layer "In2.Cu")
		(net "T2_BLAD3_EN")
	)
	(segment
		(start 7.137146 -232.424986)
		(end 4.703318 -232.424986)
		(width 0.127)
		(layer "In2.Cu")
		(net "T2_BLAD3_EN")
	)
	(segment
		(start 81.524094 -63.52667)
		(end 54.654958 -90.395806)
		(width 0.127)
		(layer "In2.Cu")
		(net "T2_BLAD3_EN")
	)
	(segment
		(start 28.642818 -111.126016)
		(end 28.64231 -111.126524)
		(width 0.127)
		(layer "In2.Cu")
		(net "T2_BLAD3_EN")
	)
	(segment
		(start 23.075646 -219.65158)
		(end 11.264138 -231.463088)
		(width 0.127)
		(layer "In2.Cu")
		(net "T2_BLAD3_EN")
	)
	(segment
		(start 19.252438 -197.48119)
		(end 23.075646 -201.304398)
		(width 0.127)
		(layer "In2.Cu")
		(net "T2_BLAD3_EN")
	)
	(segment
		(start 54.654958 -90.395806)
		(end 30.812486 -90.395806)
		(width 0.127)
		(layer "In2.Cu")
		(net "T2_BLAD3_EN")
	)
	(segment
		(start 88.600026 -51.145186)
		(end 88.17991 -50.72507)
		(width 0.127)
		(layer "In2.Cu")
		(net "T2_BLAD3_EN")
	)
	(segment
		(start 87.971376 -57.079388)
		(end 87.971376 -54.965346)
		(width 0.127)
		(layer "In2.Cu")
		(net "T2_BLAD3_EN")
	)
	(segment
		(start 28.642818 -106.0831)
		(end 28.642818 -111.126016)
		(width 0.127)
		(layer "In2.Cu")
		(net "T2_BLAD3_EN")
	)
	(segment
		(start 27.98699 -105.427272)
		(end 28.642818 -106.0831)
		(width 0.127)
		(layer "In2.Cu")
		(net "T2_BLAD3_EN")
	)
	(segment
		(start 19.252438 -183.731662)
		(end 19.252438 -197.48119)
		(width 0.127)
		(layer "In2.Cu")
		(net "T2_BLAD3_EN")
	)
	(segment
		(start 81.524094 -63.52667)
		(end 87.971376 -57.079388)
		(width 0.127)
		(layer "In2.Cu")
		(net "T2_BLAD3_EN")
	)
	(segment
		(start 88.978486 -53.958236)
		(end 88.978486 -52.827428)
		(width 0.127)
		(layer "In2.Cu")
		(net "T2_BLAD3_EN")
	)
	(segment
		(start 23.075646 -201.304398)
		(end 23.075646 -219.65158)
		(width 0.127)
		(layer "In2.Cu")
		(net "T2_BLAD3_EN")
	)
	(segment
		(start 28.64231 -174.34179)
		(end 19.252438 -183.731662)
		(width 0.127)
		(layer "In2.Cu")
		(net "T2_BLAD3_EN")
	)
	(segment
		(start 30.812486 -90.395806)
		(end 28.642818 -92.565474)
		(width 0.127)
		(layer "In2.Cu")
		(net "T2_BLAD3_EN")
	)
	(segment
		(start 88.600026 -52.448968)
		(end 88.600026 -51.145186)
		(width 0.127)
		(layer "In2.Cu")
		(net "T2_BLAD3_EN")
	)
	(segment
		(start 87.971376 -54.965346)
		(end 88.978486 -53.958236)
		(width 0.127)
		(layer "In2.Cu")
		(net "T2_BLAD3_EN")
	)
	(segment
		(start 28.64231 -111.126524)
		(end 28.64231 -174.34179)
		(width 0.127)
		(layer "In2.Cu")
		(net "T2_BLAD3_EN")
	)
	(segment
		(start 51.124612 -285.205424)
		(end 52.07762 -285.205424)
		(width 0.6604)
		(layer "F.Cu")
		(net "P12V")
	)
	(segment
		(start 52.07762 -285.205424)
		(end 53.030628 -285.205424)
		(width 0.6604)
		(layer "F.Cu")
		(net "P12V")
	)
	(segment
		(start 50.670714 -374.437148)
		(end 51.623722 -374.437148)
		(width 0.6604)
		(layer "F.Cu")
		(net "P12V")
	)
	(segment
		(start 51.967384 -173.13783)
		(end 52.920392 -173.13783)
		(width 0.6604)
		(layer "F.Cu")
		(net "P12V")
	)
	(segment
		(start 51.01463 -84.273644)
		(end 51.967638 -84.273644)
		(width 0.6604)
		(layer "F.Cu")
		(net "P12V")
	)
	(segment
		(start 52.29987 -507.67742)
		(end 53.252878 -507.67742)
		(width 0.6604)
		(layer "F.Cu")
		(net "P12V")
	)
	(segment
		(start 51.900328 -349.812356)
		(end 51.900328 -350.765364)
		(width 0.6604)
		(layer "F.Cu")
		(net "P12V")
	)
	(segment
		(start 52.29987 -507.67742)
		(end 52.29987 -508.630428)
		(width 0.6604)
		(layer "F.Cu")
		(net "P12V")
	)
	(segment
		(start 52.100988 -305.430174)
		(end 52.100988 -306.383182)
		(width 0.6604)
		(layer "F.Cu")
		(net "P12V")
	)
	(segment
		(start 51.967638 -83.320636)
		(end 51.967638 -84.273644)
		(width 0.6604)
		(layer "F.Cu")
		(net "P12V")
	)
	(segment
		(start 52.14874 -519.020552)
		(end 52.14874 -519.97356)
		(width 0.6604)
		(layer "F.Cu")
		(net "P12V")
	)
	(segment
		(start 53.363114 -240.589308)
		(end 53.363114 -241.542316)
		(width 0.6604)
		(layer "F.Cu")
		(net "P12V")
	)
	(segment
		(start 51.275996 -196.729604)
		(end 52.229004 -196.729604)
		(width 0.6604)
		(layer "F.Cu")
		(net "P12V")
	)
	(segment
		(start 52.14874 -519.020552)
		(end 53.101748 -519.020552)
		(width 0.6604)
		(layer "F.Cu")
		(net "P12V")
	)
	(segment
		(start 52.168044 -216.532968)
		(end 52.168044 -217.485976)
		(width 0.6604)
		(layer "F.Cu")
		(net "P12V")
	)
	(segment
		(start 51.967638 -84.273644)
		(end 52.920646 -84.273644)
		(width 0.6604)
		(layer "F.Cu")
		(net "P12V")
	)
	(segment
		(start 51.699668 -17.615662)
		(end 51.699668 -18.56867)
		(width 0.6604)
		(layer "F.Cu")
		(net "P12V")
	)
	(segment
		(start 51.21529 -439.763154)
		(end 52.168298 -439.763154)
		(width 0.6604)
		(layer "F.Cu")
		(net "P12V")
	)
	(segment
		(start 50.89779 -62.882272)
		(end 51.850798 -62.882272)
		(width 0.6604)
		(layer "F.Cu")
		(net "P12V")
	)
	(segment
		(start 51.081178 -395.548358)
		(end 52.034186 -395.548358)
		(width 0.6604)
		(layer "F.Cu")
		(net "P12V")
	)
	(segment
		(start 52.14874 -462.14665)
		(end 52.14874 -463.099658)
		(width 0.6604)
		(layer "F.Cu")
		(net "P12V")
	)
	(segment
		(start 51.014376 -173.13783)
		(end 51.967384 -173.13783)
		(width 0.6604)
		(layer "F.Cu")
		(net "P12V")
	)
	(segment
		(start 50.880518 -38.6207)
		(end 51.833526 -38.6207)
		(width 0.6604)
		(layer "F.Cu")
		(net "P12V")
	)
	(segment
		(start 51.833526 -38.6207)
		(end 51.833526 -39.573708)
		(width 0.6604)
		(layer "F.Cu")
		(net "P12V")
	)
	(segment
		(start 51.699414 -106.16692)
		(end 51.699414 -107.119928)
		(width 0.6604)
		(layer "F.Cu")
		(net "P12V")
	)
	(segment
		(start 51.850798 -61.929264)
		(end 51.850798 -62.882272)
		(width 0.6604)
		(layer "F.Cu")
		(net "P12V")
	)
	(segment
		(start 52.168298 -439.763154)
		(end 52.168298 -440.716162)
		(width 0.6604)
		(layer "F.Cu")
		(net "P12V")
	)
	(segment
		(start 40.273986 -22.379432)
		(end 40.980106 -22.379432)
		(width 0.4572)
		(layer "F.Cu")
		(net "P12V")
	)
	(segment
		(start 52.07762 -285.205424)
		(end 52.07762 -286.158432)
		(width 0.6604)
		(layer "F.Cu")
		(net "P12V")
	)
	(segment
		(start 51.699668 -18.56867)
		(end 51.699668 -19.521678)
		(width 0.6604)
		(layer "F.Cu")
		(net "P12V")
	)
	(segment
		(start 50.746406 -107.119928)
		(end 51.699414 -107.119928)
		(width 0.6604)
		(layer "F.Cu")
		(net "P12V")
	)
	(segment
		(start 51.351434 -418.636958)
		(end 52.304442 -418.636958)
		(width 0.6604)
		(layer "F.Cu")
		(net "P12V")
	)
	(segment
		(start 53.363114 -240.589308)
		(end 54.316122 -240.589308)
		(width 0.6604)
		(layer "F.Cu")
		(net "P12V")
	)
	(segment
		(start 52.229004 -196.729604)
		(end 53.182012 -196.729604)
		(width 0.6604)
		(layer "F.Cu")
		(net "P12V")
	)
	(segment
		(start 51.275996 -329.972416)
		(end 52.229004 -329.972416)
		(width 0.6604)
		(layer "F.Cu")
		(net "P12V")
	)
	(segment
		(start 73.332848 -473.59951)
		(end 74.323956 -473.59951)
		(width 0.4572)
		(layer "F.Cu")
		(net "P12V")
	)
	(segment
		(start 52.493672 -151.92502)
		(end 53.44668 -151.92502)
		(width 0.6604)
		(layer "F.Cu")
		(net "P12V")
	)
	(segment
		(start 81.347056 -297.892216)
		(end 82.144362 -297.892216)
		(width 0.4572)
		(layer "F.Cu")
		(net "P12V")
	)
	(segment
		(start 51.623722 -374.437148)
		(end 51.623722 -375.390156)
		(width 0.6604)
		(layer "F.Cu")
		(net "P12V")
	)
	(segment
		(start 52.168044 -217.485976)
		(end 52.168044 -218.438984)
		(width 0.6604)
		(layer "F.Cu")
		(net "P12V")
	)
	(segment
		(start 52.208176 -262.266176)
		(end 53.161184 -262.266176)
		(width 0.6604)
		(layer "F.Cu")
		(net "P12V")
	)
	(segment
		(start 52.07762 -284.252416)
		(end 52.07762 -285.205424)
		(width 0.6604)
		(layer "F.Cu")
		(net "P12V")
	)
	(segment
		(start 51.833526 -38.6207)
		(end 52.786534 -38.6207)
		(width 0.6604)
		(layer "F.Cu")
		(net "P12V")
	)
	(segment
		(start 51.346862 -507.67742)
		(end 52.29987 -507.67742)
		(width 0.6604)
		(layer "F.Cu")
		(net "P12V")
	)
	(segment
		(start 52.034186 -395.548358)
		(end 52.034186 -396.501366)
		(width 0.6604)
		(layer "F.Cu")
		(net "P12V")
	)
	(segment
		(start 50.880518 -482.70668)
		(end 51.833526 -482.70668)
		(width 0.6604)
		(layer "F.Cu")
		(net "P12V")
	)
	(segment
		(start 51.900582 -128.655318)
		(end 52.85359 -128.655318)
		(width 0.6604)
		(layer "F.Cu")
		(net "P12V")
	)
	(segment
		(start 52.304442 -418.636958)
		(end 53.25745 -418.636958)
		(width 0.6604)
		(layer "F.Cu")
		(net "P12V")
	)
	(segment
		(start 53.161184 -262.266176)
		(end 54.114192 -262.266176)
		(width 0.6604)
		(layer "F.Cu")
		(net "P12V")
	)
	(segment
		(start 51.850798 -62.882272)
		(end 51.850798 -63.83528)
		(width 0.6604)
		(layer "F.Cu")
		(net "P12V")
	)
	(segment
		(start 52.229004 -329.019408)
		(end 52.229004 -329.972416)
		(width 0.6604)
		(layer "F.Cu")
		(net "P12V")
	)
	(segment
		(start 52.034186 -395.548358)
		(end 52.987194 -395.548358)
		(width 0.6604)
		(layer "F.Cu")
		(net "P12V")
	)
	(segment
		(start 40.258492 -110.774226)
		(end 41.025318 -110.774226)
		(width 0.4572)
		(layer "F.Cu")
		(net "P12V")
	)
	(segment
		(start 51.14798 -306.383182)
		(end 52.100988 -306.383182)
		(width 0.6604)
		(layer "F.Cu")
		(net "P12V")
	)
	(segment
		(start 52.229004 -329.972416)
		(end 53.182012 -329.972416)
		(width 0.6604)
		(layer "F.Cu")
		(net "P12V")
	)
	(segment
		(start 40.263826 -199.171814)
		(end 41.015666 -199.171814)
		(width 0.4572)
		(layer "F.Cu")
		(net "P12V")
	)
	(segment
		(start 51.900582 -127.70231)
		(end 51.900582 -128.655318)
		(width 0.6604)
		(layer "F.Cu")
		(net "P12V")
	)
	(segment
		(start 51.833526 -482.70668)
		(end 51.833526 -483.659688)
		(width 0.6604)
		(layer "F.Cu")
		(net "P12V")
	)
	(segment
		(start 50.947574 -128.655318)
		(end 51.900582 -128.655318)
		(width 0.6604)
		(layer "F.Cu")
		(net "P12V")
	)
	(segment
		(start 50.74666 -18.56867)
		(end 51.699668 -18.56867)
		(width 0.6604)
		(layer "F.Cu")
		(net "P12V")
	)
	(segment
		(start 51.833526 -37.667692)
		(end 51.833526 -38.6207)
		(width 0.6604)
		(layer "F.Cu")
		(net "P12V")
	)
	(segment
		(start 52.229004 -195.776596)
		(end 52.229004 -196.729604)
		(width 0.6604)
		(layer "F.Cu")
		(net "P12V")
	)
	(segment
		(start 52.493672 -151.92502)
		(end 52.493672 -152.878028)
		(width 0.6604)
		(layer "F.Cu")
		(net "P12V")
	)
	(segment
		(start 52.168298 -438.810146)
		(end 52.168298 -439.763154)
		(width 0.6604)
		(layer "F.Cu")
		(net "P12V")
	)
	(segment
		(start 51.540664 -151.92502)
		(end 52.493672 -151.92502)
		(width 0.6604)
		(layer "F.Cu")
		(net "P12V")
	)
	(segment
		(start 51.699414 -107.119928)
		(end 52.652422 -107.119928)
		(width 0.6604)
		(layer "F.Cu")
		(net "P12V")
	)
	(segment
		(start 51.195732 -519.020552)
		(end 52.14874 -519.020552)
		(width 0.6604)
		(layer "F.Cu")
		(net "P12V")
	)
	(segment
		(start 17.213326 -449.79209)
		(end 18.211546 -449.79209)
		(width 1.016)
		(layer "F.Cu")
		(net "P12V")
	)
	(segment
		(start 51.699668 -18.56867)
		(end 52.652676 -18.56867)
		(width 0.6604)
		(layer "F.Cu")
		(net "P12V")
	)
	(segment
		(start 51.900582 -128.655318)
		(end 51.900582 -129.608326)
		(width 0.6604)
		(layer "F.Cu")
		(net "P12V")
	)
	(segment
		(start 51.967384 -172.184822)
		(end 51.967384 -173.13783)
		(width 0.6604)
		(layer "F.Cu")
		(net "P12V")
	)
	(segment
		(start 52.304442 -418.636958)
		(end 52.304442 -419.589966)
		(width 0.6604)
		(layer "F.Cu")
		(net "P12V")
	)
	(segment
		(start 52.493672 -150.972012)
		(end 52.493672 -151.92502)
		(width 0.6604)
		(layer "F.Cu")
		(net "P12V")
	)
	(segment
		(start 53.363114 -239.6363)
		(end 53.363114 -240.589308)
		(width 0.6604)
		(layer "F.Cu")
		(net "P12V")
	)
	(segment
		(start 53.161184 -261.313168)
		(end 53.161184 -262.266176)
		(width 0.6604)
		(layer "F.Cu")
		(net "P12V")
	)
	(segment
		(start 51.699414 -107.119928)
		(end 51.699414 -108.072936)
		(width 0.6604)
		(layer "F.Cu")
		(net "P12V")
	)
	(segment
		(start 52.304442 -417.68395)
		(end 52.304442 -418.636958)
		(width 0.6604)
		(layer "F.Cu")
		(net "P12V")
	)
	(segment
		(start 19.145504 -450.726048)
		(end 19.145504 -452.257922)
		(width 0.5588)
		(layer "F.Cu")
		(net "P12V")
	)
	(segment
		(start 52.29987 -506.724412)
		(end 52.29987 -507.67742)
		(width 0.6604)
		(layer "F.Cu")
		(net "P12V")
	)
	(segment
		(start 51.833526 -482.70668)
		(end 52.786534 -482.70668)
		(width 0.6604)
		(layer "F.Cu")
		(net "P12V")
	)
	(segment
		(start 51.833526 -481.753672)
		(end 51.833526 -482.70668)
		(width 0.6604)
		(layer "F.Cu")
		(net "P12V")
	)
	(segment
		(start 51.900328 -350.765364)
		(end 51.900328 -351.718372)
		(width 0.6604)
		(layer "F.Cu")
		(net "P12V")
	)
	(segment
		(start 52.100988 -306.383182)
		(end 53.053996 -306.383182)
		(width 0.6604)
		(layer "F.Cu")
		(net "P12V")
	)
	(segment
		(start 52.14874 -518.067544)
		(end 52.14874 -519.020552)
		(width 0.6604)
		(layer "F.Cu")
		(net "P12V")
	)
	(segment
		(start 18.211546 -449.79209)
		(end 19.145504 -450.726048)
		(width 1.016)
		(layer "F.Cu")
		(net "P12V")
	)
	(segment
		(start 52.14874 -463.099658)
		(end 52.14874 -464.052666)
		(width 0.6604)
		(layer "F.Cu")
		(net "P12V")
	)
	(segment
		(start 52.100988 -306.383182)
		(end 52.100988 -307.33619)
		(width 0.6604)
		(layer "F.Cu")
		(net "P12V")
	)
	(segment
		(start 52.168044 -217.485976)
		(end 53.121052 -217.485976)
		(width 0.6604)
		(layer "F.Cu")
		(net "P12V")
	)
	(segment
		(start 51.195732 -463.099658)
		(end 52.14874 -463.099658)
		(width 0.6604)
		(layer "F.Cu")
		(net "P12V")
	)
	(segment
		(start 51.215036 -217.485976)
		(end 52.168044 -217.485976)
		(width 0.6604)
		(layer "F.Cu")
		(net "P12V")
	)
	(segment
		(start 51.900328 -350.765364)
		(end 52.853336 -350.765364)
		(width 0.6604)
		(layer "F.Cu")
		(net "P12V")
	)
	(segment
		(start 52.14874 -463.099658)
		(end 53.101748 -463.099658)
		(width 0.6604)
		(layer "F.Cu")
		(net "P12V")
	)
	(segment
		(start 50.94732 -350.765364)
		(end 51.900328 -350.765364)
		(width 0.6604)
		(layer "F.Cu")
		(net "P12V")
	)
	(segment
		(start 51.850798 -62.882272)
		(end 52.803806 -62.882272)
		(width 0.6604)
		(layer "F.Cu")
		(net "P12V")
	)
	(segment
		(start 52.410106 -240.589308)
		(end 53.363114 -240.589308)
		(width 0.6604)
		(layer "F.Cu")
		(net "P12V")
	)
	(segment
		(start 52.229004 -196.729604)
		(end 52.229004 -197.682612)
		(width 0.6604)
		(layer "F.Cu")
		(net "P12V")
	)
	(segment
		(start 51.967638 -84.273644)
		(end 51.967638 -85.226652)
		(width 0.6604)
		(layer "F.Cu")
		(net "P12V")
	)
	(segment
		(start 52.034186 -394.59535)
		(end 52.034186 -395.548358)
		(width 0.6604)
		(layer "F.Cu")
		(net "P12V")
	)
	(segment
		(start 40.336724 -464.36915)
		(end 41.108376 -464.36915)
		(width 0.4572)
		(layer "F.Cu")
		(net "P12V")
	)
	(segment
		(start 51.967384 -173.13783)
		(end 51.967384 -174.090838)
		(width 0.6604)
		(layer "F.Cu")
		(net "P12V")
	)
	(segment
		(start 52.229004 -329.972416)
		(end 52.229004 -330.925424)
		(width 0.6604)
		(layer "F.Cu")
		(net "P12V")
	)
	(segment
		(start 51.623722 -374.437148)
		(end 52.57673 -374.437148)
		(width 0.6604)
		(layer "F.Cu")
		(net "P12V")
	)
	(segment
		(start 53.161184 -262.266176)
		(end 53.161184 -263.219184)
		(width 0.6604)
		(layer "F.Cu")
		(net "P12V")
	)
	(segment
		(start 51.623722 -373.48414)
		(end 51.623722 -374.437148)
		(width 0.6604)
		(layer "F.Cu")
		(net "P12V")
	)
	(segment
		(start 52.168298 -439.763154)
		(end 53.121306 -439.763154)
		(width 0.6604)
		(layer "F.Cu")
		(net "P12V")
	)
	(via
		(at 66.740786 -428.525432)
		(size 0.508)
		(drill 0.254)
		(layers "F.Cu" "B.Cu")
		(net "P12V")
	)
	(via
		(at 59.870086 -288.39541)
		(size 0.508)
		(drill 0.254)
		(layers "F.Cu" "B.Cu")
		(net "P12V")
	)
	(via
		(at 78.695042 -374.131078)
		(size 0.508)
		(drill 0.254)
		(layers "F.Cu" "B.Cu")
		(net "P12V")
	)
	(via
		(at 71.057516 -11.575288)
		(size 0.508)
		(drill 0.254)
		(layers "F.Cu" "B.Cu")
		(net "P12V")
	)
	(via
		(at 64.625982 -285.688024)
		(size 0.508)
		(drill 0.254)
		(layers "F.Cu" "B.Cu")
		(net "P12V")
	)
	(via
		(at 69.428868 -419.65372)
		(size 0.508)
		(drill 0.254)
		(layers "F.Cu" "B.Cu")
		(net "P12V")
	)
	(via
		(at 64.855598 -521.035788)
		(size 0.508)
		(drill 0.254)
		(layers "F.Cu" "B.Cu")
		(net "P12V")
	)
	(via
		(at 78.015084 -170.627802)
		(size 0.508)
		(drill 0.254)
		(layers "F.Cu" "B.Cu")
		(net "P12V")
	)
	(via
		(at 73.550526 -135.321548)
		(size 0.508)
		(drill 0.254)
		(layers "F.Cu" "B.Cu")
		(net "P12V")
	)
	(via
		(at 57.549542 -525.142206)
		(size 0.508)
		(drill 0.254)
		(layers "F.Cu" "B.Cu")
		(net "P12V")
	)
	(via
		(at 75.15733 -374.130316)
		(size 0.508)
		(drill 0.254)
		(layers "F.Cu" "B.Cu")
		(net "P12V")
	)
	(via
		(at 66.410586 -465.61629)
		(size 0.508)
		(drill 0.254)
		(layers "F.Cu" "B.Cu")
		(net "P12V")
	)
	(via
		(at 70.496176 -241.133376)
		(size 0.508)
		(drill 0.254)
		(layers "F.Cu" "B.Cu")
		(net "P12V")
	)
	(via
		(at 64.855598 -522.9987)
		(size 0.508)
		(drill 0.254)
		(layers "F.Cu" "B.Cu")
		(net "P12V")
	)
	(via
		(at 67.860164 -156.832046)
		(size 0.508)
		(drill 0.254)
		(layers "F.Cu" "B.Cu")
		(net "P12V")
	)
	(via
		(at 67.57416 -100.744274)
		(size 0.508)
		(drill 0.254)
		(layers "F.Cu" "B.Cu")
		(net "P12V")
	)
	(via
		(at 73.177908 -17.386046)
		(size 0.508)
		(drill 0.254)
		(layers "F.Cu" "B.Cu")
		(net "P12V")
	)
	(via
		(at 40.256968 -432.758088)
		(size 0.508)
		(drill 0.254)
		(layers "F.Cu" "B.Cu")
		(net "P12V")
	)
	(via
		(at 77.461364 -133.133338)
		(size 0.508)
		(drill 0.254)
		(layers "F.Cu" "B.Cu")
		(net "P12V")
	)
	(via
		(at 61.615828 -518.66419)
		(size 0.508)
		(drill 0.254)
		(layers "F.Cu" "B.Cu")
		(net "P12V")
	)
	(via
		(at 67.467734 -247.494044)
		(size 0.508)
		(drill 0.254)
		(layers "F.Cu" "B.Cu")
		(net "P12V")
	)
	(via
		(at 66.410586 -467.38286)
		(size 0.508)
		(drill 0.254)
		(layers "F.Cu" "B.Cu")
		(net "P12V")
	)
	(via
		(at 62.885828 -525.142206)
		(size 0.508)
		(drill 0.254)
		(layers "F.Cu" "B.Cu")
		(net "P12V")
	)
	(via
		(at 70.7136 -393.24026)
		(size 0.508)
		(drill 0.254)
		(layers "F.Cu" "B.Cu")
		(net "P12V")
	)
	(via
		(at 66.278506 -389.671306)
		(size 0.508)
		(drill 0.254)
		(layers "F.Cu" "B.Cu")
		(net "P12V")
	)
	(via
		(at 80.81518 -260.878574)
		(size 0.508)
		(drill 0.254)
		(layers "F.Cu" "B.Cu")
		(net "P12V")
	)
	(via
		(at 66.160142 -285.651702)
		(size 0.508)
		(drill 0.254)
		(layers "F.Cu" "B.Cu")
		(net "P12V")
	)
	(via
		(at 42.15765 -75.21956)
		(size 0.508)
		(drill 0.254)
		(layers "F.Cu" "B.Cu")
		(net "P12V")
	)
	(via
		(at 69.734176 -245.644924)
		(size 0.508)
		(drill 0.254)
		(layers "F.Cu" "B.Cu")
		(net "P12V")
	)
	(via
		(at 60.552584 -219.173298)
		(size 0.508)
		(drill 0.254)
		(layers "F.Cu" "B.Cu")
		(net "P12V")
	)
	(via
		(at 62.73292 -193.67754)
		(size 0.508)
		(drill 0.254)
		(layers "F.Cu" "B.Cu")
		(net "P12V")
	)
	(via
		(at 40.322246 -343.981278)
		(size 0.508)
		(drill 0.254)
		(layers "F.Cu" "B.Cu")
		(net "P12V")
	)
	(via
		(at 60.640214 -41.831768)
		(size 0.508)
		(drill 0.254)
		(layers "F.Cu" "B.Cu")
		(net "P12V")
	)
	(via
		(at 78.79461 -487.001312)
		(size 0.508)
		(drill 0.254)
		(layers "F.Cu" "B.Cu")
		(net "P12V")
	)
	(via
		(at 42.341546 -252.461776)
		(size 0.508)
		(drill 0.254)
		(layers "F.Cu" "B.Cu")
		(net "P12V")
	)
	(via
		(at 67.207384 -65.976246)
		(size 0.508)
		(drill 0.254)
		(layers "F.Cu" "B.Cu")
		(net "P12V")
	)
	(via
		(at 67.57416 -106.083354)
		(size 0.508)
		(drill 0.254)
		(layers "F.Cu" "B.Cu")
		(net "P12V")
	)
	(via
		(at 40.322246 -339.87486)
		(size 0.508)
		(drill 0.254)
		(layers "F.Cu" "B.Cu")
		(net "P12V")
	)
	(via
		(at 57.8358 -39.868856)
		(size 0.508)
		(drill 0.254)
		(layers "F.Cu" "B.Cu")
		(net "P12V")
	)
	(via
		(at 39.560246 -341.837772)
		(size 0.508)
		(drill 0.254)
		(layers "F.Cu" "B.Cu")
		(net "P12V")
	)
	(via
		(at 65.242694 -39.106856)
		(size 0.508)
		(drill 0.254)
		(layers "F.Cu" "B.Cu")
		(net "P12V")
	)
	(via
		(at 80.057498 -172.9994)
		(size 0.508)
		(drill 0.254)
		(layers "F.Cu" "B.Cu")
		(net "P12V")
	)
	(via
		(at 63.863982 -291.027104)
		(size 0.508)
		(drill 0.254)
		(layers "F.Cu" "B.Cu")
		(net "P12V")
	)
	(via
		(at 64.215772 -64.013334)
		(size 0.508)
		(drill 0.254)
		(layers "F.Cu" "B.Cu")
		(net "P12V")
	)
	(via
		(at 61.615828 -513.32511)
		(size 0.508)
		(drill 0.254)
		(layers "F.Cu" "B.Cu")
		(net "P12V")
	)
	(via
		(at 67.827398 -467.383622)
		(size 0.508)
		(drill 0.254)
		(layers "F.Cu" "B.Cu")
		(net "P12V")
	)
	(via
		(at 56.433212 -338.409534)
		(size 0.508)
		(drill 0.254)
		(layers "F.Cu" "B.Cu")
		(net "P12V")
	)
	(via
		(at 66.125598 -518.66419)
		(size 0.508)
		(drill 0.254)
		(layers "F.Cu" "B.Cu")
		(net "P12V")
	)
	(via
		(at 41.018968 -426.280072)
		(size 0.508)
		(drill 0.254)
		(layers "F.Cu" "B.Cu")
		(net "P12V")
	)
	(via
		(at 68.979288 -13.955776)
		(size 0.508)
		(drill 0.254)
		(layers "F.Cu" "B.Cu")
		(net "P12V")
	)
	(via
		(at 60.895484 -104.239822)
		(size 0.508)
		(drill 0.254)
		(layers "F.Cu" "B.Cu")
		(net "P12V")
	)
	(via
		(at 65.537334 -195.821046)
		(size 0.508)
		(drill 0.254)
		(layers "F.Cu" "B.Cu")
		(net "P12V")
	)
	(via
		(at 58.811414 -515.99592)
		(size 0.508)
		(drill 0.254)
		(layers "F.Cu" "B.Cu")
		(net "P12V")
	)
	(via
		(at 61.639958 -291.06368)
		(size 0.508)
		(drill 0.254)
		(layers "F.Cu" "B.Cu")
		(net "P12V")
	)
	(via
		(at 39.560246 -334.834992)
		(size 0.508)
		(drill 0.254)
		(layers "F.Cu" "B.Cu")
		(net "P12V")
	)
	(via
		(at 67.84721 -522.9987)
		(size 0.508)
		(drill 0.254)
		(layers "F.Cu" "B.Cu")
		(net "P12V")
	)
	(via
		(at 67.467734 -251.600462)
		(size 0.508)
		(drill 0.254)
		(layers "F.Cu" "B.Cu")
		(net "P12V")
	)
	(via
		(at 63.936372 -433.5653)
		(size 0.508)
		(drill 0.254)
		(layers "F.Cu" "B.Cu")
		(net "P12V")
	)
	(via
		(at 77.187044 -379.46838)
		(size 0.508)
		(drill 0.254)
		(layers "F.Cu" "B.Cu")
		(net "P12V")
	)
	(via
		(at 42.15765 -72.847962)
		(size 0.508)
		(drill 0.254)
		(layers "F.Cu" "B.Cu")
		(net "P12V")
	)
	(via
		(at 60.201048 -191.714628)
		(size 0.508)
		(drill 0.254)
		(layers "F.Cu" "B.Cu")
		(net "P12V")
	)
	(via
		(at 67.975988 -328.5363)
		(size 0.508)
		(drill 0.254)
		(layers "F.Cu" "B.Cu")
		(net "P12V")
	)
	(via
		(at 55.303928 -41.831768)
		(size 0.508)
		(drill 0.254)
		(layers "F.Cu" "B.Cu")
		(net "P12V")
	)
	(via
		(at 39.947088 -162.850576)
		(size 0.508)
		(drill 0.254)
		(layers "F.Cu" "B.Cu")
		(net "P12V")
	)
	(via
		(at 60.081414 -521.035788)
		(size 0.508)
		(drill 0.254)
		(layers "F.Cu" "B.Cu")
		(net "P12V")
	)
	(via
		(at 76.470764 -370.607082)
		(size 0.508)
		(drill 0.254)
		(layers "F.Cu" "B.Cu")
		(net "P12V")
	)
	(via
		(at 60.640214 -39.106856)
		(size 0.508)
		(drill 0.254)
		(layers "F.Cu" "B.Cu")
		(net "P12V")
	)
	(via
		(at 40.256968 -423.611802)
		(size 0.508)
		(drill 0.254)
		(layers "F.Cu" "B.Cu")
		(net "P12V")
	)
	(via
		(at 78.603856 -377.702572)
		(size 0.508)
		(drill 0.254)
		(layers "F.Cu" "B.Cu")
		(net "P12V")
	)
	(via
		(at 59.439048 -195.821046)
		(size 0.508)
		(drill 0.254)
		(layers "F.Cu" "B.Cu")
		(net "P12V")
	)
	(via
		(at 80.057498 -174.962312)
		(size 0.508)
		(drill 0.254)
		(layers "F.Cu" "B.Cu")
		(net "P12V")
	)
	(via
		(at 70.089776 -154.68854)
		(size 0.508)
		(drill 0.254)
		(layers "F.Cu" "B.Cu")
		(net "P12V")
	)
	(via
		(at 60.6044 -332.466696)
		(size 0.508)
		(drill 0.254)
		(layers "F.Cu" "B.Cu")
		(net "P12V")
	)
	(via
		(at 77.461364 -135.276844)
		(size 0.508)
		(drill 0.254)
		(layers "F.Cu" "B.Cu")
		(net "P12V")
	)
	(via
		(at 79.702914 -131.242816)
		(size 0.508)
		(drill 0.254)
		(layers "F.Cu" "B.Cu")
		(net "P12V")
	)
	(via
		(at 70.851776 -152.725628)
		(size 0.508)
		(drill 0.254)
		(layers "F.Cu" "B.Cu")
		(net "P12V")
	)
	(via
		(at 55.680356 -326.967088)
		(size 0.508)
		(drill 0.254)
		(layers "F.Cu" "B.Cu")
		(net "P12V")
	)
	(via
		(at 80.057498 -170.627802)
		(size 0.508)
		(drill 0.254)
		(layers "F.Cu" "B.Cu")
		(net "P12V")
	)
	(via
		(at 41.018968 -428.65167)
		(size 0.508)
		(drill 0.254)
		(layers "F.Cu" "B.Cu")
		(net "P12V")
	)
	(via
		(at 63.013082 -43.975274)
		(size 0.508)
		(drill 0.254)
		(layers "F.Cu" "B.Cu")
		(net "P12V")
	)
	(via
		(at 79.457042 -370.607844)
		(size 0.508)
		(drill 0.254)
		(layers "F.Cu" "B.Cu")
		(net "P12V")
	)
	(via
		(at 67.502786 -431.193702)
		(size 0.508)
		(drill 0.254)
		(layers "F.Cu" "B.Cu")
		(net "P12V")
	)
	(via
		(at 66.125598 -522.9987)
		(size 0.508)
		(drill 0.254)
		(layers "F.Cu" "B.Cu")
		(net "P12V")
	)
	(via
		(at 58.811414 -525.142206)
		(size 0.508)
		(drill 0.254)
		(layers "F.Cu" "B.Cu")
		(net "P12V")
	)
	(via
		(at 64.855598 -525.142206)
		(size 0.508)
		(drill 0.254)
		(layers "F.Cu" "B.Cu")
		(net "P12V")
	)
	(via
		(at 57.549542 -515.99592)
		(size 0.508)
		(drill 0.254)
		(layers "F.Cu" "B.Cu")
		(net "P12V")
	)
	(via
		(at 57.557924 -336.36839)
		(size 0.508)
		(drill 0.254)
		(layers "F.Cu" "B.Cu")
		(net "P12V")
	)
	(via
		(at 62.46495 -338.409534)
		(size 0.508)
		(drill 0.254)
		(layers "F.Cu" "B.Cu")
		(net "P12V")
	)
	(via
		(at 63.173356 -100.843334)
		(size 0.508)
		(drill 0.254)
		(layers "F.Cu" "B.Cu")
		(net "P12V")
	)
	(via
		(at 62.401958 -288.39541)
		(size 0.508)
		(drill 0.254)
		(layers "F.Cu" "B.Cu")
		(net "P12V")
	)
	(via
		(at 63.544196 -219.173298)
		(size 0.508)
		(drill 0.254)
		(layers "F.Cu" "B.Cu")
		(net "P12V")
	)
	(via
		(at 70.089776 -147.68576)
		(size 0.508)
		(drill 0.254)
		(layers "F.Cu" "B.Cu")
		(net "P12V")
	)
	(via
		(at 78.223364 -135.276844)
		(size 0.508)
		(drill 0.254)
		(layers "F.Cu" "B.Cu")
		(net "P12V")
	)
	(via
		(at 80.78216 -262.564372)
		(size 0.508)
		(drill 0.254)
		(layers "F.Cu" "B.Cu")
		(net "P12V")
	)
	(via
		(at 55.680356 -330.70165)
		(size 0.508)
		(drill 0.254)
		(layers "F.Cu" "B.Cu")
		(net "P12V")
	)
	(via
		(at 66.456306 -462.044796)
		(size 0.508)
		(drill 0.254)
		(layers "F.Cu" "B.Cu")
		(net "P12V")
	)
	(via
		(at 74.39533 -370.607082)
		(size 0.508)
		(drill 0.254)
		(layers "F.Cu" "B.Cu")
		(net "P12V")
	)
	(via
		(at 42.91965 -70.179692)
		(size 0.508)
		(drill 0.254)
		(layers "F.Cu" "B.Cu")
		(net "P12V")
	)
	(via
		(at 67.918584 -458.522324)
		(size 0.508)
		(drill 0.254)
		(layers "F.Cu" "B.Cu")
		(net "P12V")
	)
	(via
		(at 63.618872 -460.278226)
		(size 0.508)
		(drill 0.254)
		(layers "F.Cu" "B.Cu")
		(net "P12V")
	)
	(via
		(at 56.476646 -332.466696)
		(size 0.508)
		(drill 0.254)
		(layers "F.Cu" "B.Cu")
		(net "P12V")
	)
	(via
		(at 71.057516 -14.717776)
		(size 0.508)
		(drill 0.254)
		(layers "F.Cu" "B.Cu")
		(net "P12V")
	)
	(via
		(at 61.97092 -191.714628)
		(size 0.508)
		(drill 0.254)
		(layers "F.Cu" "B.Cu")
		(net "P12V")
	)
	(via
		(at 68.680584 -462.045558)
		(size 0.508)
		(drill 0.254)
		(layers "F.Cu" "B.Cu")
		(net "P12V")
	)
	(via
		(at 67.975988 -335.014316)
		(size 0.508)
		(drill 0.254)
		(layers "F.Cu" "B.Cu")
		(net "P12V")
	)
	(via
		(at 75.121516 -486.955592)
		(size 0.508)
		(drill 0.254)
		(layers "F.Cu" "B.Cu")
		(net "P12V")
	)
	(via
		(at 78.695042 -372.364508)
		(size 0.508)
		(drill 0.254)
		(layers "F.Cu" "B.Cu")
		(net "P12V")
	)
	(via
		(at 67.082416 -16.624046)
		(size 0.508)
		(drill 0.254)
		(layers "F.Cu" "B.Cu")
		(net "P12V")
	)
	(via
		(at 70.851776 -154.68854)
		(size 0.508)
		(drill 0.254)
		(layers "F.Cu" "B.Cu")
		(net "P12V")
	)
	(via
		(at 67.207384 -64.013334)
		(size 0.508)
		(drill 0.254)
		(layers "F.Cu" "B.Cu")
		(net "P12V")
	)
	(via
		(at 62.885828 -518.66419)
		(size 0.508)
		(drill 0.254)
		(layers "F.Cu" "B.Cu")
		(net "P12V")
	)
	(via
		(at 62.73292 -191.714628)
		(size 0.508)
		(drill 0.254)
		(layers "F.Cu" "B.Cu")
		(net "P12V")
	)
	(via
		(at 60.560966 -338.409534)
		(size 0.508)
		(drill 0.254)
		(layers "F.Cu" "B.Cu")
		(net "P12V")
	)
	(via
		(at 65.675256 -423.760138)
		(size 0.508)
		(drill 0.254)
		(layers "F.Cu" "B.Cu")
		(net "P12V")
	)
	(via
		(at 64.380872 -458.521562)
		(size 0.508)
		(drill 0.254)
		(layers "F.Cu" "B.Cu")
		(net "P12V")
	)
	(via
		(at 69.11721 -522.9987)
		(size 0.508)
		(drill 0.254)
		(layers "F.Cu" "B.Cu")
		(net "P12V")
	)
	(via
		(at 66.125598 -521.035788)
		(size 0.508)
		(drill 0.254)
		(layers "F.Cu" "B.Cu")
		(net "P12V")
	)
	(via
		(at 39.560246 -343.981278)
		(size 0.508)
		(drill 0.254)
		(layers "F.Cu" "B.Cu")
		(net "P12V")
	)
	(via
		(at 42.15765 -70.179692)
		(size 0.508)
		(drill 0.254)
		(layers "F.Cu" "B.Cu")
		(net "P12V")
	)
	(via
		(at 58.363358 -332.466696)
		(size 0.508)
		(drill 0.254)
		(layers "F.Cu" "B.Cu")
		(net "P12V")
	)
	(via
		(at 75.574398 -131.142486)
		(size 0.508)
		(drill 0.254)
		(layers "F.Cu" "B.Cu")
		(net "P12V")
	)
	(via
		(at 68.666868 -417.282122)
		(size 0.508)
		(drill 0.254)
		(layers "F.Cu" "B.Cu")
		(net "P12V")
	)
	(via
		(at 77.977746 -262.564372)
		(size 0.508)
		(drill 0.254)
		(layers "F.Cu" "B.Cu")
		(net "P12V")
	)
	(via
		(at 55.303928 -39.106856)
		(size 0.508)
		(drill 0.254)
		(layers "F.Cu" "B.Cu")
		(net "P12V")
	)
	(via
		(at 81.57718 -260.878574)
		(size 0.508)
		(drill 0.254)
		(layers "F.Cu" "B.Cu")
		(net "P12V")
	)
	(via
		(at 64.335152 -465.61629)
		(size 0.508)
		(drill 0.254)
		(layers "F.Cu" "B.Cu")
		(net "P12V")
	)
	(via
		(at 78.695042 -370.607844)
		(size 0.508)
		(drill 0.254)
		(layers "F.Cu" "B.Cu")
		(net "P12V")
	)
	(via
		(at 86.567264 -82.78749)
		(size 0.508)
		(drill 0.254)
		(layers "F.Cu" "B.Cu")
		(net "P12V")
	)
	(via
		(at 84.52485 -82.78749)
		(size 0.508)
		(drill 0.254)
		(layers "F.Cu" "B.Cu")
		(net "P12V")
	)
	(via
		(at 67.860164 -150.35403)
		(size 0.508)
		(drill 0.254)
		(layers "F.Cu" "B.Cu")
		(net "P12V")
	)
	(via
		(at 67.082416 -14.717776)
		(size 0.508)
		(drill 0.254)
		(layers "F.Cu" "B.Cu")
		(net "P12V")
	)
	(via
		(at 65.171574 -335.014316)
		(size 0.508)
		(drill 0.254)
		(layers "F.Cu" "B.Cu")
		(net "P12V")
	)
	(via
		(at 68.737988 -323.19722)
		(size 0.508)
		(drill 0.254)
		(layers "F.Cu" "B.Cu")
		(net "P12V")
	)
	(via
		(at 71.057516 -16.624046)
		(size 0.508)
		(drill 0.254)
		(layers "F.Cu" "B.Cu")
		(net "P12V")
	)
	(via
		(at 40.709088 -158.516066)
		(size 0.508)
		(drill 0.254)
		(layers "F.Cu" "B.Cu")
		(net "P12V")
	)
	(via
		(at 77.232764 -372.363746)
		(size 0.508)
		(drill 0.254)
		(layers "F.Cu" "B.Cu")
		(net "P12V")
	)
	(via
		(at 67.502786 -425.854622)
		(size 0.508)
		(drill 0.254)
		(layers "F.Cu" "B.Cu")
		(net "P12V")
	)
	(via
		(at 70.089776 -156.832046)
		(size 0.508)
		(drill 0.254)
		(layers "F.Cu" "B.Cu")
		(net "P12V")
	)
	(via
		(at 80.85201 -254.326644)
		(size 0.508)
		(drill 0.254)
		(layers "F.Cu" "B.Cu")
		(net "P12V")
	)
	(via
		(at 80.819498 -174.962312)
		(size 0.508)
		(drill 0.254)
		(layers "F.Cu" "B.Cu")
		(net "P12V")
	)
	(via
		(at 80.755744 -302.832262)
		(size 0.508)
		(drill 0.254)
		(layers "F.Cu" "B.Cu")
		(net "P12V")
	)
	(via
		(at 14.822424 -325.072248)
		(size 0.508)
		(drill 0.254)
		(layers "F.Cu" "B.Cu")
		(net "P12V")
	)
	(via
		(at 69.296534 -290.954714)
		(size 0.508)
		(drill 0.254)
		(layers "F.Cu" "B.Cu")
		(net "P12V")
	)
	(via
		(at 68.666868 -421.616632)
		(size 0.508)
		(drill 0.254)
		(layers "F.Cu" "B.Cu")
		(net "P12V")
	)
	(via
		(at 65.675256 -417.282122)
		(size 0.508)
		(drill 0.254)
		(layers "F.Cu" "B.Cu")
		(net "P12V")
	)
	(via
		(at 81.61401 -254.326644)
		(size 0.508)
		(drill 0.254)
		(layers "F.Cu" "B.Cu")
		(net "P12V")
	)
	(via
		(at 68.979288 -17.386046)
		(size 0.508)
		(drill 0.254)
		(layers "F.Cu" "B.Cu")
		(net "P12V")
	)
	(via
		(at 62.885828 -522.9987)
		(size 0.508)
		(drill 0.254)
		(layers "F.Cu" "B.Cu")
		(net "P12V")
	)
	(via
		(at 60.552584 -221.316804)
		(size 0.508)
		(drill 0.254)
		(layers "F.Cu" "B.Cu")
		(net "P12V")
	)
	(via
		(at 58.811414 -522.9987)
		(size 0.508)
		(drill 0.254)
		(layers "F.Cu" "B.Cu")
		(net "P12V")
	)
	(via
		(at 77.253084 -165.724078)
		(size 0.508)
		(drill 0.254)
		(layers "F.Cu" "B.Cu")
		(net "P12V")
	)
	(via
		(at 80.83169 -259.246878)
		(size 0.508)
		(drill 0.254)
		(layers "F.Cu" "B.Cu")
		(net "P12V")
	)
	(via
		(at 69.11721 -521.035788)
		(size 0.508)
		(drill 0.254)
		(layers "F.Cu" "B.Cu")
		(net "P12V")
	)
	(via
		(at 64.632078 -437.42356)
		(size 0.508)
		(drill 0.254)
		(layers "F.Cu" "B.Cu")
		(net "P12V")
	)
	(via
		(at 65.423288 -104.17683)
		(size 0.508)
		(drill 0.254)
		(layers "F.Cu" "B.Cu")
		(net "P12V")
	)
	(via
		(at 77.232764 -374.130316)
		(size 0.508)
		(drill 0.254)
		(layers "F.Cu" "B.Cu")
		(net "P12V")
	)
	(via
		(at 80.819498 -172.9994)
		(size 0.508)
		(drill 0.254)
		(layers "F.Cu" "B.Cu")
		(net "P12V")
	)
	(via
		(at 57.557924 -338.409534)
		(size 0.508)
		(drill 0.254)
		(layers "F.Cu" "B.Cu")
		(net "P12V")
	)
	(via
		(at 66.922142 -288.322512)
		(size 0.508)
		(drill 0.254)
		(layers "F.Cu" "B.Cu")
		(net "P12V")
	)
	(via
		(at 75.574398 -135.248904)
		(size 0.508)
		(drill 0.254)
		(layers "F.Cu" "B.Cu")
		(net "P12V")
	)
	(via
		(at 67.082416 -17.386046)
		(size 0.508)
		(drill 0.254)
		(layers "F.Cu" "B.Cu")
		(net "P12V")
	)
	(via
		(at 76.425044 -375.945146)
		(size 0.508)
		(drill 0.254)
		(layers "F.Cu" "B.Cu")
		(net "P12V")
	)
	(via
		(at 77.187044 -375.945146)
		(size 0.508)
		(drill 0.254)
		(layers "F.Cu" "B.Cu")
		(net "P12V")
	)
	(via
		(at 60.081414 -518.66419)
		(size 0.508)
		(drill 0.254)
		(layers "F.Cu" "B.Cu")
		(net "P12V")
	)
	(via
		(at 77.050646 -486.955592)
		(size 0.508)
		(drill 0.254)
		(layers "F.Cu" "B.Cu")
		(net "P12V")
	)
	(via
		(at 64.625982 -291.027104)
		(size 0.508)
		(drill 0.254)
		(layers "F.Cu" "B.Cu")
		(net "P12V")
	)
	(via
		(at 74.39533 -374.130316)
		(size 0.508)
		(drill 0.254)
		(layers "F.Cu" "B.Cu")
		(net "P12V")
	)
	(via
		(at 67.504564 -243.804186)
		(size 0.508)
		(drill 0.254)
		(layers "F.Cu" "B.Cu")
		(net "P12V")
	)
	(via
		(at 64.977772 -65.976246)
		(size 0.508)
		(drill 0.254)
		(layers "F.Cu" "B.Cu")
		(net "P12V")
	)
	(via
		(at 60.895484 -101.569012)
		(size 0.508)
		(drill 0.254)
		(layers "F.Cu" "B.Cu")
		(net "P12V")
	)
	(via
		(at 61.746384 -332.466696)
		(size 0.508)
		(drill 0.254)
		(layers "F.Cu" "B.Cu")
		(net "P12V")
	)
	(via
		(at 86.544404 -88.55837)
		(size 0.508)
		(drill 0.254)
		(layers "F.Cu" "B.Cu")
		(net "P12V")
	)
	(via
		(at 70.089776 -152.725628)
		(size 0.508)
		(drill 0.254)
		(layers "F.Cu" "B.Cu")
		(net "P12V")
	)
	(via
		(at 39.560246 -332.164182)
		(size 0.508)
		(drill 0.254)
		(layers "F.Cu" "B.Cu")
		(net "P12V")
	)
	(via
		(at 69.428868 -423.760138)
		(size 0.508)
		(drill 0.254)
		(layers "F.Cu" "B.Cu")
		(net "P12V")
	)
	(via
		(at 42.91965 -79.325978)
		(size 0.508)
		(drill 0.254)
		(layers "F.Cu" "B.Cu")
		(net "P12V")
	)
	(via
		(at 78.79461 -488.767882)
		(size 0.508)
		(drill 0.254)
		(layers "F.Cu" "B.Cu")
		(net "P12V")
	)
	(via
		(at 82.144362 -297.892216)
		(size 0.508)
		(drill 0.254)
		(layers "F.Cu" "B.Cu")
		(net "P12V")
	)
	(via
		(at 66.125598 -515.99592)
		(size 0.508)
		(drill 0.254)
		(layers "F.Cu" "B.Cu")
		(net "P12V")
	)
	(via
		(at 57.557924 -334.477868)
		(size 0.508)
		(drill 0.254)
		(layers "F.Cu" "B.Cu")
		(net "P12V")
	)
	(via
		(at 69.730874 -100.780596)
		(size 0.508)
		(drill 0.254)
		(layers "F.Cu" "B.Cu")
		(net "P12V")
	)
	(via
		(at 69.11721 -515.99592)
		(size 0.508)
		(drill 0.254)
		(layers "F.Cu" "B.Cu")
		(net "P12V")
	)
	(via
		(at 78.015084 -174.962312)
		(size 0.508)
		(drill 0.254)
		(layers "F.Cu" "B.Cu")
		(net "P12V")
	)
	(via
		(at 62.401958 -291.06368)
		(size 0.508)
		(drill 0.254)
		(layers "F.Cu" "B.Cu")
		(net "P12V")
	)
	(via
		(at 58.329068 -330.70165)
		(size 0.508)
		(drill 0.254)
		(layers "F.Cu" "B.Cu")
		(net "P12V")
	)
	(via
		(at 76.375514 -304.976022)
		(size 0.508)
		(drill 0.254)
		(layers "F.Cu" "B.Cu")
		(net "P12V")
	)
	(via
		(at 65.933574 -323.19722)
		(size 0.508)
		(drill 0.254)
		(layers "F.Cu" "B.Cu")
		(net "P12V")
	)
	(via
		(at 76.470764 -372.363746)
		(size 0.508)
		(drill 0.254)
		(layers "F.Cu" "B.Cu")
		(net "P12V")
	)
	(via
		(at 78.223364 -133.133338)
		(size 0.508)
		(drill 0.254)
		(layers "F.Cu" "B.Cu")
		(net "P12V")
	)
	(via
		(at 83.76285 -86.985094)
		(size 0.508)
		(drill 0.254)
		(layers "F.Cu" "B.Cu")
		(net "P12V")
	)
	(via
		(at 65.167764 -12.337288)
		(size 0.508)
		(drill 0.254)
		(layers "F.Cu" "B.Cu")
		(net "P12V")
	)
	(via
		(at 66.705734 -247.494044)
		(size 0.508)
		(drill 0.254)
		(layers "F.Cu" "B.Cu")
		(net "P12V")
	)
	(via
		(at 67.504564 -245.644924)
		(size 0.508)
		(drill 0.254)
		(layers "F.Cu" "B.Cu")
		(net "P12V")
	)
	(via
		(at 65.648586 -465.61629)
		(size 0.508)
		(drill 0.254)
		(layers "F.Cu" "B.Cu")
		(net "P12V")
	)
	(via
		(at 64.215772 -68.119752)
		(size 0.508)
		(drill 0.254)
		(layers "F.Cu" "B.Cu")
		(net "P12V")
	)
	(via
		(at 40.322246 -341.837772)
		(size 0.508)
		(drill 0.254)
		(layers "F.Cu" "B.Cu")
		(net "P12V")
	)
	(via
		(at 71.057516 -17.386046)
		(size 0.508)
		(drill 0.254)
		(layers "F.Cu" "B.Cu")
		(net "P12V")
	)
	(via
		(at 59.439048 -193.67754)
		(size 0.508)
		(drill 0.254)
		(layers "F.Cu" "B.Cu")
		(net "P12V")
	)
	(via
		(at 41.025318 -110.774226)
		(size 0.508)
		(drill 0.254)
		(layers "F.Cu" "B.Cu")
		(net "P12V")
	)
	(via
		(at 42.91965 -72.847962)
		(size 0.508)
		(drill 0.254)
		(layers "F.Cu" "B.Cu")
		(net "P12V")
	)
	(via
		(at 42.15765 -77.182472)
		(size 0.508)
		(drill 0.254)
		(layers "F.Cu" "B.Cu")
		(net "P12V")
	)
	(via
		(at 60.081414 -522.9987)
		(size 0.508)
		(drill 0.254)
		(layers "F.Cu" "B.Cu")
		(net "P12V")
	)
	(via
		(at 62.885828 -513.32511)
		(size 0.508)
		(drill 0.254)
		(layers "F.Cu" "B.Cu")
		(net "P12V")
	)
	(via
		(at 40.256968 -428.65167)
		(size 0.508)
		(drill 0.254)
		(layers "F.Cu" "B.Cu")
		(net "P12V")
	)
	(via
		(at 76.288646 -488.722162)
		(size 0.508)
		(drill 0.254)
		(layers "F.Cu" "B.Cu")
		(net "P12V")
	)
	(via
		(at 66.437256 -421.616632)
		(size 0.508)
		(drill 0.254)
		(layers "F.Cu" "B.Cu")
		(net "P12V")
	)
	(via
		(at 61.70295 -336.36839)
		(size 0.508)
		(drill 0.254)
		(layers "F.Cu" "B.Cu")
		(net "P12V")
	)
	(via
		(at 66.445384 -64.013334)
		(size 0.508)
		(drill 0.254)
		(layers "F.Cu" "B.Cu")
		(net "P12V")
	)
	(via
		(at 69.428868 -411.943042)
		(size 0.508)
		(drill 0.254)
		(layers "F.Cu" "B.Cu")
		(net "P12V")
	)
	(via
		(at 67.57416 -101.506274)
		(size 0.508)
		(drill 0.254)
		(layers "F.Cu" "B.Cu")
		(net "P12V")
	)
	(via
		(at 65.933574 -328.5363)
		(size 0.508)
		(drill 0.254)
		(layers "F.Cu" "B.Cu")
		(net "P12V")
	)
	(via
		(at 68.680584 -460.278988)
		(size 0.508)
		(drill 0.254)
		(layers "F.Cu" "B.Cu")
		(net "P12V")
	)
	(via
		(at 64.855598 -518.66419)
		(size 0.508)
		(drill 0.254)
		(layers "F.Cu" "B.Cu")
		(net "P12V")
	)
	(via
		(at 70.851776 -150.35403)
		(size 0.508)
		(drill 0.254)
		(layers "F.Cu" "B.Cu")
		(net "P12V")
	)
	(via
		(at 69.730874 -101.542596)
		(size 0.508)
		(drill 0.254)
		(layers "F.Cu" "B.Cu")
		(net "P12V")
	)
	(via
		(at 78.759812 -255.854962)
		(size 0.508)
		(drill 0.254)
		(layers "F.Cu" "B.Cu")
		(net "P12V")
	)
	(via
		(at 79.365856 -379.469142)
		(size 0.508)
		(drill 0.254)
		(layers "F.Cu" "B.Cu")
		(net "P12V")
	)
	(via
		(at 77.137514 -300.869604)
		(size 0.508)
		(drill 0.254)
		(layers "F.Cu" "B.Cu")
		(net "P12V")
	)
	(via
		(at 66.125598 -513.32511)
		(size 0.508)
		(drill 0.254)
		(layers "F.Cu" "B.Cu")
		(net "P12V")
	)
	(via
		(at 66.410586 -463.859626)
		(size 0.508)
		(drill 0.254)
		(layers "F.Cu" "B.Cu")
		(net "P12V")
	)
	(via
		(at 59.870086 -285.7246)
		(size 0.508)
		(drill 0.254)
		(layers "F.Cu" "B.Cu")
		(net "P12V")
	)
	(via
		(at 77.253084 -172.9994)
		(size 0.508)
		(drill 0.254)
		(layers "F.Cu" "B.Cu")
		(net "P12V")
	)
	(via
		(at 67.57416 -103.415084)
		(size 0.508)
		(drill 0.254)
		(layers "F.Cu" "B.Cu")
		(net "P12V")
	)
	(via
		(at 79.288386 -304.976022)
		(size 0.508)
		(drill 0.254)
		(layers "F.Cu" "B.Cu")
		(net "P12V")
	)
	(via
		(at 67.098164 -147.68576)
		(size 0.508)
		(drill 0.254)
		(layers "F.Cu" "B.Cu")
		(net "P12V")
	)
	(via
		(at 64.306196 -217.210386)
		(size 0.508)
		(drill 0.254)
		(layers "F.Cu" "B.Cu")
		(net "P12V")
	)
	(via
		(at 42.15765 -67.508882)
		(size 0.508)
		(drill 0.254)
		(layers "F.Cu" "B.Cu")
		(net "P12V")
	)
	(via
		(at 63.863982 -288.358834)
		(size 0.508)
		(drill 0.254)
		(layers "F.Cu" "B.Cu")
		(net "P12V")
	)
	(via
		(at 14.837664 -323.185282)
		(size 0.508)
		(drill 0.254)
		(layers "F.Cu" "B.Cu")
		(net "P12V")
	)
	(via
		(at 64.855598 -515.99592)
		(size 0.508)
		(drill 0.254)
		(layers "F.Cu" "B.Cu")
		(net "P12V")
	)
	(via
		(at 74.359516 -486.955592)
		(size 0.508)
		(drill 0.254)
		(layers "F.Cu" "B.Cu")
		(net "P12V")
	)
	(via
		(at 66.278506 -391.42797)
		(size 0.508)
		(drill 0.254)
		(layers "F.Cu" "B.Cu")
		(net "P12V")
	)
	(via
		(at 56.279542 -525.142206)
		(size 0.508)
		(drill 0.254)
		(layers "F.Cu" "B.Cu")
		(net "P12V")
	)
	(via
		(at 68.737988 -332.87081)
		(size 0.508)
		(drill 0.254)
		(layers "F.Cu" "B.Cu")
		(net "P12V")
	)
	(via
		(at 80.819498 -167.959532)
		(size 0.508)
		(drill 0.254)
		(layers "F.Cu" "B.Cu")
		(net "P12V")
	)
	(via
		(at 64.855598 -513.32511)
		(size 0.508)
		(drill 0.254)
		(layers "F.Cu" "B.Cu")
		(net "P12V")
	)
	(via
		(at 58.319924 -340.31936)
		(size 0.508)
		(drill 0.254)
		(layers "F.Cu" "B.Cu")
		(net "P12V")
	)
	(via
		(at 69.296534 -288.286444)
		(size 0.508)
		(drill 0.254)
		(layers "F.Cu" "B.Cu")
		(net "P12V")
	)
	(via
		(at 63.573152 -463.859626)
		(size 0.508)
		(drill 0.254)
		(layers "F.Cu" "B.Cu")
		(net "P12V")
	)
	(via
		(at 69.428868 -417.282122)
		(size 0.508)
		(drill 0.254)
		(layers "F.Cu" "B.Cu")
		(net "P12V")
	)
	(via
		(at 84.52485 -85.159088)
		(size 0.508)
		(drill 0.254)
		(layers "F.Cu" "B.Cu")
		(net "P12V")
	)
	(via
		(at 65.167764 -11.575288)
		(size 0.508)
		(drill 0.254)
		(layers "F.Cu" "B.Cu")
		(net "P12V")
	)
	(via
		(at 40.322246 -337.503262)
		(size 0.508)
		(drill 0.254)
		(layers "F.Cu" "B.Cu")
		(net "P12V")
	)
	(via
		(at 81.517744 -302.832262)
		(size 0.508)
		(drill 0.254)
		(layers "F.Cu" "B.Cu")
		(net "P12V")
	)
	(via
		(at 69.730874 -106.119676)
		(size 0.508)
		(drill 0.254)
		(layers "F.Cu" "B.Cu")
		(net "P12V")
	)
	(via
		(at 66.445384 -65.976246)
		(size 0.508)
		(drill 0.254)
		(layers "F.Cu" "B.Cu")
		(net "P12V")
	)
	(via
		(at 55.303928 -43.213274)
		(size 0.508)
		(drill 0.254)
		(layers "F.Cu" "B.Cu")
		(net "P12V")
	)
	(via
		(at 76.425044 -377.70181)
		(size 0.508)
		(drill 0.254)
		(layers "F.Cu" "B.Cu")
		(net "P12V")
	)
	(via
		(at 57.549542 -521.035788)
		(size 0.508)
		(drill 0.254)
		(layers "F.Cu" "B.Cu")
		(net "P12V")
	)
	(via
		(at 69.296534 -285.615634)
		(size 0.508)
		(drill 0.254)
		(layers "F.Cu" "B.Cu")
		(net "P12V")
	)
	(via
		(at 74.359516 -488.722162)
		(size 0.508)
		(drill 0.254)
		(layers "F.Cu" "B.Cu")
		(net "P12V")
	)
	(via
		(at 80.818736 -257.579876)
		(size 0.508)
		(drill 0.254)
		(layers "F.Cu" "B.Cu")
		(net "P12V")
	)
	(via
		(at 67.098164 -150.35403)
		(size 0.508)
		(drill 0.254)
		(layers "F.Cu" "B.Cu")
		(net "P12V")
	)
	(via
		(at 87.329264 -86.985094)
		(size 0.508)
		(drill 0.254)
		(layers "F.Cu" "B.Cu")
		(net "P12V")
	)
	(via
		(at 78.809596 -254.326644)
		(size 0.508)
		(drill 0.254)
		(layers "F.Cu" "B.Cu")
		(net "P12V")
	)
	(via
		(at 73.177908 -12.337288)
		(size 0.508)
		(drill 0.254)
		(layers "F.Cu" "B.Cu")
		(net "P12V")
	)
	(via
		(at 65.242694 -41.069768)
		(size 0.508)
		(drill 0.254)
		(layers "F.Cu" "B.Cu")
		(net "P12V")
	)
	(via
		(at 64.977772 -64.013334)
		(size 0.508)
		(drill 0.254)
		(layers "F.Cu" "B.Cu")
		(net "P12V")
	)
	(via
		(at 68.979288 -11.575288)
		(size 0.508)
		(drill 0.254)
		(layers "F.Cu" "B.Cu")
		(net "P12V")
	)
	(via
		(at 64.698372 -435.528212)
		(size 0.508)
		(drill 0.254)
		(layers "F.Cu" "B.Cu")
		(net "P12V")
	)
	(via
		(at 80.464914 -131.242816)
		(size 0.508)
		(drill 0.254)
		(layers "F.Cu" "B.Cu")
		(net "P12V")
	)
	(via
		(at 65.537334 -191.714628)
		(size 0.508)
		(drill 0.254)
		(layers "F.Cu" "B.Cu")
		(net "P12V")
	)
	(via
		(at 68.207636 -391.42797)
		(size 0.508)
		(drill 0.254)
		(layers "F.Cu" "B.Cu")
		(net "P12V")
	)
	(via
		(at 63.013082 -41.831768)
		(size 0.508)
		(drill 0.254)
		(layers "F.Cu" "B.Cu")
		(net "P12V")
	)
	(via
		(at 59.798966 -334.477868)
		(size 0.508)
		(drill 0.254)
		(layers "F.Cu" "B.Cu")
		(net "P12V")
	)
	(via
		(at 78.526386 -304.976022)
		(size 0.508)
		(drill 0.254)
		(layers "F.Cu" "B.Cu")
		(net "P12V")
	)
	(via
		(at 81.517744 -304.975768)
		(size 0.508)
		(drill 0.254)
		(layers "F.Cu" "B.Cu")
		(net "P12V")
	)
	(via
		(at 76.336398 -131.142486)
		(size 0.508)
		(drill 0.254)
		(layers "F.Cu" "B.Cu")
		(net "P12V")
	)
	(via
		(at 65.242694 -39.868856)
		(size 0.508)
		(drill 0.254)
		(layers "F.Cu" "B.Cu")
		(net "P12V")
	)
	(via
		(at 61.97092 -195.821046)
		(size 0.508)
		(drill 0.254)
		(layers "F.Cu" "B.Cu")
		(net "P12V")
	)
	(via
		(at 39.947088 -153.612342)
		(size 0.508)
		(drill 0.254)
		(layers "F.Cu" "B.Cu")
		(net "P12V")
	)
	(via
		(at 57.8358 -43.213274)
		(size 0.508)
		(drill 0.254)
		(layers "F.Cu" "B.Cu")
		(net "P12V")
	)
	(via
		(at 68.666868 -411.943042)
		(size 0.508)
		(drill 0.254)
		(layers "F.Cu" "B.Cu")
		(net "P12V")
	)
	(via
		(at 15.018258 -319.442338)
		(size 0.508)
		(drill 0.254)
		(layers "F.Cu" "B.Cu")
		(net "P12V")
	)
	(via
		(at 64.977772 -61.641736)
		(size 0.508)
		(drill 0.254)
		(layers "F.Cu" "B.Cu")
		(net "P12V")
	)
	(via
		(at 69.11721 -525.142206)
		(size 0.508)
		(drill 0.254)
		(layers "F.Cu" "B.Cu")
		(net "P12V")
	)
	(via
		(at 67.502786 -428.525432)
		(size 0.508)
		(drill 0.254)
		(layers "F.Cu" "B.Cu")
		(net "P12V")
	)
	(via
		(at 78.010766 -260.878574)
		(size 0.508)
		(drill 0.254)
		(layers "F.Cu" "B.Cu")
		(net "P12V")
	)
	(via
		(at 70.7136 -391.47369)
		(size 0.508)
		(drill 0.254)
		(layers "F.Cu" "B.Cu")
		(net "P12V")
	)
	(via
		(at 65.648586 -463.859626)
		(size 0.508)
		(drill 0.254)
		(layers "F.Cu" "B.Cu")
		(net "P12V")
	)
	(via
		(at 69.9516 -391.47369)
		(size 0.508)
		(drill 0.254)
		(layers "F.Cu" "B.Cu")
		(net "P12V")
	)
	(via
		(at 78.739746 -262.564372)
		(size 0.508)
		(drill 0.254)
		(layers "F.Cu" "B.Cu")
		(net "P12V")
	)
	(via
		(at 58.811414 -513.32511)
		(size 0.508)
		(drill 0.254)
		(layers "F.Cu" "B.Cu")
		(net "P12V")
	)
	(via
		(at 58.811414 -518.66419)
		(size 0.508)
		(drill 0.254)
		(layers "F.Cu" "B.Cu")
		(net "P12V")
	)
	(via
		(at 67.918584 -460.278988)
		(size 0.508)
		(drill 0.254)
		(layers "F.Cu" "B.Cu")
		(net "P12V")
	)
	(via
		(at 78.047596 -254.326644)
		(size 0.508)
		(drill 0.254)
		(layers "F.Cu" "B.Cu")
		(net "P12V")
	)
	(via
		(at 78.03261 -485.244648)
		(size 0.508)
		(drill 0.254)
		(layers "F.Cu" "B.Cu")
		(net "P12V")
	)
	(via
		(at 83.76285 -85.159088)
		(size 0.508)
		(drill 0.254)
		(layers "F.Cu" "B.Cu")
		(net "P12V")
	)
	(via
		(at 71.057516 -13.955776)
		(size 0.508)
		(drill 0.254)
		(layers "F.Cu" "B.Cu")
		(net "P12V")
	)
	(via
		(at 67.84721 -513.32511)
		(size 0.508)
		(drill 0.254)
		(layers "F.Cu" "B.Cu")
		(net "P12V")
	)
	(via
		(at 68.589398 -467.383622)
		(size 0.508)
		(drill 0.254)
		(layers "F.Cu" "B.Cu")
		(net "P12V")
	)
	(via
		(at 41.018968 -420.940992)
		(size 0.508)
		(drill 0.254)
		(layers "F.Cu" "B.Cu")
		(net "P12V")
	)
	(via
		(at 75.574398 -133.105398)
		(size 0.508)
		(drill 0.254)
		(layers "F.Cu" "B.Cu")
		(net "P12V")
	)
	(via
		(at 83.742022 -79.24292)
		(size 0.508)
		(drill 0.254)
		(layers "F.Cu" "B.Cu")
		(net "P12V")
	)
	(via
		(at 64.306196 -219.173298)
		(size 0.508)
		(drill 0.254)
		(layers "F.Cu" "B.Cu")
		(net "P12V")
	)
	(via
		(at 68.969636 -391.42797)
		(size 0.508)
		(drill 0.254)
		(layers "F.Cu" "B.Cu")
		(net "P12V")
	)
	(via
		(at 42.271696 -254.90678)
		(size 0.508)
		(drill 0.254)
		(layers "F.Cu" "B.Cu")
		(net "P12V")
	)
	(via
		(at 63.173356 -106.944414)
		(size 0.508)
		(drill 0.254)
		(layers "F.Cu" "B.Cu")
		(net "P12V")
	)
	(via
		(at 42.271696 -256.869692)
		(size 0.508)
		(drill 0.254)
		(layers "F.Cu" "B.Cu")
		(net "P12V")
	)
	(via
		(at 62.474094 -328.800714)
		(size 0.508)
		(drill 0.254)
		(layers "F.Cu" "B.Cu")
		(net "P12V")
	)
	(via
		(at 59.439048 -191.714628)
		(size 0.508)
		(drill 0.254)
		(layers "F.Cu" "B.Cu")
		(net "P12V")
	)
	(via
		(at 65.423288 -101.50602)
		(size 0.508)
		(drill 0.254)
		(layers "F.Cu" "B.Cu")
		(net "P12V")
	)
	(via
		(at 63.936372 -435.528212)
		(size 0.508)
		(drill 0.254)
		(layers "F.Cu" "B.Cu")
		(net "P12V")
	)
	(via
		(at 58.329068 -326.967088)
		(size 0.508)
		(drill 0.254)
		(layers "F.Cu" "B.Cu")
		(net "P12V")
	)
	(via
		(at 60.560966 -336.36839)
		(size 0.508)
		(drill 0.254)
		(layers "F.Cu" "B.Cu")
		(net "P12V")
	)
	(via
		(at 61.615828 -515.99592)
		(size 0.508)
		(drill 0.254)
		(layers "F.Cu" "B.Cu")
		(net "P12V")
	)
	(via
		(at 65.537334 -193.67754)
		(size 0.508)
		(drill 0.254)
		(layers "F.Cu" "B.Cu")
		(net "P12V")
	)
	(via
		(at 65.675256 -411.943042)
		(size 0.508)
		(drill 0.254)
		(layers "F.Cu" "B.Cu")
		(net "P12V")
	)
	(via
		(at 68.534534 -290.954714)
		(size 0.508)
		(drill 0.254)
		(layers "F.Cu" "B.Cu")
		(net "P12V")
	)
	(via
		(at 57.549542 -522.9987)
		(size 0.508)
		(drill 0.254)
		(layers "F.Cu" "B.Cu")
		(net "P12V")
	)
	(via
		(at 68.737988 -330.907898)
		(size 0.508)
		(drill 0.254)
		(layers "F.Cu" "B.Cu")
		(net "P12V")
	)
	(via
		(at 69.11721 -518.66419)
		(size 0.508)
		(drill 0.254)
		(layers "F.Cu" "B.Cu")
		(net "P12V")
	)
	(via
		(at 84.504022 -79.24292)
		(size 0.508)
		(drill 0.254)
		(layers "F.Cu" "B.Cu")
		(net "P12V")
	)
	(via
		(at 77.137514 -304.976022)
		(size 0.508)
		(drill 0.254)
		(layers "F.Cu" "B.Cu")
		(net "P12V")
	)
	(via
		(at 65.675256 -421.616632)
		(size 0.508)
		(drill 0.254)
		(layers "F.Cu" "B.Cu")
		(net "P12V")
	)
	(via
		(at 60.895484 -106.146092)
		(size 0.508)
		(drill 0.254)
		(layers "F.Cu" "B.Cu")
		(net "P12V")
	)
	(via
		(at 78.603856 -379.469142)
		(size 0.508)
		(drill 0.254)
		(layers "F.Cu" "B.Cu")
		(net "P12V")
	)
	(via
		(at 41.018968 -423.611802)
		(size 0.508)
		(drill 0.254)
		(layers "F.Cu" "B.Cu")
		(net "P12V")
	)
	(via
		(at 67.098164 -156.832046)
		(size 0.508)
		(drill 0.254)
		(layers "F.Cu" "B.Cu")
		(net "P12V")
	)
	(via
		(at 79.96174 -488.767882)
		(size 0.508)
		(drill 0.254)
		(layers "F.Cu" "B.Cu")
		(net "P12V")
	)
	(via
		(at 67.860164 -154.68854)
		(size 0.508)
		(drill 0.254)
		(layers "F.Cu" "B.Cu")
		(net "P12V")
	)
	(via
		(at 78.223364 -131.170426)
		(size 0.508)
		(drill 0.254)
		(layers "F.Cu" "B.Cu")
		(net "P12V")
	)
	(via
		(at 69.697346 -247.494044)
		(size 0.508)
		(drill 0.254)
		(layers "F.Cu" "B.Cu")
		(net "P12V")
	)
	(via
		(at 61.97092 -193.67754)
		(size 0.508)
		(drill 0.254)
		(layers "F.Cu" "B.Cu")
		(net "P12V")
	)
	(via
		(at 68.969636 -393.19454)
		(size 0.508)
		(drill 0.254)
		(layers "F.Cu" "B.Cu")
		(net "P12V")
	)
	(via
		(at 65.167764 -17.386046)
		(size 0.508)
		(drill 0.254)
		(layers "F.Cu" "B.Cu")
		(net "P12V")
	)
	(via
		(at 66.445384 -68.119752)
		(size 0.508)
		(drill 0.254)
		(layers "F.Cu" "B.Cu")
		(net "P12V")
	)
	(via
		(at 68.737988 -335.014316)
		(size 0.508)
		(drill 0.254)
		(layers "F.Cu" "B.Cu")
		(net "P12V")
	)
	(via
		(at 80.72374 -488.767882)
		(size 0.508)
		(drill 0.254)
		(layers "F.Cu" "B.Cu")
		(net "P12V")
	)
	(via
		(at 65.933574 -325.86803)
		(size 0.508)
		(drill 0.254)
		(layers "F.Cu" "B.Cu")
		(net "P12V")
	)
	(via
		(at 63.013082 -39.106856)
		(size 0.508)
		(drill 0.254)
		(layers "F.Cu" "B.Cu")
		(net "P12V")
	)
	(via
		(at 80.057498 -167.959532)
		(size 0.508)
		(drill 0.254)
		(layers "F.Cu" "B.Cu")
		(net "P12V")
	)
	(via
		(at 72.944228 -304.957988)
		(size 0.508)
		(drill 0.254)
		(layers "F.Cu" "B.Cu")
		(net "P12V")
	)
	(via
		(at 61.639958 -285.7246)
		(size 0.508)
		(drill 0.254)
		(layers "F.Cu" "B.Cu")
		(net "P12V")
	)
	(via
		(at 67.504564 -241.133376)
		(size 0.508)
		(drill 0.254)
		(layers "F.Cu" "B.Cu")
		(net "P12V")
	)
	(via
		(at 78.015084 -177.105818)
		(size 0.508)
		(drill 0.254)
		(layers "F.Cu" "B.Cu")
		(net "P12V")
	)
	(via
		(at 67.84721 -518.66419)
		(size 0.508)
		(drill 0.254)
		(layers "F.Cu" "B.Cu")
		(net "P12V")
	)
	(via
		(at 69.428868 -414.613852)
		(size 0.508)
		(drill 0.254)
		(layers "F.Cu" "B.Cu")
		(net "P12V")
	)
	(via
		(at 73.177908 -16.624046)
		(size 0.508)
		(drill 0.254)
		(layers "F.Cu" "B.Cu")
		(net "P12V")
	)
	(via
		(at 40.256968 -430.614582)
		(size 0.508)
		(drill 0.254)
		(layers "F.Cu" "B.Cu")
		(net "P12V")
	)
	(via
		(at 65.167764 -13.955776)
		(size 0.508)
		(drill 0.254)
		(layers "F.Cu" "B.Cu")
		(net "P12V")
	)
	(via
		(at 80.755744 -304.975768)
		(size 0.508)
		(drill 0.254)
		(layers "F.Cu" "B.Cu")
		(net "P12V")
	)
	(via
		(at 74.323956 -473.59951)
		(size 0.508)
		(drill 0.254)
		(layers "F.Cu" "B.Cu")
		(net "P12V")
	)
	(via
		(at 64.698372 -428.525432)
		(size 0.508)
		(drill 0.254)
		(layers "F.Cu" "B.Cu")
		(net "P12V")
	)
	(via
		(at 70.089776 -150.35403)
		(size 0.508)
		(drill 0.254)
		(layers "F.Cu" "B.Cu")
		(net "P12V")
	)
	(via
		(at 61.314584 -221.316804)
		(size 0.508)
		(drill 0.254)
		(layers "F.Cu" "B.Cu")
		(net "P12V")
	)
	(via
		(at 60.640214 -43.213274)
		(size 0.508)
		(drill 0.254)
		(layers "F.Cu" "B.Cu")
		(net "P12V")
	)
	(via
		(at 73.550526 -131.21513)
		(size 0.508)
		(drill 0.254)
		(layers "F.Cu" "B.Cu")
		(net "P12V")
	)
	(via
		(at 74.351134 -302.77816)
		(size 0.508)
		(drill 0.254)
		(layers "F.Cu" "B.Cu")
		(net "P12V")
	)
	(via
		(at 68.207636 -389.671306)
		(size 0.508)
		(drill 0.254)
		(layers "F.Cu" "B.Cu")
		(net "P12V")
	)
	(via
		(at 74.351134 -304.921666)
		(size 0.508)
		(drill 0.254)
		(layers "F.Cu" "B.Cu")
		(net "P12V")
	)
	(via
		(at 75.113134 -300.815248)
		(size 0.508)
		(drill 0.254)
		(layers "F.Cu" "B.Cu")
		(net "P12V")
	)
	(via
		(at 40.980106 -22.379432)
		(size 0.508)
		(drill 0.254)
		(layers "F.Cu" "B.Cu")
		(net "P12V")
	)
	(via
		(at 59.80811 -328.800714)
		(size 0.508)
		(drill 0.254)
		(layers "F.Cu" "B.Cu")
		(net "P12V")
	)
	(via
		(at 60.640214 -43.975274)
		(size 0.508)
		(drill 0.254)
		(layers "F.Cu" "B.Cu")
		(net "P12V")
	)
	(via
		(at 60.201048 -195.821046)
		(size 0.508)
		(drill 0.254)
		(layers "F.Cu" "B.Cu")
		(net "P12V")
	)
	(via
		(at 41.018968 -432.758088)
		(size 0.508)
		(drill 0.254)
		(layers "F.Cu" "B.Cu")
		(net "P12V")
	)
	(via
		(at 39.947088 -155.847796)
		(size 0.508)
		(drill 0.254)
		(layers "F.Cu" "B.Cu")
		(net "P12V")
	)
	(via
		(at 62.885828 -521.035788)
		(size 0.508)
		(drill 0.254)
		(layers "F.Cu" "B.Cu")
		(net "P12V")
	)
	(via
		(at 61.615828 -522.9987)
		(size 0.508)
		(drill 0.254)
		(layers "F.Cu" "B.Cu")
		(net "P12V")
	)
	(via
		(at 66.278506 -393.19454)
		(size 0.508)
		(drill 0.254)
		(layers "F.Cu" "B.Cu")
		(net "P12V")
	)
	(via
		(at 81.823306 -135.330946)
		(size 0.508)
		(drill 0.254)
		(layers "F.Cu" "B.Cu")
		(net "P12V")
	)
	(via
		(at 77.253084 -167.959532)
		(size 0.508)
		(drill 0.254)
		(layers "F.Cu" "B.Cu")
		(net "P12V")
	)
	(via
		(at 79.288386 -302.832516)
		(size 0.508)
		(drill 0.254)
		(layers "F.Cu" "B.Cu")
		(net "P12V")
	)
	(via
		(at 39.560246 -337.503262)
		(size 0.508)
		(drill 0.254)
		(layers "F.Cu" "B.Cu")
		(net "P12V")
	)
	(via
		(at 67.918584 -462.045558)
		(size 0.508)
		(drill 0.254)
		(layers "F.Cu" "B.Cu")
		(net "P12V")
	)
	(via
		(at 57.567068 -330.70165)
		(size 0.508)
		(drill 0.254)
		(layers "F.Cu" "B.Cu")
		(net "P12V")
	)
	(via
		(at 80.819498 -170.627802)
		(size 0.508)
		(drill 0.254)
		(layers "F.Cu" "B.Cu")
		(net "P12V")
	)
	(via
		(at 71.88073 -391.47369)
		(size 0.508)
		(drill 0.254)
		(layers "F.Cu" "B.Cu")
		(net "P12V")
	)
	(via
		(at 75.113134 -302.77816)
		(size 0.508)
		(drill 0.254)
		(layers "F.Cu" "B.Cu")
		(net "P12V")
	)
	(via
		(at 64.775334 -191.714628)
		(size 0.508)
		(drill 0.254)
		(layers "F.Cu" "B.Cu")
		(net "P12V")
	)
	(via
		(at 61.615828 -521.035788)
		(size 0.508)
		(drill 0.254)
		(layers "F.Cu" "B.Cu")
		(net "P12V")
	)
	(via
		(at 67.207384 -58.973466)
		(size 0.508)
		(drill 0.254)
		(layers "F.Cu" "B.Cu")
		(net "P12V")
	)
	(via
		(at 76.336398 -135.248904)
		(size 0.508)
		(drill 0.254)
		(layers "F.Cu" "B.Cu")
		(net "P12V")
	)
	(via
		(at 67.975988 -325.86803)
		(size 0.508)
		(drill 0.254)
		(layers "F.Cu" "B.Cu")
		(net "P12V")
	)
	(via
		(at 56.279542 -518.66419)
		(size 0.508)
		(drill 0.254)
		(layers "F.Cu" "B.Cu")
		(net "P12V")
	)
	(via
		(at 84.52485 -86.985094)
		(size 0.508)
		(drill 0.254)
		(layers "F.Cu" "B.Cu")
		(net "P12V")
	)
	(via
		(at 69.734176 -241.133376)
		(size 0.508)
		(drill 0.254)
		(layers "F.Cu" "B.Cu")
		(net "P12V")
	)
	(via
		(at 61.314584 -219.173298)
		(size 0.508)
		(drill 0.254)
		(layers "F.Cu" "B.Cu")
		(net "P12V")
	)
	(via
		(at 68.680584 -458.522324)
		(size 0.508)
		(drill 0.254)
		(layers "F.Cu" "B.Cu")
		(net "P12V")
	)
	(via
		(at 69.697346 -249.456956)
		(size 0.508)
		(drill 0.254)
		(layers "F.Cu" "B.Cu")
		(net "P12V")
	)
	(via
		(at 60.560966 -340.31936)
		(size 0.508)
		(drill 0.254)
		(layers "F.Cu" "B.Cu")
		(net "P12V")
	)
	(via
		(at 81.517744 -300.86935)
		(size 0.508)
		(drill 0.254)
		(layers "F.Cu" "B.Cu")
		(net "P12V")
	)
	(via
		(at 66.437256 -419.65372)
		(size 0.508)
		(drill 0.254)
		(layers "F.Cu" "B.Cu")
		(net "P12V")
	)
	(via
		(at 78.014322 -257.579876)
		(size 0.508)
		(drill 0.254)
		(layers "F.Cu" "B.Cu")
		(net "P12V")
	)
	(via
		(at 42.91965 -75.21956)
		(size 0.508)
		(drill 0.254)
		(layers "F.Cu" "B.Cu")
		(net "P12V")
	)
	(via
		(at 73.550526 -133.178042)
		(size 0.508)
		(drill 0.254)
		(layers "F.Cu" "B.Cu")
		(net "P12V")
	)
	(via
		(at 81.580736 -257.579876)
		(size 0.508)
		(drill 0.254)
		(layers "F.Cu" "B.Cu")
		(net "P12V")
	)
	(via
		(at 72.182228 -304.957988)
		(size 0.508)
		(drill 0.254)
		(layers "F.Cu" "B.Cu")
		(net "P12V")
	)
	(via
		(at 63.870078 -437.42356)
		(size 0.508)
		(drill 0.254)
		(layers "F.Cu" "B.Cu")
		(net "P12V")
	)
	(via
		(at 76.336398 -133.105398)
		(size 0.508)
		(drill 0.254)
		(layers "F.Cu" "B.Cu")
		(net "P12V")
	)
	(via
		(at 71.88073 -393.24026)
		(size 0.508)
		(drill 0.254)
		(layers "F.Cu" "B.Cu")
		(net "P12V")
	)
	(via
		(at 75.11161 -375.945146)
		(size 0.508)
		(drill 0.254)
		(layers "F.Cu" "B.Cu")
		(net "P12V")
	)
	(via
		(at 79.365856 -375.945908)
		(size 0.508)
		(drill 0.254)
		(layers "F.Cu" "B.Cu")
		(net "P12V")
	)
	(via
		(at 79.96174 -487.001312)
		(size 0.508)
		(drill 0.254)
		(layers "F.Cu" "B.Cu")
		(net "P12V")
	)
	(via
		(at 77.137514 -302.832516)
		(size 0.508)
		(drill 0.254)
		(layers "F.Cu" "B.Cu")
		(net "P12V")
	)
	(via
		(at 69.730874 -104.213406)
		(size 0.508)
		(drill 0.254)
		(layers "F.Cu" "B.Cu")
		(net "P12V")
	)
	(via
		(at 40.709088 -160.887664)
		(size 0.508)
		(drill 0.254)
		(layers "F.Cu" "B.Cu")
		(net "P12V")
	)
	(via
		(at 64.977772 -68.119752)
		(size 0.508)
		(drill 0.254)
		(layers "F.Cu" "B.Cu")
		(net "P12V")
	)
	(via
		(at 66.740786 -433.5653)
		(size 0.508)
		(drill 0.254)
		(layers "F.Cu" "B.Cu")
		(net "P12V")
	)
	(via
		(at 56.442356 -326.967088)
		(size 0.508)
		(drill 0.254)
		(layers "F.Cu" "B.Cu")
		(net "P12V")
	)
	(via
		(at 73.177908 -13.955776)
		(size 0.508)
		(drill 0.254)
		(layers "F.Cu" "B.Cu")
		(net "P12V")
	)
	(via
		(at 64.215772 -56.302656)
		(size 0.508)
		(drill 0.254)
		(layers "F.Cu" "B.Cu")
		(net "P12V")
	)
	(via
		(at 60.081414 -525.142206)
		(size 0.508)
		(drill 0.254)
		(layers "F.Cu" "B.Cu")
		(net "P12V")
	)
	(via
		(at 63.936372 -425.854622)
		(size 0.508)
		(drill 0.254)
		(layers "F.Cu" "B.Cu")
		(net "P12V")
	)
	(via
		(at 72.64273 -391.47369)
		(size 0.508)
		(drill 0.254)
		(layers "F.Cu" "B.Cu")
		(net "P12V")
	)
	(via
		(at 86.567264 -80.933036)
		(size 0.508)
		(drill 0.254)
		(layers "F.Cu" "B.Cu")
		(net "P12V")
	)
	(via
		(at 59.108086 -285.7246)
		(size 0.508)
		(drill 0.254)
		(layers "F.Cu" "B.Cu")
		(net "P12V")
	)
	(via
		(at 74.359516 -485.198928)
		(size 0.508)
		(drill 0.254)
		(layers "F.Cu" "B.Cu")
		(net "P12V")
	)
	(via
		(at 64.215772 -61.641736)
		(size 0.508)
		(drill 0.254)
		(layers "F.Cu" "B.Cu")
		(net "P12V")
	)
	(via
		(at 66.437256 -417.282122)
		(size 0.508)
		(drill 0.254)
		(layers "F.Cu" "B.Cu")
		(net "P12V")
	)
	(via
		(at 79.457042 -372.364508)
		(size 0.508)
		(drill 0.254)
		(layers "F.Cu" "B.Cu")
		(net "P12V")
	)
	(via
		(at 66.922142 -290.990782)
		(size 0.508)
		(drill 0.254)
		(layers "F.Cu" "B.Cu")
		(net "P12V")
	)
	(via
		(at 42.341546 -247.122696)
		(size 0.508)
		(drill 0.254)
		(layers "F.Cu" "B.Cu")
		(net "P12V")
	)
	(via
		(at 63.618872 -462.044796)
		(size 0.508)
		(drill 0.254)
		(layers "F.Cu" "B.Cu")
		(net "P12V")
	)
	(via
		(at 67.84721 -521.035788)
		(size 0.508)
		(drill 0.254)
		(layers "F.Cu" "B.Cu")
		(net "P12V")
	)
	(via
		(at 67.84721 -525.142206)
		(size 0.508)
		(drill 0.254)
		(layers "F.Cu" "B.Cu")
		(net "P12V")
	)
	(via
		(at 86.567264 -86.985094)
		(size 0.508)
		(drill 0.254)
		(layers "F.Cu" "B.Cu")
		(net "P12V")
	)
	(via
		(at 70.851776 -147.68576)
		(size 0.508)
		(drill 0.254)
		(layers "F.Cu" "B.Cu")
		(net "P12V")
	)
	(via
		(at 67.860164 -147.68576)
		(size 0.508)
		(drill 0.254)
		(layers "F.Cu" "B.Cu")
		(net "P12V")
	)
	(via
		(at 64.215772 -65.976246)
		(size 0.508)
		(drill 0.254)
		(layers "F.Cu" "B.Cu")
		(net "P12V")
	)
	(via
		(at 40.322246 -332.164182)
		(size 0.508)
		(drill 0.254)
		(layers "F.Cu" "B.Cu")
		(net "P12V")
	)
	(via
		(at 70.851776 -145.450306)
		(size 0.508)
		(drill 0.254)
		(layers "F.Cu" "B.Cu")
		(net "P12V")
	)
	(via
		(at 59.108086 -291.06368)
		(size 0.508)
		(drill 0.254)
		(layers "F.Cu" "B.Cu")
		(net "P12V")
	)
	(via
		(at 66.742564 -241.133376)
		(size 0.508)
		(drill 0.254)
		(layers "F.Cu" "B.Cu")
		(net "P12V")
	)
	(via
		(at 66.125598 -525.142206)
		(size 0.508)
		(drill 0.254)
		(layers "F.Cu" "B.Cu")
		(net "P12V")
	)
	(via
		(at 67.207384 -68.119752)
		(size 0.508)
		(drill 0.254)
		(layers "F.Cu" "B.Cu")
		(net "P12V")
	)
	(via
		(at 65.242694 -41.831768)
		(size 0.508)
		(drill 0.254)
		(layers "F.Cu" "B.Cu")
		(net "P12V")
	)
	(via
		(at 78.526386 -300.869604)
		(size 0.508)
		(drill 0.254)
		(layers "F.Cu" "B.Cu")
		(net "P12V")
	)
	(via
		(at 65.648586 -467.38286)
		(size 0.508)
		(drill 0.254)
		(layers "F.Cu" "B.Cu")
		(net "P12V")
	)
	(via
		(at 59.798966 -340.31936)
		(size 0.508)
		(drill 0.254)
		(layers "F.Cu" "B.Cu")
		(net "P12V")
	)
	(via
		(at 65.242694 -43.975274)
		(size 0.508)
		(drill 0.254)
		(layers "F.Cu" "B.Cu")
		(net "P12V")
	)
	(via
		(at 67.57416 -106.845354)
		(size 0.508)
		(drill 0.254)
		(layers "F.Cu" "B.Cu")
		(net "P12V")
	)
	(via
		(at 65.171574 -330.907898)
		(size 0.508)
		(drill 0.254)
		(layers "F.Cu" "B.Cu")
		(net "P12V")
	)
	(via
		(at 65.694306 -460.278226)
		(size 0.508)
		(drill 0.254)
		(layers "F.Cu" "B.Cu")
		(net "P12V")
	)
	(via
		(at 66.740786 -425.854622)
		(size 0.508)
		(drill 0.254)
		(layers "F.Cu" "B.Cu")
		(net "P12V")
	)
	(via
		(at 63.013082 -39.868856)
		(size 0.508)
		(drill 0.254)
		(layers "F.Cu" "B.Cu")
		(net "P12V")
	)
	(via
		(at 75.11161 -379.46838)
		(size 0.508)
		(drill 0.254)
		(layers "F.Cu" "B.Cu")
		(net "P12V")
	)
	(via
		(at 67.040506 -389.671306)
		(size 0.508)
		(drill 0.254)
		(layers "F.Cu" "B.Cu")
		(net "P12V")
	)
	(via
		(at 78.03261 -488.767882)
		(size 0.508)
		(drill 0.254)
		(layers "F.Cu" "B.Cu")
		(net "P12V")
	)
	(via
		(at 55.671212 -338.409534)
		(size 0.508)
		(drill 0.254)
		(layers "F.Cu" "B.Cu")
		(net "P12V")
	)
	(via
		(at 78.79461 -485.244648)
		(size 0.508)
		(drill 0.254)
		(layers "F.Cu" "B.Cu")
		(net "P12V")
	)
	(via
		(at 78.027276 -259.246878)
		(size 0.508)
		(drill 0.254)
		(layers "F.Cu" "B.Cu")
		(net "P12V")
	)
	(via
		(at 66.437256 -414.613852)
		(size 0.508)
		(drill 0.254)
		(layers "F.Cu" "B.Cu")
		(net "P12V")
	)
	(via
		(at 63.013082 -41.069768)
		(size 0.508)
		(drill 0.254)
		(layers "F.Cu" "B.Cu")
		(net "P12V")
	)
	(via
		(at 62.401958 -285.7246)
		(size 0.508)
		(drill 0.254)
		(layers "F.Cu" "B.Cu")
		(net "P12V")
	)
	(via
		(at 63.573152 -465.61629)
		(size 0.508)
		(drill 0.254)
		(layers "F.Cu" "B.Cu")
		(net "P12V")
	)
	(via
		(at 68.589398 -463.860388)
		(size 0.508)
		(drill 0.254)
		(layers "F.Cu" "B.Cu")
		(net "P12V")
	)
	(via
		(at 41.015666 -199.171814)
		(size 0.508)
		(drill 0.254)
		(layers "F.Cu" "B.Cu")
		(net "P12V")
	)
	(via
		(at 61.712094 -330.70165)
		(size 0.508)
		(drill 0.254)
		(layers "F.Cu" "B.Cu")
		(net "P12V")
	)
	(via
		(at 69.9516 -393.24026)
		(size 0.508)
		(drill 0.254)
		(layers "F.Cu" "B.Cu")
		(net "P12V")
	)
	(via
		(at 82.585306 -135.330946)
		(size 0.508)
		(drill 0.254)
		(layers "F.Cu" "B.Cu")
		(net "P12V")
	)
	(via
		(at 67.040506 -391.42797)
		(size 0.508)
		(drill 0.254)
		(layers "F.Cu" "B.Cu")
		(net "P12V")
	)
	(via
		(at 80.755744 -300.86935)
		(size 0.508)
		(drill 0.254)
		(layers "F.Cu" "B.Cu")
		(net "P12V")
	)
	(via
		(at 60.895484 -106.908092)
		(size 0.508)
		(drill 0.254)
		(layers "F.Cu" "B.Cu")
		(net "P12V")
	)
	(via
		(at 56.442356 -328.800714)
		(size 0.508)
		(drill 0.254)
		(layers "F.Cu" "B.Cu")
		(net "P12V")
	)
	(via
		(at 72.64273 -393.24026)
		(size 0.508)
		(drill 0.254)
		(layers "F.Cu" "B.Cu")
		(net "P12V")
	)
	(via
		(at 74.312526 -133.178042)
		(size 0.508)
		(drill 0.254)
		(layers "F.Cu" "B.Cu")
		(net "P12V")
	)
	(via
		(at 75.15733 -372.363746)
		(size 0.508)
		(drill 0.254)
		(layers "F.Cu" "B.Cu")
		(net "P12V")
	)
	(via
		(at 60.57011 -330.70165)
		(size 0.508)
		(drill 0.254)
		(layers "F.Cu" "B.Cu")
		(net "P12V")
	)
	(via
		(at 55.303928 -41.069768)
		(size 0.508)
		(drill 0.254)
		(layers "F.Cu" "B.Cu")
		(net "P12V")
	)
	(via
		(at 55.714646 -332.466696)
		(size 0.508)
		(drill 0.254)
		(layers "F.Cu" "B.Cu")
		(net "P12V")
	)
	(via
		(at 57.567068 -328.800714)
		(size 0.508)
		(drill 0.254)
		(layers "F.Cu" "B.Cu")
		(net "P12V")
	)
	(via
		(at 59.8424 -332.466696)
		(size 0.508)
		(drill 0.254)
		(layers "F.Cu" "B.Cu")
		(net "P12V")
	)
	(via
		(at 40.709088 -162.850576)
		(size 0.508)
		(drill 0.254)
		(layers "F.Cu" "B.Cu")
		(net "P12V")
	)
	(via
		(at 63.173356 -101.605334)
		(size 0.508)
		(drill 0.254)
		(layers "F.Cu" "B.Cu")
		(net "P12V")
	)
	(via
		(at 69.730874 -106.881676)
		(size 0.508)
		(drill 0.254)
		(layers "F.Cu" "B.Cu")
		(net "P12V")
	)
	(via
		(at 78.015084 -172.9994)
		(size 0.508)
		(drill 0.254)
		(layers "F.Cu" "B.Cu")
		(net "P12V")
	)
	(via
		(at 61.615828 -525.142206)
		(size 0.508)
		(drill 0.254)
		(layers "F.Cu" "B.Cu")
		(net "P12V")
	)
	(via
		(at 87.308436 -79.24292)
		(size 0.508)
		(drill 0.254)
		(layers "F.Cu" "B.Cu")
		(net "P12V")
	)
	(via
		(at 64.625982 -288.358834)
		(size 0.508)
		(drill 0.254)
		(layers "F.Cu" "B.Cu")
		(net "P12V")
	)
	(via
		(at 62.474094 -330.70165)
		(size 0.508)
		(drill 0.254)
		(layers "F.Cu" "B.Cu")
		(net "P12V")
	)
	(via
		(at 81.823306 -133.18744)
		(size 0.508)
		(drill 0.254)
		(layers "F.Cu" "B.Cu")
		(net "P12V")
	)
	(via
		(at 77.253084 -177.105818)
		(size 0.508)
		(drill 0.254)
		(layers "F.Cu" "B.Cu")
		(net "P12V")
	)
	(via
		(at 80.464914 -135.349234)
		(size 0.508)
		(drill 0.254)
		(layers "F.Cu" "B.Cu")
		(net "P12V")
	)
	(via
		(at 67.975988 -323.19722)
		(size 0.508)
		(drill 0.254)
		(layers "F.Cu" "B.Cu")
		(net "P12V")
	)
	(via
		(at 58.319924 -334.477868)
		(size 0.508)
		(drill 0.254)
		(layers "F.Cu" "B.Cu")
		(net "P12V")
	)
	(via
		(at 67.860164 -152.725628)
		(size 0.508)
		(drill 0.254)
		(layers "F.Cu" "B.Cu")
		(net "P12V")
	)
	(via
		(at 67.207384 -56.302656)
		(size 0.508)
		(drill 0.254)
		(layers "F.Cu" "B.Cu")
		(net "P12V")
	)
	(via
		(at 64.380872 -462.044796)
		(size 0.508)
		(drill 0.254)
		(layers "F.Cu" "B.Cu")
		(net "P12V")
	)
	(via
		(at 55.303928 -39.868856)
		(size 0.508)
		(drill 0.254)
		(layers "F.Cu" "B.Cu")
		(net "P12V")
	)
	(via
		(at 80.057498 -177.105818)
		(size 0.508)
		(drill 0.254)
		(layers "F.Cu" "B.Cu")
		(net "P12V")
	)
	(via
		(at 64.215772 -58.973466)
		(size 0.508)
		(drill 0.254)
		(layers "F.Cu" "B.Cu")
		(net "P12V")
	)
	(via
		(at 77.997812 -255.854962)
		(size 0.508)
		(drill 0.254)
		(layers "F.Cu" "B.Cu")
		(net "P12V")
	)
	(via
		(at 60.640214 -39.868856)
		(size 0.508)
		(drill 0.254)
		(layers "F.Cu" "B.Cu")
		(net "P12V")
	)
	(via
		(at 40.709088 -153.612342)
		(size 0.508)
		(drill 0.254)
		(layers "F.Cu" "B.Cu")
		(net "P12V")
	)
	(via
		(at 65.933574 -330.907898)
		(size 0.508)
		(drill 0.254)
		(layers "F.Cu" "B.Cu")
		(net "P12V")
	)
	(via
		(at 70.7136 -389.717026)
		(size 0.508)
		(drill 0.254)
		(layers "F.Cu" "B.Cu")
		(net "P12V")
	)
	(via
		(at 75.113134 -304.921666)
		(size 0.508)
		(drill 0.254)
		(layers "F.Cu" "B.Cu")
		(net "P12V")
	)
	(via
		(at 41.509696 -254.90678)
		(size 0.508)
		(drill 0.254)
		(layers "F.Cu" "B.Cu")
		(net "P12V")
	)
	(via
		(at 55.303928 -43.975274)
		(size 0.508)
		(drill 0.254)
		(layers "F.Cu" "B.Cu")
		(net "P12V")
	)
	(via
		(at 65.423288 -100.74402)
		(size 0.508)
		(drill 0.254)
		(layers "F.Cu" "B.Cu")
		(net "P12V")
	)
	(via
		(at 66.160142 -290.990782)
		(size 0.508)
		(drill 0.254)
		(layers "F.Cu" "B.Cu")
		(net "P12V")
	)
	(via
		(at 66.922142 -285.651702)
		(size 0.508)
		(drill 0.254)
		(layers "F.Cu" "B.Cu")
		(net "P12V")
	)
	(via
		(at 80.72374 -485.244648)
		(size 0.508)
		(drill 0.254)
		(layers "F.Cu" "B.Cu")
		(net "P12V")
	)
	(via
		(at 65.933574 -332.87081)
		(size 0.508)
		(drill 0.254)
		(layers "F.Cu" "B.Cu")
		(net "P12V")
	)
	(via
		(at 77.253084 -174.962312)
		(size 0.508)
		(drill 0.254)
		(layers "F.Cu" "B.Cu")
		(net "P12V")
	)
	(via
		(at 76.375514 -302.832516)
		(size 0.508)
		(drill 0.254)
		(layers "F.Cu" "B.Cu")
		(net "P12V")
	)
	(via
		(at 77.461364 -131.170426)
		(size 0.508)
		(drill 0.254)
		(layers "F.Cu" "B.Cu")
		(net "P12V")
	)
	(via
		(at 62.508384 -332.466696)
		(size 0.508)
		(drill 0.254)
		(layers "F.Cu" "B.Cu")
		(net "P12V")
	)
	(via
		(at 79.365856 -377.702572)
		(size 0.508)
		(drill 0.254)
		(layers "F.Cu" "B.Cu")
		(net "P12V")
	)
	(via
		(at 64.335152 -463.859626)
		(size 0.508)
		(drill 0.254)
		(layers "F.Cu" "B.Cu")
		(net "P12V")
	)
	(via
		(at 60.081414 -515.99592)
		(size 0.508)
		(drill 0.254)
		(layers "F.Cu" "B.Cu")
		(net "P12V")
	)
	(via
		(at 65.171574 -323.19722)
		(size 0.508)
		(drill 0.254)
		(layers "F.Cu" "B.Cu")
		(net "P12V")
	)
	(via
		(at 57.601358 -332.466696)
		(size 0.508)
		(drill 0.254)
		(layers "F.Cu" "B.Cu")
		(net "P12V")
	)
	(via
		(at 69.9516 -389.717026)
		(size 0.508)
		(drill 0.254)
		(layers "F.Cu" "B.Cu")
		(net "P12V")
	)
	(via
		(at 68.589398 -465.617052)
		(size 0.508)
		(drill 0.254)
		(layers "F.Cu" "B.Cu")
		(net "P12V")
	)
	(via
		(at 63.863982 -285.688024)
		(size 0.508)
		(drill 0.254)
		(layers "F.Cu" "B.Cu")
		(net "P12V")
	)
	(via
		(at 66.456306 -458.521562)
		(size 0.508)
		(drill 0.254)
		(layers "F.Cu" "B.Cu")
		(net "P12V")
	)
	(via
		(at 42.91965 -67.508882)
		(size 0.508)
		(drill 0.254)
		(layers "F.Cu" "B.Cu")
		(net "P12V")
	)
	(via
		(at 60.57011 -328.800714)
		(size 0.508)
		(drill 0.254)
		(layers "F.Cu" "B.Cu")
		(net "P12V")
	)
	(via
		(at 79.702914 -135.349234)
		(size 0.508)
		(drill 0.254)
		(layers "F.Cu" "B.Cu")
		(net "P12V")
	)
	(via
		(at 67.827398 -465.617052)
		(size 0.508)
		(drill 0.254)
		(layers "F.Cu" "B.Cu")
		(net "P12V")
	)
	(via
		(at 79.288386 -300.869604)
		(size 0.508)
		(drill 0.254)
		(layers "F.Cu" "B.Cu")
		(net "P12V")
	)
	(via
		(at 70.459346 -251.600462)
		(size 0.508)
		(drill 0.254)
		(layers "F.Cu" "B.Cu")
		(net "P12V")
	)
	(via
		(at 79.96174 -485.244648)
		(size 0.508)
		(drill 0.254)
		(layers "F.Cu" "B.Cu")
		(net "P12V")
	)
	(via
		(at 57.8358 -39.106856)
		(size 0.508)
		(drill 0.254)
		(layers "F.Cu" "B.Cu")
		(net "P12V")
	)
	(via
		(at 57.8358 -41.069768)
		(size 0.508)
		(drill 0.254)
		(layers "F.Cu" "B.Cu")
		(net "P12V")
	)
	(via
		(at 67.84721 -515.99592)
		(size 0.508)
		(drill 0.254)
		(layers "F.Cu" "B.Cu")
		(net "P12V")
	)
	(via
		(at 87.306404 -88.55837)
		(size 0.508)
		(drill 0.254)
		(layers "F.Cu" "B.Cu")
		(net "P12V")
	)
	(via
		(at 60.895484 -103.477822)
		(size 0.508)
		(drill 0.254)
		(layers "F.Cu" "B.Cu")
		(net "P12V")
	)
	(via
		(at 81.54416 -262.564372)
		(size 0.508)
		(drill 0.254)
		(layers "F.Cu" "B.Cu")
		(net "P12V")
	)
	(via
		(at 81.564226 -255.854962)
		(size 0.508)
		(drill 0.254)
		(layers "F.Cu" "B.Cu")
		(net "P12V")
	)
	(via
		(at 82.585306 -133.18744)
		(size 0.508)
		(drill 0.254)
		(layers "F.Cu" "B.Cu")
		(net "P12V")
	)
	(via
		(at 68.534534 -288.286444)
		(size 0.508)
		(drill 0.254)
		(layers "F.Cu" "B.Cu")
		(net "P12V")
	)
	(via
		(at 59.108086 -288.39541)
		(size 0.508)
		(drill 0.254)
		(layers "F.Cu" "B.Cu")
		(net "P12V")
	)
	(via
		(at 62.46495 -340.31936)
		(size 0.508)
		(drill 0.254)
		(layers "F.Cu" "B.Cu")
		(net "P12V")
	)
	(via
		(at 77.253084 -170.627802)
		(size 0.508)
		(drill 0.254)
		(layers "F.Cu" "B.Cu")
		(net "P12V")
	)
	(via
		(at 63.936372 -431.193702)
		(size 0.508)
		(drill 0.254)
		(layers "F.Cu" "B.Cu")
		(net "P12V")
	)
	(via
		(at 60.552584 -217.210386)
		(size 0.508)
		(drill 0.254)
		(layers "F.Cu" "B.Cu")
		(net "P12V")
	)
	(via
		(at 64.775334 -193.67754)
		(size 0.508)
		(drill 0.254)
		(layers "F.Cu" "B.Cu")
		(net "P12V")
	)
	(via
		(at 67.57416 -104.177084)
		(size 0.508)
		(drill 0.254)
		(layers "F.Cu" "B.Cu")
		(net "P12V")
	)
	(via
		(at 67.436492 -437.42356)
		(size 0.508)
		(drill 0.254)
		(layers "F.Cu" "B.Cu")
		(net "P12V")
	)
	(via
		(at 72.182228 -302.814482)
		(size 0.508)
		(drill 0.254)
		(layers "F.Cu" "B.Cu")
		(net "P12V")
	)
	(via
		(at 56.279542 -513.32511)
		(size 0.508)
		(drill 0.254)
		(layers "F.Cu" "B.Cu")
		(net "P12V")
	)
	(via
		(at 72.64273 -389.717026)
		(size 0.508)
		(drill 0.254)
		(layers "F.Cu" "B.Cu")
		(net "P12V")
	)
	(via
		(at 80.72374 -487.001312)
		(size 0.508)
		(drill 0.254)
		(layers "F.Cu" "B.Cu")
		(net "P12V")
	)
	(via
		(at 67.827398 -463.860388)
		(size 0.508)
		(drill 0.254)
		(layers "F.Cu" "B.Cu")
		(net "P12V")
	)
	(via
		(at 68.737988 -328.5363)
		(size 0.508)
		(drill 0.254)
		(layers "F.Cu" "B.Cu")
		(net "P12V")
	)
	(via
		(at 62.46495 -334.477868)
		(size 0.508)
		(drill 0.254)
		(layers "F.Cu" "B.Cu")
		(net "P12V")
	)
	(via
		(at 74.34961 -375.945146)
		(size 0.508)
		(drill 0.254)
		(layers "F.Cu" "B.Cu")
		(net "P12V")
	)
	(via
		(at 59.798966 -338.409534)
		(size 0.508)
		(drill 0.254)
		(layers "F.Cu" "B.Cu")
		(net "P12V")
	)
	(via
		(at 41.018968 -430.614582)
		(size 0.508)
		(drill 0.254)
		(layers "F.Cu" "B.Cu")
		(net "P12V")
	)
	(via
		(at 69.697346 -251.600462)
		(size 0.508)
		(drill 0.254)
		(layers "F.Cu" "B.Cu")
		(net "P12V")
	)
	(via
		(at 66.705734 -251.600462)
		(size 0.508)
		(drill 0.254)
		(layers "F.Cu" "B.Cu")
		(net "P12V")
	)
	(via
		(at 76.288646 -486.955592)
		(size 0.508)
		(drill 0.254)
		(layers "F.Cu" "B.Cu")
		(net "P12V")
	)
	(via
		(at 62.46495 -336.36839)
		(size 0.508)
		(drill 0.254)
		(layers "F.Cu" "B.Cu")
		(net "P12V")
	)
	(via
		(at 67.098164 -154.68854)
		(size 0.508)
		(drill 0.254)
		(layers "F.Cu" "B.Cu")
		(net "P12V")
	)
	(via
		(at 40.709088 -155.847796)
		(size 0.508)
		(drill 0.254)
		(layers "F.Cu" "B.Cu")
		(net "P12V")
	)
	(via
		(at 87.329264 -80.933036)
		(size 0.508)
		(drill 0.254)
		(layers "F.Cu" "B.Cu")
		(net "P12V")
	)
	(via
		(at 39.947088 -160.887664)
		(size 0.508)
		(drill 0.254)
		(layers "F.Cu" "B.Cu")
		(net "P12V")
	)
	(via
		(at 72.182228 -300.85157)
		(size 0.508)
		(drill 0.254)
		(layers "F.Cu" "B.Cu")
		(net "P12V")
	)
	(via
		(at 72.944228 -300.85157)
		(size 0.508)
		(drill 0.254)
		(layers "F.Cu" "B.Cu")
		(net "P12V")
	)
	(via
		(at 76.470764 -374.130316)
		(size 0.508)
		(drill 0.254)
		(layers "F.Cu" "B.Cu")
		(net "P12V")
	)
	(via
		(at 63.173356 -104.276144)
		(size 0.508)
		(drill 0.254)
		(layers "F.Cu" "B.Cu")
		(net "P12V")
	)
	(via
		(at 55.671212 -340.31936)
		(size 0.508)
		(drill 0.254)
		(layers "F.Cu" "B.Cu")
		(net "P12V")
	)
	(via
		(at 78.772766 -260.878574)
		(size 0.508)
		(drill 0.254)
		(layers "F.Cu" "B.Cu")
		(net "P12V")
	)
	(via
		(at 55.680356 -328.800714)
		(size 0.508)
		(drill 0.254)
		(layers "F.Cu" "B.Cu")
		(net "P12V")
	)
	(via
		(at 57.557924 -340.31936)
		(size 0.508)
		(drill 0.254)
		(layers "F.Cu" "B.Cu")
		(net "P12V")
	)
	(via
		(at 63.573152 -467.38286)
		(size 0.508)
		(drill 0.254)
		(layers "F.Cu" "B.Cu")
		(net "P12V")
	)
	(via
		(at 42.341546 -249.793506)
		(size 0.508)
		(drill 0.254)
		(layers "F.Cu" "B.Cu")
		(net "P12V")
	)
	(via
		(at 62.885828 -515.99592)
		(size 0.508)
		(drill 0.254)
		(layers "F.Cu" "B.Cu")
		(net "P12V")
	)
	(via
		(at 41.579546 -247.122696)
		(size 0.508)
		(drill 0.254)
		(layers "F.Cu" "B.Cu")
		(net "P12V")
	)
	(via
		(at 69.734176 -243.804186)
		(size 0.508)
		(drill 0.254)
		(layers "F.Cu" "B.Cu")
		(net "P12V")
	)
	(via
		(at 40.709088 -164.994082)
		(size 0.508)
		(drill 0.254)
		(layers "F.Cu" "B.Cu")
		(net "P12V")
	)
	(via
		(at 68.979288 -12.337288)
		(size 0.508)
		(drill 0.254)
		(layers "F.Cu" "B.Cu")
		(net "P12V")
	)
	(via
		(at 66.160142 -288.322512)
		(size 0.508)
		(drill 0.254)
		(layers "F.Cu" "B.Cu")
		(net "P12V")
	)
	(via
		(at 63.936372 -428.525432)
		(size 0.508)
		(drill 0.254)
		(layers "F.Cu" "B.Cu")
		(net "P12V")
	)
	(via
		(at 66.445384 -61.641736)
		(size 0.508)
		(drill 0.254)
		(layers "F.Cu" "B.Cu")
		(net "P12V")
	)
	(via
		(at 79.457042 -374.131078)
		(size 0.508)
		(drill 0.254)
		(layers "F.Cu" "B.Cu")
		(net "P12V")
	)
	(via
		(at 41.509696 -259.013198)
		(size 0.508)
		(drill 0.254)
		(layers "F.Cu" "B.Cu")
		(net "P12V")
	)
	(via
		(at 40.256968 -426.280072)
		(size 0.508)
		(drill 0.254)
		(layers "F.Cu" "B.Cu")
		(net "P12V")
	)
	(via
		(at 66.740786 -431.193702)
		(size 0.508)
		(drill 0.254)
		(layers "F.Cu" "B.Cu")
		(net "P12V")
	)
	(via
		(at 75.15733 -370.607082)
		(size 0.508)
		(drill 0.254)
		(layers "F.Cu" "B.Cu")
		(net "P12V")
	)
	(via
		(at 59.80811 -330.70165)
		(size 0.508)
		(drill 0.254)
		(layers "F.Cu" "B.Cu")
		(net "P12V")
	)
	(via
		(at 66.456306 -460.278226)
		(size 0.508)
		(drill 0.254)
		(layers "F.Cu" "B.Cu")
		(net "P12V")
	)
	(via
		(at 65.171574 -332.87081)
		(size 0.508)
		(drill 0.254)
		(layers "F.Cu" "B.Cu")
		(net "P12V")
	)
	(via
		(at 76.288646 -485.198928)
		(size 0.508)
		(drill 0.254)
		(layers "F.Cu" "B.Cu")
		(net "P12V")
	)
	(via
		(at 70.459346 -247.494044)
		(size 0.508)
		(drill 0.254)
		(layers "F.Cu" "B.Cu")
		(net "P12V")
	)
	(via
		(at 61.314584 -217.210386)
		(size 0.508)
		(drill 0.254)
		(layers "F.Cu" "B.Cu")
		(net "P12V")
	)
	(via
		(at 87.329264 -85.159088)
		(size 0.508)
		(drill 0.254)
		(layers "F.Cu" "B.Cu")
		(net "P12V")
	)
	(via
		(at 68.666868 -423.760138)
		(size 0.508)
		(drill 0.254)
		(layers "F.Cu" "B.Cu")
		(net "P12V")
	)
	(via
		(at 65.167764 -14.717776)
		(size 0.508)
		(drill 0.254)
		(layers "F.Cu" "B.Cu")
		(net "P12V")
	)
	(via
		(at 66.742564 -245.644924)
		(size 0.508)
		(drill 0.254)
		(layers "F.Cu" "B.Cu")
		(net "P12V")
	)
	(via
		(at 64.306196 -221.316804)
		(size 0.508)
		(drill 0.254)
		(layers "F.Cu" "B.Cu")
		(net "P12V")
	)
	(via
		(at 60.895484 -100.807012)
		(size 0.508)
		(drill 0.254)
		(layers "F.Cu" "B.Cu")
		(net "P12V")
	)
	(via
		(at 68.666868 -419.65372)
		(size 0.508)
		(drill 0.254)
		(layers "F.Cu" "B.Cu")
		(net "P12V")
	)
	(via
		(at 71.057516 -12.337288)
		(size 0.508)
		(drill 0.254)
		(layers "F.Cu" "B.Cu")
		(net "P12V")
	)
	(via
		(at 42.91965 -77.182472)
		(size 0.508)
		(drill 0.254)
		(layers "F.Cu" "B.Cu")
		(net "P12V")
	)
	(via
		(at 64.775334 -195.821046)
		(size 0.508)
		(drill 0.254)
		(layers "F.Cu" "B.Cu")
		(net "P12V")
	)
	(via
		(at 61.712094 -328.800714)
		(size 0.508)
		(drill 0.254)
		(layers "F.Cu" "B.Cu")
		(net "P12V")
	)
	(via
		(at 58.319924 -338.409534)
		(size 0.508)
		(drill 0.254)
		(layers "F.Cu" "B.Cu")
		(net "P12V")
	)
	(via
		(at 65.167764 -16.624046)
		(size 0.508)
		(drill 0.254)
		(layers "F.Cu" "B.Cu")
		(net "P12V")
	)
	(via
		(at 74.312526 -131.21513)
		(size 0.508)
		(drill 0.254)
		(layers "F.Cu" "B.Cu")
		(net "P12V")
	)
	(via
		(at 80.819498 -177.105818)
		(size 0.508)
		(drill 0.254)
		(layers "F.Cu" "B.Cu")
		(net "P12V")
	)
	(via
		(at 67.098164 -152.725628)
		(size 0.508)
		(drill 0.254)
		(layers "F.Cu" "B.Cu")
		(net "P12V")
	)
	(via
		(at 57.8358 -41.831768)
		(size 0.508)
		(drill 0.254)
		(layers "F.Cu" "B.Cu")
		(net "P12V")
	)
	(via
		(at 60.640214 -41.069768)
		(size 0.508)
		(drill 0.254)
		(layers "F.Cu" "B.Cu")
		(net "P12V")
	)
	(via
		(at 77.050646 -485.198928)
		(size 0.508)
		(drill 0.254)
		(layers "F.Cu" "B.Cu")
		(net "P12V")
	)
	(via
		(at 60.081414 -513.32511)
		(size 0.508)
		(drill 0.254)
		(layers "F.Cu" "B.Cu")
		(net "P12V")
	)
	(via
		(at 69.11721 -513.32511)
		(size 0.508)
		(drill 0.254)
		(layers "F.Cu" "B.Cu")
		(net "P12V")
	)
	(via
		(at 70.089776 -145.450306)
		(size 0.508)
		(drill 0.254)
		(layers "F.Cu" "B.Cu")
		(net "P12V")
	)
	(via
		(at 62.73292 -195.821046)
		(size 0.508)
		(drill 0.254)
		(layers "F.Cu" "B.Cu")
		(net "P12V")
	)
	(via
		(at 70.496176 -245.644924)
		(size 0.508)
		(drill 0.254)
		(layers "F.Cu" "B.Cu")
		(net "P12V")
	)
	(via
		(at 67.467734 -249.456956)
		(size 0.508)
		(drill 0.254)
		(layers "F.Cu" "B.Cu")
		(net "P12V")
	)
	(via
		(at 75.121516 -485.198928)
		(size 0.508)
		(drill 0.254)
		(layers "F.Cu" "B.Cu")
		(net "P12V")
	)
	(via
		(at 67.502786 -433.5653)
		(size 0.508)
		(drill 0.254)
		(layers "F.Cu" "B.Cu")
		(net "P12V")
	)
	(via
		(at 42.15765 -79.325978)
		(size 0.508)
		(drill 0.254)
		(layers "F.Cu" "B.Cu")
		(net "P12V")
	)
	(via
		(at 71.88073 -389.717026)
		(size 0.508)
		(drill 0.254)
		(layers "F.Cu" "B.Cu")
		(net "P12V")
	)
	(via
		(at 74.34961 -377.70181)
		(size 0.508)
		(drill 0.254)
		(layers "F.Cu" "B.Cu")
		(net "P12V")
	)
	(via
		(at 65.694306 -458.521562)
		(size 0.508)
		(drill 0.254)
		(layers "F.Cu" "B.Cu")
		(net "P12V")
	)
	(via
		(at 65.171574 -328.5363)
		(size 0.508)
		(drill 0.254)
		(layers "F.Cu" "B.Cu")
		(net "P12V")
	)
	(via
		(at 66.674492 -437.42356)
		(size 0.508)
		(drill 0.254)
		(layers "F.Cu" "B.Cu")
		(net "P12V")
	)
	(via
		(at 67.082416 -11.575288)
		(size 0.508)
		(drill 0.254)
		(layers "F.Cu" "B.Cu")
		(net "P12V")
	)
	(via
		(at 39.947088 -158.516066)
		(size 0.508)
		(drill 0.254)
		(layers "F.Cu" "B.Cu")
		(net "P12V")
	)
	(via
		(at 65.675256 -414.613852)
		(size 0.508)
		(drill 0.254)
		(layers "F.Cu" "B.Cu")
		(net "P12V")
	)
	(via
		(at 63.173356 -106.182414)
		(size 0.508)
		(drill 0.254)
		(layers "F.Cu" "B.Cu")
		(net "P12V")
	)
	(via
		(at 65.423288 -103.41483)
		(size 0.508)
		(drill 0.254)
		(layers "F.Cu" "B.Cu")
		(net "P12V")
	)
	(via
		(at 41.579546 -252.461776)
		(size 0.508)
		(drill 0.254)
		(layers "F.Cu" "B.Cu")
		(net "P12V")
	)
	(via
		(at 70.459346 -249.456956)
		(size 0.508)
		(drill 0.254)
		(layers "F.Cu" "B.Cu")
		(net "P12V")
	)
	(via
		(at 40.322246 -334.834992)
		(size 0.508)
		(drill 0.254)
		(layers "F.Cu" "B.Cu")
		(net "P12V")
	)
	(via
		(at 60.560966 -334.477868)
		(size 0.508)
		(drill 0.254)
		(layers "F.Cu" "B.Cu")
		(net "P12V")
	)
	(via
		(at 66.705734 -249.456956)
		(size 0.508)
		(drill 0.254)
		(layers "F.Cu" "B.Cu")
		(net "P12V")
	)
	(via
		(at 57.567068 -326.967088)
		(size 0.508)
		(drill 0.254)
		(layers "F.Cu" "B.Cu")
		(net "P12V")
	)
	(via
		(at 77.232764 -370.607082)
		(size 0.508)
		(drill 0.254)
		(layers "F.Cu" "B.Cu")
		(net "P12V")
	)
	(via
		(at 56.433212 -336.36839)
		(size 0.508)
		(drill 0.254)
		(layers "F.Cu" "B.Cu")
		(net "P12V")
	)
	(via
		(at 78.015084 -167.959532)
		(size 0.508)
		(drill 0.254)
		(layers "F.Cu" "B.Cu")
		(net "P12V")
	)
	(via
		(at 57.549542 -513.32511)
		(size 0.508)
		(drill 0.254)
		(layers "F.Cu" "B.Cu")
		(net "P12V")
	)
	(via
		(at 66.437256 -423.760138)
		(size 0.508)
		(drill 0.254)
		(layers "F.Cu" "B.Cu")
		(net "P12V")
	)
	(via
		(at 84.52485 -80.933036)
		(size 0.508)
		(drill 0.254)
		(layers "F.Cu" "B.Cu")
		(net "P12V")
	)
	(via
		(at 78.776322 -257.579876)
		(size 0.508)
		(drill 0.254)
		(layers "F.Cu" "B.Cu")
		(net "P12V")
	)
	(via
		(at 72.944228 -302.814482)
		(size 0.508)
		(drill 0.254)
		(layers "F.Cu" "B.Cu")
		(net "P12V")
	)
	(via
		(at 70.496176 -243.804186)
		(size 0.508)
		(drill 0.254)
		(layers "F.Cu" "B.Cu")
		(net "P12V")
	)
	(via
		(at 55.671212 -334.477868)
		(size 0.508)
		(drill 0.254)
		(layers "F.Cu" "B.Cu")
		(net "P12V")
	)
	(via
		(at 67.975988 -332.87081)
		(size 0.508)
		(drill 0.254)
		(layers "F.Cu" "B.Cu")
		(net "P12V")
	)
	(via
		(at 64.698372 -425.854622)
		(size 0.508)
		(drill 0.254)
		(layers "F.Cu" "B.Cu")
		(net "P12V")
	)
	(via
		(at 78.03261 -487.001312)
		(size 0.508)
		(drill 0.254)
		(layers "F.Cu" "B.Cu")
		(net "P12V")
	)
	(via
		(at 64.977772 -58.973466)
		(size 0.508)
		(drill 0.254)
		(layers "F.Cu" "B.Cu")
		(net "P12V")
	)
	(via
		(at 67.860164 -145.450306)
		(size 0.508)
		(drill 0.254)
		(layers "F.Cu" "B.Cu")
		(net "P12V")
	)
	(via
		(at 58.319924 -336.36839)
		(size 0.508)
		(drill 0.254)
		(layers "F.Cu" "B.Cu")
		(net "P12V")
	)
	(via
		(at 67.082416 -13.955776)
		(size 0.508)
		(drill 0.254)
		(layers "F.Cu" "B.Cu")
		(net "P12V")
	)
	(via
		(at 77.187044 -377.70181)
		(size 0.508)
		(drill 0.254)
		(layers "F.Cu" "B.Cu")
		(net "P12V")
	)
	(via
		(at 83.76285 -80.933036)
		(size 0.508)
		(drill 0.254)
		(layers "F.Cu" "B.Cu")
		(net "P12V")
	)
	(via
		(at 83.73999 -88.55837)
		(size 0.508)
		(drill 0.254)
		(layers "F.Cu" "B.Cu")
		(net "P12V")
	)
	(via
		(at 78.603856 -375.945908)
		(size 0.508)
		(drill 0.254)
		(layers "F.Cu" "B.Cu")
		(net "P12V")
	)
	(via
		(at 78.015084 -165.724078)
		(size 0.508)
		(drill 0.254)
		(layers "F.Cu" "B.Cu")
		(net "P12V")
	)
	(via
		(at 68.969636 -389.671306)
		(size 0.508)
		(drill 0.254)
		(layers "F.Cu" "B.Cu")
		(net "P12V")
	)
	(via
		(at 56.279542 -515.99592)
		(size 0.508)
		(drill 0.254)
		(layers "F.Cu" "B.Cu")
		(net "P12V")
	)
	(via
		(at 64.977772 -56.302656)
		(size 0.508)
		(drill 0.254)
		(layers "F.Cu" "B.Cu")
		(net "P12V")
	)
	(via
		(at 59.870086 -291.06368)
		(size 0.508)
		(drill 0.254)
		(layers "F.Cu" "B.Cu")
		(net "P12V")
	)
	(via
		(at 82.585306 -131.224528)
		(size 0.508)
		(drill 0.254)
		(layers "F.Cu" "B.Cu")
		(net "P12V")
	)
	(via
		(at 40.256968 -420.940992)
		(size 0.508)
		(drill 0.254)
		(layers "F.Cu" "B.Cu")
		(net "P12V")
	)
	(via
		(at 41.509696 -256.869692)
		(size 0.508)
		(drill 0.254)
		(layers "F.Cu" "B.Cu")
		(net "P12V")
	)
	(via
		(at 80.802226 -255.854962)
		(size 0.508)
		(drill 0.254)
		(layers "F.Cu" "B.Cu")
		(net "P12V")
	)
	(via
		(at 67.040506 -393.19454)
		(size 0.508)
		(drill 0.254)
		(layers "F.Cu" "B.Cu")
		(net "P12V")
	)
	(via
		(at 65.423288 -106.8451)
		(size 0.508)
		(drill 0.254)
		(layers "F.Cu" "B.Cu")
		(net "P12V")
	)
	(via
		(at 74.312526 -135.321548)
		(size 0.508)
		(drill 0.254)
		(layers "F.Cu" "B.Cu")
		(net "P12V")
	)
	(via
		(at 74.34961 -379.46838)
		(size 0.508)
		(drill 0.254)
		(layers "F.Cu" "B.Cu")
		(net "P12V")
	)
	(via
		(at 57.8358 -43.975274)
		(size 0.508)
		(drill 0.254)
		(layers "F.Cu" "B.Cu")
		(net "P12V")
	)
	(via
		(at 64.698372 -433.5653)
		(size 0.508)
		(drill 0.254)
		(layers "F.Cu" "B.Cu")
		(net "P12V")
	)
	(via
		(at 66.437256 -411.943042)
		(size 0.508)
		(drill 0.254)
		(layers "F.Cu" "B.Cu")
		(net "P12V")
	)
	(via
		(at 42.271696 -259.013198)
		(size 0.508)
		(drill 0.254)
		(layers "F.Cu" "B.Cu")
		(net "P12V")
	)
	(via
		(at 86.546436 -79.24292)
		(size 0.508)
		(drill 0.254)
		(layers "F.Cu" "B.Cu")
		(net "P12V")
	)
	(via
		(at 81.59369 -259.246878)
		(size 0.508)
		(drill 0.254)
		(layers "F.Cu" "B.Cu")
		(net "P12V")
	)
	(via
		(at 61.639958 -288.39541)
		(size 0.508)
		(drill 0.254)
		(layers "F.Cu" "B.Cu")
		(net "P12V")
	)
	(via
		(at 75.121516 -488.722162)
		(size 0.508)
		(drill 0.254)
		(layers "F.Cu" "B.Cu")
		(net "P12V")
	)
	(via
		(at 57.549542 -518.66419)
		(size 0.508)
		(drill 0.254)
		(layers "F.Cu" "B.Cu")
		(net "P12V")
	)
	(via
		(at 74.39533 -372.363746)
		(size 0.508)
		(drill 0.254)
		(layers "F.Cu" "B.Cu")
		(net "P12V")
	)
	(via
		(at 65.171574 -325.86803)
		(size 0.508)
		(drill 0.254)
		(layers "F.Cu" "B.Cu")
		(net "P12V")
	)
	(via
		(at 65.423288 -106.0831)
		(size 0.508)
		(drill 0.254)
		(layers "F.Cu" "B.Cu")
		(net "P12V")
	)
	(via
		(at 68.534534 -285.615634)
		(size 0.508)
		(drill 0.254)
		(layers "F.Cu" "B.Cu")
		(net "P12V")
	)
	(via
		(at 69.730874 -103.451406)
		(size 0.508)
		(drill 0.254)
		(layers "F.Cu" "B.Cu")
		(net "P12V")
	)
	(via
		(at 67.502786 -435.528212)
		(size 0.508)
		(drill 0.254)
		(layers "F.Cu" "B.Cu")
		(net "P12V")
	)
	(via
		(at 66.445384 -58.973466)
		(size 0.508)
		(drill 0.254)
		(layers "F.Cu" "B.Cu")
		(net "P12V")
	)
	(via
		(at 75.11161 -377.70181)
		(size 0.508)
		(drill 0.254)
		(layers "F.Cu" "B.Cu")
		(net "P12V")
	)
	(via
		(at 64.698372 -431.193702)
		(size 0.508)
		(drill 0.254)
		(layers "F.Cu" "B.Cu")
		(net "P12V")
	)
	(via
		(at 80.819498 -165.724078)
		(size 0.508)
		(drill 0.254)
		(layers "F.Cu" "B.Cu")
		(net "P12V")
	)
	(via
		(at 60.201048 -193.67754)
		(size 0.508)
		(drill 0.254)
		(layers "F.Cu" "B.Cu")
		(net "P12V")
	)
	(via
		(at 67.082416 -12.337288)
		(size 0.508)
		(drill 0.254)
		(layers "F.Cu" "B.Cu")
		(net "P12V")
	)
	(via
		(at 64.380872 -460.278226)
		(size 0.508)
		(drill 0.254)
		(layers "F.Cu" "B.Cu")
		(net "P12V")
	)
	(via
		(at 56.279542 -522.9987)
		(size 0.508)
		(drill 0.254)
		(layers "F.Cu" "B.Cu")
		(net "P12V")
	)
	(via
		(at 65.242694 -43.213274)
		(size 0.508)
		(drill 0.254)
		(layers "F.Cu" "B.Cu")
		(net "P12V")
	)
	(via
		(at 86.567264 -85.159088)
		(size 0.508)
		(drill 0.254)
		(layers "F.Cu" "B.Cu")
		(net "P12V")
	)
	(via
		(at 78.789276 -259.246878)
		(size 0.508)
		(drill 0.254)
		(layers "F.Cu" "B.Cu")
		(net "P12V")
	)
	(via
		(at 83.76285 -82.78749)
		(size 0.508)
		(drill 0.254)
		(layers "F.Cu" "B.Cu")
		(net "P12V")
	)
	(via
		(at 87.329264 -82.78749)
		(size 0.508)
		(drill 0.254)
		(layers "F.Cu" "B.Cu")
		(net "P12V")
	)
	(via
		(at 73.177908 -14.717776)
		(size 0.508)
		(drill 0.254)
		(layers "F.Cu" "B.Cu")
		(net "P12V")
	)
	(via
		(at 63.544196 -221.316804)
		(size 0.508)
		(drill 0.254)
		(layers "F.Cu" "B.Cu")
		(net "P12V")
	)
	(via
		(at 55.671212 -336.36839)
		(size 0.508)
		(drill 0.254)
		(layers "F.Cu" "B.Cu")
		(net "P12V")
	)
	(via
		(at 56.433212 -334.477868)
		(size 0.508)
		(drill 0.254)
		(layers "F.Cu" "B.Cu")
		(net "P12V")
	)
	(via
		(at 74.351134 -300.815248)
		(size 0.508)
		(drill 0.254)
		(layers "F.Cu" "B.Cu")
		(net "P12V")
	)
	(via
		(at 66.740786 -435.528212)
		(size 0.508)
		(drill 0.254)
		(layers "F.Cu" "B.Cu")
		(net "P12V")
	)
	(via
		(at 58.811414 -521.035788)
		(size 0.508)
		(drill 0.254)
		(layers "F.Cu" "B.Cu")
		(net "P12V")
	)
	(via
		(at 76.375514 -300.869604)
		(size 0.508)
		(drill 0.254)
		(layers "F.Cu" "B.Cu")
		(net "P12V")
	)
	(via
		(at 39.560246 -339.87486)
		(size 0.508)
		(drill 0.254)
		(layers "F.Cu" "B.Cu")
		(net "P12V")
	)
	(via
		(at 64.335152 -467.38286)
		(size 0.508)
		(drill 0.254)
		(layers "F.Cu" "B.Cu")
		(net "P12V")
	)
	(via
		(at 73.177908 -11.575288)
		(size 0.508)
		(drill 0.254)
		(layers "F.Cu" "B.Cu")
		(net "P12V")
	)
	(via
		(at 41.579546 -249.793506)
		(size 0.508)
		(drill 0.254)
		(layers "F.Cu" "B.Cu")
		(net "P12V")
	)
	(via
		(at 67.975988 -330.907898)
		(size 0.508)
		(drill 0.254)
		(layers "F.Cu" "B.Cu")
		(net "P12V")
	)
	(via
		(at 76.425044 -379.46838)
		(size 0.508)
		(drill 0.254)
		(layers "F.Cu" "B.Cu")
		(net "P12V")
	)
	(via
		(at 84.50199 -88.55837)
		(size 0.508)
		(drill 0.254)
		(layers "F.Cu" "B.Cu")
		(net "P12V")
	)
	(via
		(at 68.737988 -325.86803)
		(size 0.508)
		(drill 0.254)
		(layers "F.Cu" "B.Cu")
		(net "P12V")
	)
	(via
		(at 80.057498 -165.724078)
		(size 0.508)
		(drill 0.254)
		(layers "F.Cu" "B.Cu")
		(net "P12V")
	)
	(via
		(at 63.618872 -458.521562)
		(size 0.508)
		(drill 0.254)
		(layers "F.Cu" "B.Cu")
		(net "P12V")
	)
	(via
		(at 41.108376 -464.36915)
		(size 0.508)
		(drill 0.254)
		(layers "F.Cu" "B.Cu")
		(net "P12V")
	)
	(via
		(at 78.526386 -302.832516)
		(size 0.508)
		(drill 0.254)
		(layers "F.Cu" "B.Cu")
		(net "P12V")
	)
	(via
		(at 61.70295 -334.477868)
		(size 0.508)
		(drill 0.254)
		(layers "F.Cu" "B.Cu")
		(net "P12V")
	)
	(via
		(at 68.666868 -414.613852)
		(size 0.508)
		(drill 0.254)
		(layers "F.Cu" "B.Cu")
		(net "P12V")
	)
	(via
		(at 65.933574 -335.014316)
		(size 0.508)
		(drill 0.254)
		(layers "F.Cu" "B.Cu")
		(net "P12V")
	)
	(via
		(at 67.098164 -145.450306)
		(size 0.508)
		(drill 0.254)
		(layers "F.Cu" "B.Cu")
		(net "P12V")
	)
	(via
		(at 56.433212 -340.31936)
		(size 0.508)
		(drill 0.254)
		(layers "F.Cu" "B.Cu")
		(net "P12V")
	)
	(via
		(at 39.947088 -164.994082)
		(size 0.508)
		(drill 0.254)
		(layers "F.Cu" "B.Cu")
		(net "P12V")
	)
	(via
		(at 68.979288 -14.717776)
		(size 0.508)
		(drill 0.254)
		(layers "F.Cu" "B.Cu")
		(net "P12V")
	)
	(via
		(at 67.207384 -61.641736)
		(size 0.508)
		(drill 0.254)
		(layers "F.Cu" "B.Cu")
		(net "P12V")
	)
	(via
		(at 61.70295 -340.31936)
		(size 0.508)
		(drill 0.254)
		(layers "F.Cu" "B.Cu")
		(net "P12V")
	)
	(via
		(at 69.428868 -421.616632)
		(size 0.508)
		(drill 0.254)
		(layers "F.Cu" "B.Cu")
		(net "P12V")
	)
	(via
		(at 56.279542 -521.035788)
		(size 0.508)
		(drill 0.254)
		(layers "F.Cu" "B.Cu")
		(net "P12V")
	)
	(via
		(at 68.979288 -16.624046)
		(size 0.508)
		(drill 0.254)
		(layers "F.Cu" "B.Cu")
		(net "P12V")
	)
	(via
		(at 61.70295 -338.409534)
		(size 0.508)
		(drill 0.254)
		(layers "F.Cu" "B.Cu")
		(net "P12V")
	)
	(via
		(at 66.445384 -56.302656)
		(size 0.508)
		(drill 0.254)
		(layers "F.Cu" "B.Cu")
		(net "P12V")
	)
	(via
		(at 65.694306 -462.044796)
		(size 0.508)
		(drill 0.254)
		(layers "F.Cu" "B.Cu")
		(net "P12V")
	)
	(via
		(at 63.544196 -217.210386)
		(size 0.508)
		(drill 0.254)
		(layers "F.Cu" "B.Cu")
		(net "P12V")
	)
	(via
		(at 63.173356 -103.514144)
		(size 0.508)
		(drill 0.254)
		(layers "F.Cu" "B.Cu")
		(net "P12V")
	)
	(via
		(at 81.823306 -131.224528)
		(size 0.508)
		(drill 0.254)
		(layers "F.Cu" "B.Cu")
		(net "P12V")
	)
	(via
		(at 68.207636 -393.19454)
		(size 0.508)
		(drill 0.254)
		(layers "F.Cu" "B.Cu")
		(net "P12V")
	)
	(via
		(at 59.798966 -336.36839)
		(size 0.508)
		(drill 0.254)
		(layers "F.Cu" "B.Cu")
		(net "P12V")
	)
	(via
		(at 56.442356 -330.70165)
		(size 0.508)
		(drill 0.254)
		(layers "F.Cu" "B.Cu")
		(net "P12V")
	)
	(via
		(at 79.702914 -133.205728)
		(size 0.508)
		(drill 0.254)
		(layers "F.Cu" "B.Cu")
		(net "P12V")
	)
	(via
		(at 63.013082 -43.213274)
		(size 0.508)
		(drill 0.254)
		(layers "F.Cu" "B.Cu")
		(net "P12V")
	)
	(via
		(at 70.851776 -156.832046)
		(size 0.508)
		(drill 0.254)
		(layers "F.Cu" "B.Cu")
		(net "P12V")
	)
	(via
		(at 77.050646 -488.722162)
		(size 0.508)
		(drill 0.254)
		(layers "F.Cu" "B.Cu")
		(net "P12V")
	)
	(via
		(at 80.464914 -133.205728)
		(size 0.508)
		(drill 0.254)
		(layers "F.Cu" "B.Cu")
		(net "P12V")
	)
	(via
		(at 66.742564 -243.804186)
		(size 0.508)
		(drill 0.254)
		(layers "F.Cu" "B.Cu")
		(net "P12V")
	)
	(via
		(at 65.675256 -419.65372)
		(size 0.508)
		(drill 0.254)
		(layers "F.Cu" "B.Cu")
		(net "P12V")
	)
	(via
		(at 58.329068 -328.800714)
		(size 0.508)
		(drill 0.254)
		(layers "F.Cu" "B.Cu")
		(net "P12V")
	)
	(segment
		(start 50.880518 -38.6207)
		(end 51.833526 -38.6207)
		(width 0.635)
		(layer "In2.Cu")
		(net "P12V")
	)
	(segment
		(start 51.195732 -463.099658)
		(end 52.14874 -463.099658)
		(width 0.635)
		(layer "In2.Cu")
		(net "P12V")
	)
	(segment
		(start 51.275996 -329.972416)
		(end 52.229004 -329.972416)
		(width 0.635)
		(layer "In2.Cu")
		(net "P12V")
	)
	(segment
		(start 51.699414 -106.16692)
		(end 51.699414 -107.119928)
		(width 0.635)
		(layer "In2.Cu")
		(net "P12V")
	)
	(segment
		(start 52.229004 -329.972416)
		(end 52.229004 -330.925424)
		(width 0.635)
		(layer "In2.Cu")
		(net "P12V")
	)
	(segment
		(start 51.967384 -173.13783)
		(end 51.967384 -174.090838)
		(width 0.635)
		(layer "In2.Cu")
		(net "P12V")
	)
	(segment
		(start 53.363114 -240.589308)
		(end 54.316122 -240.589308)
		(width 0.635)
		(layer "In2.Cu")
		(net "P12V")
	)
	(segment
		(start 51.14798 -306.383182)
		(end 52.100988 -306.383182)
		(width 0.635)
		(layer "In2.Cu")
		(net "P12V")
	)
	(segment
		(start 52.034186 -395.548358)
		(end 52.987194 -395.548358)
		(width 0.635)
		(layer "In2.Cu")
		(net "P12V")
	)
	(segment
		(start 52.229004 -196.729604)
		(end 52.229004 -197.682612)
		(width 0.635)
		(layer "In2.Cu")
		(net "P12V")
	)
	(segment
		(start 51.967638 -84.273644)
		(end 52.920646 -84.273644)
		(width 0.635)
		(layer "In2.Cu")
		(net "P12V")
	)
	(segment
		(start 52.168044 -217.485976)
		(end 53.121052 -217.485976)
		(width 0.635)
		(layer "In2.Cu")
		(net "P12V")
	)
	(segment
		(start 51.900328 -349.812356)
		(end 51.900328 -350.765364)
		(width 0.635)
		(layer "In2.Cu")
		(net "P12V")
	)
	(segment
		(start 51.346862 -507.67742)
		(end 52.29987 -507.67742)
		(width 0.635)
		(layer "In2.Cu")
		(net "P12V")
	)
	(segment
		(start 51.195732 -519.020552)
		(end 52.14874 -519.020552)
		(width 0.635)
		(layer "In2.Cu")
		(net "P12V")
	)
	(segment
		(start 51.900582 -127.70231)
		(end 51.900582 -128.655318)
		(width 0.635)
		(layer "In2.Cu")
		(net "P12V")
	)
	(segment
		(start 52.14874 -519.020552)
		(end 53.101748 -519.020552)
		(width 0.635)
		(layer "In2.Cu")
		(net "P12V")
	)
	(segment
		(start 52.410106 -240.589308)
		(end 53.363114 -240.589308)
		(width 0.635)
		(layer "In2.Cu")
		(net "P12V")
	)
	(segment
		(start 51.967638 -83.320636)
		(end 51.967638 -84.273644)
		(width 0.635)
		(layer "In2.Cu")
		(net "P12V")
	)
	(segment
		(start 51.967638 -84.273644)
		(end 51.967638 -85.226652)
		(width 0.635)
		(layer "In2.Cu")
		(net "P12V")
	)
	(segment
		(start 51.699414 -107.119928)
		(end 51.699414 -108.072936)
		(width 0.635)
		(layer "In2.Cu")
		(net "P12V")
	)
	(segment
		(start 52.168298 -438.810146)
		(end 52.168298 -439.763154)
		(width 0.635)
		(layer "In2.Cu")
		(net "P12V")
	)
	(segment
		(start 53.363114 -240.589308)
		(end 53.363114 -241.542316)
		(width 0.635)
		(layer "In2.Cu")
		(net "P12V")
	)
	(segment
		(start 51.21529 -439.763154)
		(end 52.168298 -439.763154)
		(width 0.635)
		(layer "In2.Cu")
		(net "P12V")
	)
	(segment
		(start 50.89779 -62.882272)
		(end 51.850798 -62.882272)
		(width 0.635)
		(layer "In2.Cu")
		(net "P12V")
	)
	(segment
		(start 52.493672 -150.972012)
		(end 52.493672 -151.92502)
		(width 0.635)
		(layer "In2.Cu")
		(net "P12V")
	)
	(segment
		(start 52.168298 -439.763154)
		(end 53.121306 -439.763154)
		(width 0.635)
		(layer "In2.Cu")
		(net "P12V")
	)
	(segment
		(start 51.900328 -350.765364)
		(end 52.853336 -350.765364)
		(width 0.635)
		(layer "In2.Cu")
		(net "P12V")
	)
	(segment
		(start 52.229004 -329.019408)
		(end 52.229004 -329.972416)
		(width 0.635)
		(layer "In2.Cu")
		(net "P12V")
	)
	(segment
		(start 51.623722 -374.437148)
		(end 51.623722 -375.390156)
		(width 0.635)
		(layer "In2.Cu")
		(net "P12V")
	)
	(segment
		(start 52.100988 -306.383182)
		(end 52.100988 -307.33619)
		(width 0.635)
		(layer "In2.Cu")
		(net "P12V")
	)
	(segment
		(start 51.850798 -62.882272)
		(end 51.850798 -63.83528)
		(width 0.635)
		(layer "In2.Cu")
		(net "P12V")
	)
	(segment
		(start 52.304442 -417.68395)
		(end 52.304442 -418.636958)
		(width 0.635)
		(layer "In2.Cu")
		(net "P12V")
	)
	(segment
		(start 52.229004 -195.776596)
		(end 52.229004 -196.729604)
		(width 0.635)
		(layer "In2.Cu")
		(net "P12V")
	)
	(segment
		(start 51.215036 -217.485976)
		(end 52.168044 -217.485976)
		(width 0.635)
		(layer "In2.Cu")
		(net "P12V")
	)
	(segment
		(start 52.493672 -151.92502)
		(end 52.493672 -152.878028)
		(width 0.635)
		(layer "In2.Cu")
		(net "P12V")
	)
	(segment
		(start 52.034186 -394.59535)
		(end 52.034186 -395.548358)
		(width 0.635)
		(layer "In2.Cu")
		(net "P12V")
	)
	(segment
		(start 50.947574 -128.655318)
		(end 51.900582 -128.655318)
		(width 0.635)
		(layer "In2.Cu")
		(net "P12V")
	)
	(segment
		(start 50.880518 -482.70668)
		(end 51.833526 -482.70668)
		(width 0.635)
		(layer "In2.Cu")
		(net "P12V")
	)
	(segment
		(start 52.229004 -329.972416)
		(end 53.182012 -329.972416)
		(width 0.635)
		(layer "In2.Cu")
		(net "P12V")
	)
	(segment
		(start 52.14874 -462.14665)
		(end 52.14874 -463.099658)
		(width 0.635)
		(layer "In2.Cu")
		(net "P12V")
	)
	(segment
		(start 51.01463 -84.273644)
		(end 51.967638 -84.273644)
		(width 0.635)
		(layer "In2.Cu")
		(net "P12V")
	)
	(segment
		(start 51.833526 -482.70668)
		(end 52.786534 -482.70668)
		(width 0.635)
		(layer "In2.Cu")
		(net "P12V")
	)
	(segment
		(start 52.168298 -439.763154)
		(end 52.168298 -440.716162)
		(width 0.635)
		(layer "In2.Cu")
		(net "P12V")
	)
	(segment
		(start 51.967384 -172.184822)
		(end 51.967384 -173.13783)
		(width 0.635)
		(layer "In2.Cu")
		(net "P12V")
	)
	(segment
		(start 52.14874 -519.020552)
		(end 52.14874 -519.97356)
		(width 0.635)
		(layer "In2.Cu")
		(net "P12V")
	)
	(segment
		(start 53.363114 -239.6363)
		(end 53.363114 -240.589308)
		(width 0.635)
		(layer "In2.Cu")
		(net "P12V")
	)
	(segment
		(start 52.229004 -196.729604)
		(end 53.182012 -196.729604)
		(width 0.635)
		(layer "In2.Cu")
		(net "P12V")
	)
	(segment
		(start 51.699668 -17.615662)
		(end 51.699668 -18.56867)
		(width 0.635)
		(layer "In2.Cu")
		(net "P12V")
	)
	(segment
		(start 51.623722 -374.437148)
		(end 52.57673 -374.437148)
		(width 0.635)
		(layer "In2.Cu")
		(net "P12V")
	)
	(segment
		(start 52.29987 -507.67742)
		(end 52.29987 -508.630428)
		(width 0.635)
		(layer "In2.Cu")
		(net "P12V")
	)
	(segment
		(start 52.168044 -216.532968)
		(end 52.168044 -217.485976)
		(width 0.635)
		(layer "In2.Cu")
		(net "P12V")
	)
	(segment
		(start 51.275996 -196.729604)
		(end 52.229004 -196.729604)
		(width 0.635)
		(layer "In2.Cu")
		(net "P12V")
	)
	(segment
		(start 51.900582 -128.655318)
		(end 51.900582 -129.608326)
		(width 0.635)
		(layer "In2.Cu")
		(net "P12V")
	)
	(segment
		(start 51.014376 -173.13783)
		(end 51.967384 -173.13783)
		(width 0.635)
		(layer "In2.Cu")
		(net "P12V")
	)
	(segment
		(start 51.850798 -62.882272)
		(end 52.803806 -62.882272)
		(width 0.635)
		(layer "In2.Cu")
		(net "P12V")
	)
	(segment
		(start 50.94732 -350.765364)
		(end 51.900328 -350.765364)
		(width 0.635)
		(layer "In2.Cu")
		(net "P12V")
	)
	(segment
		(start 51.833526 -38.6207)
		(end 51.833526 -39.573708)
		(width 0.635)
		(layer "In2.Cu")
		(net "P12V")
	)
	(segment
		(start 50.74666 -18.56867)
		(end 51.699668 -18.56867)
		(width 0.635)
		(layer "In2.Cu")
		(net "P12V")
	)
	(segment
		(start 51.623722 -373.48414)
		(end 51.623722 -374.437148)
		(width 0.635)
		(layer "In2.Cu")
		(net "P12V")
	)
	(segment
		(start 52.07762 -284.252416)
		(end 52.07762 -285.205424)
		(width 0.635)
		(layer "In2.Cu")
		(net "P12V")
	)
	(segment
		(start 51.699668 -18.56867)
		(end 52.652676 -18.56867)
		(width 0.635)
		(layer "In2.Cu")
		(net "P12V")
	)
	(segment
		(start 51.850798 -61.929264)
		(end 51.850798 -62.882272)
		(width 0.635)
		(layer "In2.Cu")
		(net "P12V")
	)
	(segment
		(start 52.493672 -151.92502)
		(end 53.44668 -151.92502)
		(width 0.635)
		(layer "In2.Cu")
		(net "P12V")
	)
	(segment
		(start 51.699414 -107.119928)
		(end 52.652422 -107.119928)
		(width 0.635)
		(layer "In2.Cu")
		(net "P12V")
	)
	(segment
		(start 51.124612 -285.205424)
		(end 52.07762 -285.205424)
		(width 0.635)
		(layer "In2.Cu")
		(net "P12V")
	)
	(segment
		(start 52.100988 -305.430174)
		(end 52.100988 -306.383182)
		(width 0.635)
		(layer "In2.Cu")
		(net "P12V")
	)
	(segment
		(start 50.746406 -107.119928)
		(end 51.699414 -107.119928)
		(width 0.635)
		(layer "In2.Cu")
		(net "P12V")
	)
	(segment
		(start 52.168044 -217.485976)
		(end 52.168044 -218.438984)
		(width 0.635)
		(layer "In2.Cu")
		(net "P12V")
	)
	(segment
		(start 52.07762 -285.205424)
		(end 52.07762 -286.158432)
		(width 0.635)
		(layer "In2.Cu")
		(net "P12V")
	)
	(segment
		(start 52.304442 -418.636958)
		(end 52.304442 -419.589966)
		(width 0.635)
		(layer "In2.Cu")
		(net "P12V")
	)
	(segment
		(start 52.29987 -507.67742)
		(end 53.252878 -507.67742)
		(width 0.635)
		(layer "In2.Cu")
		(net "P12V")
	)
	(segment
		(start 51.967384 -173.13783)
		(end 52.920392 -173.13783)
		(width 0.635)
		(layer "In2.Cu")
		(net "P12V")
	)
	(segment
		(start 52.14874 -463.099658)
		(end 52.14874 -464.052666)
		(width 0.635)
		(layer "In2.Cu")
		(net "P12V")
	)
	(segment
		(start 51.540664 -151.92502)
		(end 52.493672 -151.92502)
		(width 0.635)
		(layer "In2.Cu")
		(net "P12V")
	)
	(segment
		(start 51.081178 -395.548358)
		(end 52.034186 -395.548358)
		(width 0.635)
		(layer "In2.Cu")
		(net "P12V")
	)
	(segment
		(start 52.29987 -506.724412)
		(end 52.29987 -507.67742)
		(width 0.635)
		(layer "In2.Cu")
		(net "P12V")
	)
	(segment
		(start 52.304442 -418.636958)
		(end 53.25745 -418.636958)
		(width 0.635)
		(layer "In2.Cu")
		(net "P12V")
	)
	(segment
		(start 51.699668 -18.56867)
		(end 51.699668 -19.521678)
		(width 0.635)
		(layer "In2.Cu")
		(net "P12V")
	)
	(segment
		(start 51.900328 -350.765364)
		(end 51.900328 -351.718372)
		(width 0.635)
		(layer "In2.Cu")
		(net "P12V")
	)
	(segment
		(start 51.900582 -128.655318)
		(end 52.85359 -128.655318)
		(width 0.635)
		(layer "In2.Cu")
		(net "P12V")
	)
	(segment
		(start 51.833526 -482.70668)
		(end 51.833526 -483.659688)
		(width 0.635)
		(layer "In2.Cu")
		(net "P12V")
	)
	(segment
		(start 51.833526 -37.667692)
		(end 51.833526 -38.6207)
		(width 0.635)
		(layer "In2.Cu")
		(net "P12V")
	)
	(segment
		(start 52.14874 -463.099658)
		(end 53.101748 -463.099658)
		(width 0.635)
		(layer "In2.Cu")
		(net "P12V")
	)
	(segment
		(start 52.07762 -285.205424)
		(end 53.030628 -285.205424)
		(width 0.635)
		(layer "In2.Cu")
		(net "P12V")
	)
	(segment
		(start 51.351434 -418.636958)
		(end 52.304442 -418.636958)
		(width 0.635)
		(layer "In2.Cu")
		(net "P12V")
	)
	(segment
		(start 51.833526 -481.753672)
		(end 51.833526 -482.70668)
		(width 0.635)
		(layer "In2.Cu")
		(net "P12V")
	)
	(segment
		(start 52.100988 -306.383182)
		(end 53.053996 -306.383182)
		(width 0.635)
		(layer "In2.Cu")
		(net "P12V")
	)
	(segment
		(start 52.034186 -395.548358)
		(end 52.034186 -396.501366)
		(width 0.635)
		(layer "In2.Cu")
		(net "P12V")
	)
	(segment
		(start 51.833526 -38.6207)
		(end 52.786534 -38.6207)
		(width 0.635)
		(layer "In2.Cu")
		(net "P12V")
	)
	(segment
		(start 50.670714 -374.437148)
		(end 51.623722 -374.437148)
		(width 0.635)
		(layer "In2.Cu")
		(net "P12V")
	)
	(segment
		(start 52.14874 -518.067544)
		(end 52.14874 -519.020552)
		(width 0.635)
		(layer "In2.Cu")
		(net "P12V")
	)
	(via
		(at 81.374488 -57.398666)
		(size 0.508)
		(drill 0.254)
		(layers "F.Cu" "B.Cu")
		(net "T2_BLAD4_TXD")
	)
	(segment
		(start 1.948942 -220.670628)
		(end 4.083304 -220.670628)
		(width 0.127)
		(layer "In5.Cu")
		(net "T2_BLAD4_TXD")
	)
	(segment
		(start 4.21386 -220.540072)
		(end 6.645656 -220.540072)
		(width 0.127)
		(layer "In5.Cu")
		(net "T2_BLAD4_TXD")
	)
	(segment
		(start 83.754468 -55.018686)
		(end 83.754468 -50.348134)
		(width 0.127)
		(layer "In5.Cu")
		(net "T2_BLAD4_TXD")
	)
	(segment
		(start 51.030886 -87.111332)
		(end 80.743552 -57.398666)
		(width 0.127)
		(layer "In5.Cu")
		(net "T2_BLAD4_TXD")
	)
	(segment
		(start 18.873978 -110.674658)
		(end 18.873978 -93.01226)
		(width 0.127)
		(layer "In5.Cu")
		(net "T2_BLAD4_TXD")
	)
	(segment
		(start 93.220032 -48.937672)
		(end 93.220032 -50.231548)
		(width 0.127)
		(layer "In5.Cu")
		(net "T2_BLAD4_TXD")
	)
	(segment
		(start 24.774906 -87.111332)
		(end 51.030886 -87.111332)
		(width 0.127)
		(layer "In5.Cu")
		(net "T2_BLAD4_TXD")
	)
	(segment
		(start 24.734774 -116.535454)
		(end 18.873978 -110.674658)
		(width 0.127)
		(layer "In5.Cu")
		(net "T2_BLAD4_TXD")
	)
	(segment
		(start 8.665972 -219.449396)
		(end 9.456674 -218.658694)
		(width 0.127)
		(layer "In5.Cu")
		(net "T2_BLAD4_TXD")
	)
	(segment
		(start 85.978746 -48.123856)
		(end 92.406216 -48.123856)
		(width 0.127)
		(layer "In5.Cu")
		(net "T2_BLAD4_TXD")
	)
	(segment
		(start 83.754468 -50.348134)
		(end 85.978746 -48.123856)
		(width 0.127)
		(layer "In5.Cu")
		(net "T2_BLAD4_TXD")
	)
	(segment
		(start 7.736332 -219.449396)
		(end 8.665972 -219.449396)
		(width 0.127)
		(layer "In5.Cu")
		(net "T2_BLAD4_TXD")
	)
	(segment
		(start 81.374488 -57.398666)
		(end 83.754468 -55.018686)
		(width 0.127)
		(layer "In5.Cu")
		(net "T2_BLAD4_TXD")
	)
	(segment
		(start 4.083304 -220.670628)
		(end 4.21386 -220.540072)
		(width 0.127)
		(layer "In5.Cu")
		(net "T2_BLAD4_TXD")
	)
	(segment
		(start 9.456674 -218.658694)
		(end 9.456674 -202.776328)
		(width 0.127)
		(layer "In5.Cu")
		(net "T2_BLAD4_TXD")
	)
	(segment
		(start 9.456674 -202.776328)
		(end 14.38275 -197.850252)
		(width 0.127)
		(layer "In5.Cu")
		(net "T2_BLAD4_TXD")
	)
	(segment
		(start 92.72651 -50.72507)
		(end 90.71991 -50.72507)
		(width 0.127)
		(layer "In5.Cu")
		(net "T2_BLAD4_TXD")
	)
	(segment
		(start 6.645656 -220.540072)
		(end 7.736332 -219.449396)
		(width 0.127)
		(layer "In5.Cu")
		(net "T2_BLAD4_TXD")
	)
	(segment
		(start 92.406216 -48.123856)
		(end 93.220032 -48.937672)
		(width 0.127)
		(layer "In5.Cu")
		(net "T2_BLAD4_TXD")
	)
	(segment
		(start 14.38275 -173.726602)
		(end 24.734774 -163.374578)
		(width 0.127)
		(layer "In5.Cu")
		(net "T2_BLAD4_TXD")
	)
	(segment
		(start 93.220032 -50.231548)
		(end 92.72651 -50.72507)
		(width 0.127)
		(layer "In5.Cu")
		(net "T2_BLAD4_TXD")
	)
	(segment
		(start 18.873978 -93.01226)
		(end 24.774906 -87.111332)
		(width 0.127)
		(layer "In5.Cu")
		(net "T2_BLAD4_TXD")
	)
	(segment
		(start 24.734774 -163.374578)
		(end 24.734774 -116.535454)
		(width 0.127)
		(layer "In5.Cu")
		(net "T2_BLAD4_TXD")
	)
	(segment
		(start 80.743552 -57.398666)
		(end 81.374488 -57.398666)
		(width 0.127)
		(layer "In5.Cu")
		(net "T2_BLAD4_TXD")
	)
	(segment
		(start 14.38275 -197.850252)
		(end 14.38275 -173.726602)
		(width 0.127)
		(layer "In5.Cu")
		(net "T2_BLAD4_TXD")
	)
	(segment
		(start 30.45968 -461.829912)
		(end 27.640026 -461.829912)
		(width 0.4572)
		(layer "F.Cu")
		(net "PSU6_REMOTE_N")
	)
	(via
		(at 84.429346 -489.403898)
		(size 0.508)
		(drill 0.254)
		(layers "F.Cu" "B.Cu")
		(net "T12_BLAD1_EN")
	)
	(segment
		(start 84.429346 -489.403898)
		(end 84.429346 -487.041952)
		(width 0.127)
		(layer "In2.Cu")
		(net "T12_BLAD1_EN")
	)
	(segment
		(start 84.309712 -486.922318)
		(end 84.309712 -467.359238)
		(width 0.127)
		(layer "In2.Cu")
		(net "T12_BLAD1_EN")
	)
	(segment
		(start 86.948264 -497.76507)
		(end 84.429346 -495.246152)
		(width 0.127)
		(layer "In2.Cu")
		(net "T12_BLAD1_EN")
	)
	(segment
		(start 88.17991 -497.76507)
		(end 86.948264 -497.76507)
		(width 0.127)
		(layer "In2.Cu")
		(net "T12_BLAD1_EN")
	)
	(segment
		(start 4.790694 -321.51066)
		(end 3.949954 -320.66992)
		(width 0.127)
		(layer "In2.Cu")
		(net "T12_BLAD1_EN")
	)
	(segment
		(start 83.015582 -449.798694)
		(end 80.799686 -447.582798)
		(width 0.127)
		(layer "In2.Cu")
		(net "T12_BLAD1_EN")
	)
	(segment
		(start 84.429346 -487.041952)
		(end 84.309712 -486.922318)
		(width 0.127)
		(layer "In2.Cu")
		(net "T12_BLAD1_EN")
	)
	(segment
		(start 12.853162 -370.016532)
		(end 12.853162 -324.401942)
		(width 0.127)
		(layer "In2.Cu")
		(net "T12_BLAD1_EN")
	)
	(segment
		(start 84.429346 -495.246152)
		(end 84.429346 -489.403898)
		(width 0.127)
		(layer "In2.Cu")
		(net "T12_BLAD1_EN")
	)
	(segment
		(start 23.506176 -438.534048)
		(end 23.506176 -380.669546)
		(width 0.127)
		(layer "In2.Cu")
		(net "T12_BLAD1_EN")
	)
	(segment
		(start 80.799686 -447.582798)
		(end 42.621708 -447.582798)
		(width 0.127)
		(layer "In2.Cu")
		(net "T12_BLAD1_EN")
	)
	(segment
		(start 7.122414 -321.51066)
		(end 4.790694 -321.51066)
		(width 0.127)
		(layer "In2.Cu")
		(net "T12_BLAD1_EN")
	)
	(segment
		(start 10.887964 -322.436744)
		(end 8.048498 -322.436744)
		(width 0.127)
		(layer "In2.Cu")
		(net "T12_BLAD1_EN")
	)
	(segment
		(start 12.853162 -324.401942)
		(end 10.887964 -322.436744)
		(width 0.127)
		(layer "In2.Cu")
		(net "T12_BLAD1_EN")
	)
	(segment
		(start 23.506176 -380.669546)
		(end 12.853162 -370.016532)
		(width 0.127)
		(layer "In2.Cu")
		(net "T12_BLAD1_EN")
	)
	(segment
		(start 83.015582 -466.065108)
		(end 83.015582 -449.798694)
		(width 0.127)
		(layer "In2.Cu")
		(net "T12_BLAD1_EN")
	)
	(segment
		(start 8.048498 -322.436744)
		(end 7.122414 -321.51066)
		(width 0.127)
		(layer "In2.Cu")
		(net "T12_BLAD1_EN")
	)
	(segment
		(start 42.621708 -447.582798)
		(end 38.5699 -443.53099)
		(width 0.127)
		(layer "In2.Cu")
		(net "T12_BLAD1_EN")
	)
	(segment
		(start 84.309712 -467.359238)
		(end 83.015582 -466.065108)
		(width 0.127)
		(layer "In2.Cu")
		(net "T12_BLAD1_EN")
	)
	(segment
		(start 28.503118 -443.53099)
		(end 23.506176 -438.534048)
		(width 0.127)
		(layer "In2.Cu")
		(net "T12_BLAD1_EN")
	)
	(segment
		(start 38.5699 -443.53099)
		(end 28.503118 -443.53099)
		(width 0.127)
		(layer "In2.Cu")
		(net "T12_BLAD1_EN")
	)
	(via
		(at 84.085684 -58.933334)
		(size 0.508)
		(drill 0.254)
		(layers "F.Cu" "B.Cu")
		(net "T2_BLAD2_TXD")
	)
	(segment
		(start 11.167618 -222.50527)
		(end 9.779254 -223.893634)
		(width 0.127)
		(layer "In5.Cu")
		(net "T2_BLAD2_TXD")
	)
	(segment
		(start 26.491438 -114.92738)
		(end 26.491438 -163.953698)
		(width 0.127)
		(layer "In5.Cu")
		(net "T2_BLAD2_TXD")
	)
	(segment
		(start 11.167618 -204.260704)
		(end 11.167618 -222.50527)
		(width 0.127)
		(layer "In5.Cu")
		(net "T2_BLAD2_TXD")
	)
	(segment
		(start 87.210138 -56.774842)
		(end 86.244176 -56.774842)
		(width 0.127)
		(layer "In5.Cu")
		(net "T2_BLAD2_TXD")
	)
	(segment
		(start 54.185058 -88.83396)
		(end 26.069798 -88.83396)
		(width 0.127)
		(layer "In5.Cu")
		(net "T2_BLAD2_TXD")
	)
	(segment
		(start 7.003542 -224.815654)
		(end 4.803902 -224.815654)
		(width 0.127)
		(layer "In5.Cu")
		(net "T2_BLAD2_TXD")
	)
	(segment
		(start 84.085684 -58.933334)
		(end 54.185058 -88.83396)
		(width 0.127)
		(layer "In5.Cu")
		(net "T2_BLAD2_TXD")
	)
	(segment
		(start 17.536414 -197.891908)
		(end 11.167618 -204.260704)
		(width 0.127)
		(layer "In5.Cu")
		(net "T2_BLAD2_TXD")
	)
	(segment
		(start 90.71991 -53.26507)
		(end 87.210138 -56.774842)
		(width 0.127)
		(layer "In5.Cu")
		(net "T2_BLAD2_TXD")
	)
	(segment
		(start 17.536414 -172.908722)
		(end 17.536414 -197.891908)
		(width 0.127)
		(layer "In5.Cu")
		(net "T2_BLAD2_TXD")
	)
	(segment
		(start 86.244176 -56.774842)
		(end 84.085684 -58.933334)
		(width 0.127)
		(layer "In5.Cu")
		(net "T2_BLAD2_TXD")
	)
	(segment
		(start 4.803902 -224.815654)
		(end 3.948938 -225.670618)
		(width 0.127)
		(layer "In5.Cu")
		(net "T2_BLAD2_TXD")
	)
	(segment
		(start 26.069798 -88.83396)
		(end 21.018754 -93.885004)
		(width 0.127)
		(layer "In5.Cu")
		(net "T2_BLAD2_TXD")
	)
	(segment
		(start 7.925562 -223.893634)
		(end 7.003542 -224.815654)
		(width 0.127)
		(layer "In5.Cu")
		(net "T2_BLAD2_TXD")
	)
	(segment
		(start 9.779254 -223.893634)
		(end 7.925562 -223.893634)
		(width 0.127)
		(layer "In5.Cu")
		(net "T2_BLAD2_TXD")
	)
	(segment
		(start 21.018754 -109.454696)
		(end 26.491438 -114.92738)
		(width 0.127)
		(layer "In5.Cu")
		(net "T2_BLAD2_TXD")
	)
	(segment
		(start 21.018754 -93.885004)
		(end 21.018754 -109.454696)
		(width 0.127)
		(layer "In5.Cu")
		(net "T2_BLAD2_TXD")
	)
	(segment
		(start 26.491438 -163.953698)
		(end 17.536414 -172.908722)
		(width 0.127)
		(layer "In5.Cu")
		(net "T2_BLAD2_TXD")
	)
	(segment
		(start 28.25369 -285.02991)
		(end 28.253436 -285.030164)
		(width 0.508)
		(layer "F.Cu")
		(net "PSU4_REMOTE_N")
	)
	(segment
		(start 30.45968 -285.02991)
		(end 28.25369 -285.02991)
		(width 0.508)
		(layer "F.Cu")
		(net "PSU4_REMOTE_N")
	)
	(segment
		(start 28.253436 -285.030164)
		(end 27.643836 -285.030164)
		(width 0.508)
		(layer "F.Cu")
		(net "PSU4_REMOTE_N")
	)
	(via
		(at 86.445344 -488.291886)
		(size 0.508)
		(drill 0.254)
		(layers "F.Cu" "B.Cu")
		(net "T12_BLAD3_EN")
	)
	(segment
		(start 29.094176 -443.187836)
		(end 38.693852 -443.187836)
		(width 0.127)
		(layer "In2.Cu")
		(net "T12_BLAD3_EN")
	)
	(segment
		(start 8.153654 -320.406268)
		(end 9.496298 -320.406268)
		(width 0.127)
		(layer "In2.Cu")
		(net "T12_BLAD3_EN")
	)
	(segment
		(start 83.345782 -465.928202)
		(end 84.639912 -467.222332)
		(width 0.127)
		(layer "In2.Cu")
		(net "T12_BLAD3_EN")
	)
	(segment
		(start 7.162038 -319.414652)
		(end 8.153654 -320.406268)
		(width 0.127)
		(layer "In2.Cu")
		(net "T12_BLAD3_EN")
	)
	(segment
		(start 24.241506 -438.335166)
		(end 29.094176 -443.187836)
		(width 0.127)
		(layer "In2.Cu")
		(net "T12_BLAD3_EN")
	)
	(segment
		(start 13.258038 -324.168008)
		(end 13.258038 -369.388898)
		(width 0.127)
		(layer "In2.Cu")
		(net "T12_BLAD3_EN")
	)
	(segment
		(start 3.949954 -318.669924)
		(end 4.694682 -319.414652)
		(width 0.127)
		(layer "In2.Cu")
		(net "T12_BLAD3_EN")
	)
	(segment
		(start 84.639912 -485.666542)
		(end 86.445344 -487.471974)
		(width 0.127)
		(layer "In2.Cu")
		(net "T12_BLAD3_EN")
	)
	(segment
		(start 13.258038 -369.388898)
		(end 24.241506 -380.372366)
		(width 0.127)
		(layer "In2.Cu")
		(net "T12_BLAD3_EN")
	)
	(segment
		(start 80.936592 -447.252598)
		(end 83.345782 -449.661788)
		(width 0.127)
		(layer "In2.Cu")
		(net "T12_BLAD3_EN")
	)
	(segment
		(start 88.17991 -490.026452)
		(end 86.445344 -488.291886)
		(width 0.127)
		(layer "In2.Cu")
		(net "T12_BLAD3_EN")
	)
	(segment
		(start 42.758614 -447.252598)
		(end 80.936592 -447.252598)
		(width 0.127)
		(layer "In2.Cu")
		(net "T12_BLAD3_EN")
	)
	(segment
		(start 84.639912 -467.222332)
		(end 84.639912 -485.666542)
		(width 0.127)
		(layer "In2.Cu")
		(net "T12_BLAD3_EN")
	)
	(segment
		(start 24.241506 -380.372366)
		(end 24.241506 -438.335166)
		(width 0.127)
		(layer "In2.Cu")
		(net "T12_BLAD3_EN")
	)
	(segment
		(start 4.694682 -319.414652)
		(end 7.162038 -319.414652)
		(width 0.127)
		(layer "In2.Cu")
		(net "T12_BLAD3_EN")
	)
	(segment
		(start 9.496298 -320.406268)
		(end 13.258038 -324.168008)
		(width 0.127)
		(layer "In2.Cu")
		(net "T12_BLAD3_EN")
	)
	(segment
		(start 86.445344 -487.471974)
		(end 86.445344 -488.291886)
		(width 0.127)
		(layer "In2.Cu")
		(net "T12_BLAD3_EN")
	)
	(segment
		(start 88.17991 -495.22507)
		(end 88.17991 -490.026452)
		(width 0.127)
		(layer "In2.Cu")
		(net "T12_BLAD3_EN")
	)
	(segment
		(start 83.345782 -449.661788)
		(end 83.345782 -465.928202)
		(width 0.127)
		(layer "In2.Cu")
		(net "T12_BLAD3_EN")
	)
	(segment
		(start 38.693852 -443.187836)
		(end 42.758614 -447.252598)
		(width 0.127)
		(layer "In2.Cu")
		(net "T12_BLAD3_EN")
	)
	(via
		(at 81.762346 -60.486798)
		(size 0.508)
		(drill 0.254)
		(layers "F.Cu" "B.Cu")
		(net "T2_BLAD2_RXD")
	)
	(segment
		(start 91.65209 -52.33289)
		(end 91.98991 -51.99507)
		(width 0.127)
		(layer "In5.Cu")
		(net "T2_BLAD2_RXD")
	)
	(segment
		(start 85.88248 -56.366664)
		(end 86.323424 -56.366664)
		(width 0.127)
		(layer "In5.Cu")
		(net "T2_BLAD2_RXD")
	)
	(segment
		(start 10.82548 -203.987146)
		(end 10.82548 -222.363538)
		(width 0.127)
		(layer "In5.Cu")
		(net "T2_BLAD2_RXD")
	)
	(segment
		(start 90.357198 -52.33289)
		(end 91.65209 -52.33289)
		(width 0.127)
		(layer "In5.Cu")
		(net "T2_BLAD2_RXD")
	)
	(segment
		(start 25.766776 -88.491822)
		(end 20.630896 -93.627702)
		(width 0.127)
		(layer "In5.Cu")
		(net "T2_BLAD2_RXD")
	)
	(segment
		(start 16.64335 -173.334426)
		(end 16.64335 -198.169276)
		(width 0.127)
		(layer "In5.Cu")
		(net "T2_BLAD2_RXD")
	)
	(segment
		(start 20.630896 -93.627702)
		(end 20.630896 -109.8423)
		(width 0.127)
		(layer "In5.Cu")
		(net "T2_BLAD2_RXD")
	)
	(segment
		(start 16.64335 -198.169276)
		(end 10.82548 -203.987146)
		(width 0.127)
		(layer "In5.Cu")
		(net "T2_BLAD2_RXD")
	)
	(segment
		(start 53.757322 -88.491822)
		(end 25.766776 -88.491822)
		(width 0.127)
		(layer "In5.Cu")
		(net "T2_BLAD2_RXD")
	)
	(segment
		(start 26.126186 -115.33759)
		(end 26.126186 -163.85159)
		(width 0.127)
		(layer "In5.Cu")
		(net "T2_BLAD2_RXD")
	)
	(segment
		(start 86.323424 -56.366664)
		(end 90.357198 -52.33289)
		(width 0.127)
		(layer "In5.Cu")
		(net "T2_BLAD2_RXD")
	)
	(segment
		(start 81.762346 -60.486798)
		(end 85.88248 -56.366664)
		(width 0.127)
		(layer "In5.Cu")
		(net "T2_BLAD2_RXD")
	)
	(segment
		(start 81.762346 -60.486798)
		(end 53.757322 -88.491822)
		(width 0.127)
		(layer "In5.Cu")
		(net "T2_BLAD2_RXD")
	)
	(segment
		(start 26.126186 -163.85159)
		(end 16.64335 -173.334426)
		(width 0.127)
		(layer "In5.Cu")
		(net "T2_BLAD2_RXD")
	)
	(segment
		(start 10.82548 -222.363538)
		(end 9.637522 -223.551496)
		(width 0.127)
		(layer "In5.Cu")
		(net "T2_BLAD2_RXD")
	)
	(segment
		(start 4.146042 -224.473516)
		(end 1.948942 -226.670616)
		(width 0.127)
		(layer "In5.Cu")
		(net "T2_BLAD2_RXD")
	)
	(segment
		(start 9.637522 -223.551496)
		(end 7.78383 -223.551496)
		(width 0.127)
		(layer "In5.Cu")
		(net "T2_BLAD2_RXD")
	)
	(segment
		(start 20.630896 -109.8423)
		(end 26.126186 -115.33759)
		(width 0.127)
		(layer "In5.Cu")
		(net "T2_BLAD2_RXD")
	)
	(segment
		(start 7.78383 -223.551496)
		(end 6.86181 -224.473516)
		(width 0.127)
		(layer "In5.Cu")
		(net "T2_BLAD2_RXD")
	)
	(segment
		(start 6.86181 -224.473516)
		(end 4.146042 -224.473516)
		(width 0.127)
		(layer "In5.Cu")
		(net "T2_BLAD2_RXD")
	)
	(segment
		(start 22.981158 -319.878964)
		(end 22.981158 -335.465674)
		(width 0.1524)
		(layer "F.Cu")
		(net "I2C_PSU3_SDA")
	)
	(segment
		(start 11.808714 -316.854586)
		(end 19.95678 -316.854586)
		(width 0.1524)
		(layer "F.Cu")
		(net "I2C_PSU3_SDA")
	)
	(segment
		(start 6.449822 -318.669924)
		(end 9.993376 -318.669924)
		(width 0.1524)
		(layer "F.Cu")
		(net "I2C_PSU3_SDA")
	)
	(segment
		(start 22.981158 -335.465674)
		(end 23.133558 -335.618074)
		(width 0.1524)
		(layer "F.Cu")
		(net "I2C_PSU3_SDA")
	)
	(segment
		(start 19.95678 -316.854586)
		(end 22.981158 -319.878964)
		(width 0.1524)
		(layer "F.Cu")
		(net "I2C_PSU3_SDA")
	)
	(segment
		(start 9.993376 -318.669924)
		(end 11.808714 -316.854586)
		(width 0.1524)
		(layer "F.Cu")
		(net "I2C_PSU3_SDA")
	)
	(segment
		(start 23.133558 -335.618074)
		(end 23.17496 -335.618074)
		(width 0.1524)
		(layer "F.Cu")
		(net "I2C_PSU3_SDA")
	)
	(segment
		(start 23.17496 -335.618074)
		(end 25.582626 -338.02574)
		(width 0.1524)
		(layer "F.Cu")
		(net "I2C_PSU3_SDA")
	)
	(via
		(at 25.582626 -338.02574)
		(size 0.508)
		(drill 0.254)
		(layers "F.Cu" "B.Cu")
		(net "I2C_PSU3_SDA")
	)
	(segment
		(start 35.53968 -358.190038)
		(end 36.667186 -359.317544)
		(width 0.1524)
		(layer "B.Cu")
		(net "I2C_PSU3_SDA")
	)
	(segment
		(start 26.180034 -351.538286)
		(end 32.831786 -358.190038)
		(width 0.1524)
		(layer "B.Cu")
		(net "I2C_PSU3_SDA")
	)
	(segment
		(start 26.180034 -338.623148)
		(end 26.180034 -351.538286)
		(width 0.1524)
		(layer "B.Cu")
		(net "I2C_PSU3_SDA")
	)
	(segment
		(start 29.064966 -374.501156)
		(end 26.859484 -376.706638)
		(width 0.1524)
		(layer "B.Cu")
		(net "I2C_PSU3_SDA")
	)
	(segment
		(start 34.537396 -446.589912)
		(end 35.53968 -446.589912)
		(width 0.1524)
		(layer "B.Cu")
		(net "I2C_PSU3_SDA")
	)
	(segment
		(start 35.079432 -364.61192)
		(end 34.231326 -365.460026)
		(width 0.1524)
		(layer "B.Cu")
		(net "I2C_PSU3_SDA")
	)
	(segment
		(start 36.162234 -364.61192)
		(end 35.079432 -364.61192)
		(width 0.1524)
		(layer "B.Cu")
		(net "I2C_PSU3_SDA")
	)
	(segment
		(start 26.859484 -376.706638)
		(end 26.859484 -438.912)
		(width 0.1524)
		(layer "B.Cu")
		(net "I2C_PSU3_SDA")
	)
	(segment
		(start 36.667186 -364.106968)
		(end 36.162234 -364.61192)
		(width 0.1524)
		(layer "B.Cu")
		(net "I2C_PSU3_SDA")
	)
	(segment
		(start 25.582626 -338.02574)
		(end 26.180034 -338.623148)
		(width 0.1524)
		(layer "B.Cu")
		(net "I2C_PSU3_SDA")
	)
	(segment
		(start 36.667186 -359.317544)
		(end 36.667186 -364.106968)
		(width 0.1524)
		(layer "B.Cu")
		(net "I2C_PSU3_SDA")
	)
	(segment
		(start 32.831786 -358.190038)
		(end 35.53968 -358.190038)
		(width 0.1524)
		(layer "B.Cu")
		(net "I2C_PSU3_SDA")
	)
	(segment
		(start 26.859484 -438.912)
		(end 34.537396 -446.589912)
		(width 0.1524)
		(layer "B.Cu")
		(net "I2C_PSU3_SDA")
	)
	(segment
		(start 34.231326 -371.258846)
		(end 30.989016 -374.501156)
		(width 0.1524)
		(layer "B.Cu")
		(net "I2C_PSU3_SDA")
	)
	(segment
		(start 30.989016 -374.501156)
		(end 29.064966 -374.501156)
		(width 0.1524)
		(layer "B.Cu")
		(net "I2C_PSU3_SDA")
	)
	(segment
		(start 34.231326 -365.460026)
		(end 34.231326 -371.258846)
		(width 0.1524)
		(layer "B.Cu")
		(net "I2C_PSU3_SDA")
	)
	(via
		(at 87.478108 -485.425242)
		(size 0.508)
		(drill 0.254)
		(layers "F.Cu" "B.Cu")
		(net "T12_BLAD1_TXD")
	)
	(segment
		(start 84.018882 -449.400676)
		(end 81.210404 -446.592198)
		(width 0.127)
		(layer "In2.Cu")
		(net "T12_BLAD1_TXD")
	)
	(segment
		(start 85.300312 -483.247446)
		(end 85.300312 -466.948266)
		(width 0.127)
		(layer "In2.Cu")
		(net "T12_BLAD1_TXD")
	)
	(segment
		(start 85.300312 -466.948266)
		(end 84.018882 -465.666836)
		(width 0.127)
		(layer "In2.Cu")
		(net "T12_BLAD1_TXD")
	)
	(segment
		(start 8.83285 -316.413896)
		(end 8.14324 -316.413896)
		(width 0.127)
		(layer "In2.Cu")
		(net "T12_BLAD1_TXD")
	)
	(segment
		(start 29.882592 -442.445394)
		(end 25.282398 -437.8452)
		(width 0.127)
		(layer "In2.Cu")
		(net "T12_BLAD1_TXD")
	)
	(segment
		(start 25.282398 -437.8452)
		(end 25.282398 -379.89383)
		(width 0.127)
		(layer "In2.Cu")
		(net "T12_BLAD1_TXD")
	)
	(segment
		(start 92.947998 -493.25911)
		(end 92.947998 -497.004594)
		(width 0.127)
		(layer "In2.Cu")
		(net "T12_BLAD1_TXD")
	)
	(segment
		(start 92.695014 -493.006126)
		(end 92.947998 -493.25911)
		(width 0.127)
		(layer "In2.Cu")
		(net "T12_BLAD1_TXD")
	)
	(segment
		(start 92.695014 -490.642148)
		(end 92.695014 -493.006126)
		(width 0.127)
		(layer "In2.Cu")
		(net "T12_BLAD1_TXD")
	)
	(segment
		(start 43.032426 -446.592198)
		(end 38.885622 -442.445394)
		(width 0.127)
		(layer "In2.Cu")
		(net "T12_BLAD1_TXD")
	)
	(segment
		(start 38.885622 -442.445394)
		(end 29.882592 -442.445394)
		(width 0.127)
		(layer "In2.Cu")
		(net "T12_BLAD1_TXD")
	)
	(segment
		(start 84.018882 -465.666836)
		(end 84.018882 -449.400676)
		(width 0.127)
		(layer "In2.Cu")
		(net "T12_BLAD1_TXD")
	)
	(segment
		(start 81.210404 -446.592198)
		(end 43.032426 -446.592198)
		(width 0.127)
		(layer "In2.Cu")
		(net "T12_BLAD1_TXD")
	)
	(segment
		(start 14.745208 -337.029298)
		(end 16.50746 -335.267046)
		(width 0.127)
		(layer "In2.Cu")
		(net "T12_BLAD1_TXD")
	)
	(segment
		(start 86.737698 -498.862858)
		(end 85.63991 -497.76507)
		(width 0.127)
		(layer "In2.Cu")
		(net "T12_BLAD1_TXD")
	)
	(segment
		(start 87.478108 -485.425242)
		(end 92.695014 -490.642148)
		(width 0.127)
		(layer "In2.Cu")
		(net "T12_BLAD1_TXD")
	)
	(segment
		(start 7.22122 -315.491876)
		(end 4.771898 -315.491876)
		(width 0.127)
		(layer "In2.Cu")
		(net "T12_BLAD1_TXD")
	)
	(segment
		(start 87.478108 -485.425242)
		(end 85.300312 -483.247446)
		(width 0.127)
		(layer "In2.Cu")
		(net "T12_BLAD1_TXD")
	)
	(segment
		(start 91.089734 -498.862858)
		(end 86.737698 -498.862858)
		(width 0.127)
		(layer "In2.Cu")
		(net "T12_BLAD1_TXD")
	)
	(segment
		(start 14.745208 -369.35664)
		(end 14.745208 -337.029298)
		(width 0.127)
		(layer "In2.Cu")
		(net "T12_BLAD1_TXD")
	)
	(segment
		(start 16.50746 -324.08876)
		(end 8.83285 -316.413896)
		(width 0.127)
		(layer "In2.Cu")
		(net "T12_BLAD1_TXD")
	)
	(segment
		(start 25.282398 -379.89383)
		(end 14.745208 -369.35664)
		(width 0.127)
		(layer "In2.Cu")
		(net "T12_BLAD1_TXD")
	)
	(segment
		(start 92.947998 -497.004594)
		(end 91.089734 -498.862858)
		(width 0.127)
		(layer "In2.Cu")
		(net "T12_BLAD1_TXD")
	)
	(segment
		(start 16.50746 -335.267046)
		(end 16.50746 -324.08876)
		(width 0.127)
		(layer "In2.Cu")
		(net "T12_BLAD1_TXD")
	)
	(segment
		(start 8.14324 -316.413896)
		(end 7.22122 -315.491876)
		(width 0.127)
		(layer "In2.Cu")
		(net "T12_BLAD1_TXD")
	)
	(segment
		(start 4.771898 -315.491876)
		(end 3.949954 -314.669932)
		(width 0.127)
		(layer "In2.Cu")
		(net "T12_BLAD1_TXD")
	)
	(via
		(at 77.791818 -61.21654)
		(size 0.508)
		(drill 0.254)
		(layers "F.Cu" "B.Cu")
		(net "T2_BLAD1_TXD")
	)
	(segment
		(start 17.88668 -180.91531)
		(end 26.92654 -171.87545)
		(width 0.127)
		(layer "In2.Cu")
		(net "T2_BLAD1_TXD")
	)
	(segment
		(start 77.45095 -61.557408)
		(end 77.791818 -61.21654)
		(width 0.127)
		(layer "In2.Cu")
		(net "T2_BLAD1_TXD")
	)
	(segment
		(start 53.073808 -88.992964)
		(end 77.45095 -64.615822)
		(width 0.127)
		(layer "In2.Cu")
		(net "T2_BLAD1_TXD")
	)
	(segment
		(start 3.948938 -227.670614)
		(end 4.676394 -228.39807)
		(width 0.127)
		(layer "In2.Cu")
		(net "T2_BLAD1_TXD")
	)
	(segment
		(start 26.32202 -169.200068)
		(end 26.32202 -109.55655)
		(width 0.127)
		(layer "In2.Cu")
		(net "T2_BLAD1_TXD")
	)
	(segment
		(start 77.45095 -64.615822)
		(end 77.45095 -61.557408)
		(width 0.127)
		(layer "In2.Cu")
		(net "T2_BLAD1_TXD")
	)
	(segment
		(start 26.92654 -169.804588)
		(end 26.32202 -169.200068)
		(width 0.127)
		(layer "In2.Cu")
		(net "T2_BLAD1_TXD")
	)
	(segment
		(start 85.63991 -53.26507)
		(end 85.63991 -55.201566)
		(width 0.127)
		(layer "In2.Cu")
		(net "T2_BLAD1_TXD")
	)
	(segment
		(start 6.847332 -228.39807)
		(end 7.739888 -227.505514)
		(width 0.127)
		(layer "In2.Cu")
		(net "T2_BLAD1_TXD")
	)
	(segment
		(start 26.515568 -104.36606)
		(end 25.826974 -103.677466)
		(width 0.127)
		(layer "In2.Cu")
		(net "T2_BLAD1_TXD")
	)
	(segment
		(start 17.88668 -197.89394)
		(end 17.88668 -180.91531)
		(width 0.127)
		(layer "In2.Cu")
		(net "T2_BLAD1_TXD")
	)
	(segment
		(start 25.826974 -103.677466)
		(end 25.826974 -101.814376)
		(width 0.127)
		(layer "In2.Cu")
		(net "T2_BLAD1_TXD")
	)
	(segment
		(start 81.095342 -57.913016)
		(end 77.791818 -61.21654)
		(width 0.127)
		(layer "In2.Cu")
		(net "T2_BLAD1_TXD")
	)
	(segment
		(start 85.63991 -55.201566)
		(end 82.92846 -57.913016)
		(width 0.127)
		(layer "In2.Cu")
		(net "T2_BLAD1_TXD")
	)
	(segment
		(start 25.826974 -101.814376)
		(end 25.407366 -101.394768)
		(width 0.127)
		(layer "In2.Cu")
		(net "T2_BLAD1_TXD")
	)
	(segment
		(start 25.407366 -93.16974)
		(end 29.584142 -88.992964)
		(width 0.127)
		(layer "In2.Cu")
		(net "T2_BLAD1_TXD")
	)
	(segment
		(start 4.676394 -228.39807)
		(end 6.847332 -228.39807)
		(width 0.127)
		(layer "In2.Cu")
		(net "T2_BLAD1_TXD")
	)
	(segment
		(start 11.234166 -225.911156)
		(end 11.234166 -204.546454)
		(width 0.127)
		(layer "In2.Cu")
		(net "T2_BLAD1_TXD")
	)
	(segment
		(start 26.32202 -109.55655)
		(end 27.01036 -108.86821)
		(width 0.127)
		(layer "In2.Cu")
		(net "T2_BLAD1_TXD")
	)
	(segment
		(start 27.01036 -108.86821)
		(end 27.01036 -107.668568)
		(width 0.127)
		(layer "In2.Cu")
		(net "T2_BLAD1_TXD")
	)
	(segment
		(start 11.234166 -204.546454)
		(end 17.88668 -197.89394)
		(width 0.127)
		(layer "In2.Cu")
		(net "T2_BLAD1_TXD")
	)
	(segment
		(start 25.407366 -101.394768)
		(end 25.407366 -93.16974)
		(width 0.127)
		(layer "In2.Cu")
		(net "T2_BLAD1_TXD")
	)
	(segment
		(start 27.01036 -107.668568)
		(end 26.515568 -107.173776)
		(width 0.127)
		(layer "In2.Cu")
		(net "T2_BLAD1_TXD")
	)
	(segment
		(start 29.584142 -88.992964)
		(end 53.073808 -88.992964)
		(width 0.127)
		(layer "In2.Cu")
		(net "T2_BLAD1_TXD")
	)
	(segment
		(start 26.515568 -107.173776)
		(end 26.515568 -104.36606)
		(width 0.127)
		(layer "In2.Cu")
		(net "T2_BLAD1_TXD")
	)
	(segment
		(start 26.92654 -171.87545)
		(end 26.92654 -169.804588)
		(width 0.127)
		(layer "In2.Cu")
		(net "T2_BLAD1_TXD")
	)
	(segment
		(start 7.739888 -227.505514)
		(end 9.639808 -227.505514)
		(width 0.127)
		(layer "In2.Cu")
		(net "T2_BLAD1_TXD")
	)
	(segment
		(start 9.639808 -227.505514)
		(end 11.234166 -225.911156)
		(width 0.127)
		(layer "In2.Cu")
		(net "T2_BLAD1_TXD")
	)
	(segment
		(start 82.92846 -57.913016)
		(end 81.095342 -57.913016)
		(width 0.127)
		(layer "In2.Cu")
		(net "T2_BLAD1_TXD")
	)
	(segment
		(start 28.17876 -373.43207)
		(end 27.56916 -373.43207)
		(width 0.508)
		(layer "F.Cu")
		(net "PSU5_REMOTE_N")
	)
	(segment
		(start 28.180792 -373.430038)
		(end 28.17876 -373.43207)
		(width 0.508)
		(layer "F.Cu")
		(net "PSU5_REMOTE_N")
	)
	(segment
		(start 30.45968 -373.430038)
		(end 28.180792 -373.430038)
		(width 0.508)
		(layer "F.Cu")
		(net "PSU5_REMOTE_N")
	)
	(via
		(at 93.915992 -488.13593)
		(size 0.508)
		(drill 0.254)
		(layers "F.Cu" "B.Cu")
		(net "T12_BLAD3_TXD")
	)
	(segment
		(start 89.74709 -442.962284)
		(end 46.82236 -442.962284)
		(width 0.127)
		(layer "In5.Cu")
		(net "T12_BLAD3_TXD")
	)
	(segment
		(start 99.57943 -452.794624)
		(end 89.74709 -442.962284)
		(width 0.127)
		(layer "In5.Cu")
		(net "T12_BLAD3_TXD")
	)
	(segment
		(start 46.82236 -442.962284)
		(end 43.572938 -439.712862)
		(width 0.127)
		(layer "In5.Cu")
		(net "T12_BLAD3_TXD")
	)
	(segment
		(start 21.293582 -350.985074)
		(end 20.897596 -350.589088)
		(width 0.127)
		(layer "In5.Cu")
		(net "T12_BLAD3_TXD")
	)
	(segment
		(start 5.925058 -311.441846)
		(end 4.32943 -309.846218)
		(width 0.127)
		(layer "In5.Cu")
		(net "T12_BLAD3_TXD")
	)
	(segment
		(start 13.247116 -310.396382)
		(end 7.88162 -310.396382)
		(width 0.127)
		(layer "In5.Cu")
		(net "T12_BLAD3_TXD")
	)
	(segment
		(start 93.915992 -488.13593)
		(end 99.57943 -482.472492)
		(width 0.127)
		(layer "In5.Cu")
		(net "T12_BLAD3_TXD")
	)
	(segment
		(start 7.88162 -310.396382)
		(end 6.836156 -311.441846)
		(width 0.127)
		(layer "In5.Cu")
		(net "T12_BLAD3_TXD")
	)
	(segment
		(start 28.567634 -437.781446)
		(end 28.567634 -379.392434)
		(width 0.127)
		(layer "In5.Cu")
		(net "T12_BLAD3_TXD")
	)
	(segment
		(start 93.915992 -488.13593)
		(end 86.826852 -495.22507)
		(width 0.127)
		(layer "In5.Cu")
		(net "T12_BLAD3_TXD")
	)
	(segment
		(start 28.567634 -379.392434)
		(end 21.293582 -372.118382)
		(width 0.127)
		(layer "In5.Cu")
		(net "T12_BLAD3_TXD")
	)
	(segment
		(start 2.126234 -309.846218)
		(end 1.949958 -309.669942)
		(width 0.127)
		(layer "In5.Cu")
		(net "T12_BLAD3_TXD")
	)
	(segment
		(start 86.826852 -495.22507)
		(end 85.63991 -495.22507)
		(width 0.127)
		(layer "In5.Cu")
		(net "T12_BLAD3_TXD")
	)
	(segment
		(start 30.49905 -439.712862)
		(end 28.567634 -437.781446)
		(width 0.127)
		(layer "In5.Cu")
		(net "T12_BLAD3_TXD")
	)
	(segment
		(start 20.897596 -318.046862)
		(end 13.247116 -310.396382)
		(width 0.127)
		(layer "In5.Cu")
		(net "T12_BLAD3_TXD")
	)
	(segment
		(start 4.32943 -309.846218)
		(end 2.126234 -309.846218)
		(width 0.127)
		(layer "In5.Cu")
		(net "T12_BLAD3_TXD")
	)
	(segment
		(start 6.836156 -311.441846)
		(end 5.925058 -311.441846)
		(width 0.127)
		(layer "In5.Cu")
		(net "T12_BLAD3_TXD")
	)
	(segment
		(start 20.897596 -350.589088)
		(end 20.897596 -318.046862)
		(width 0.127)
		(layer "In5.Cu")
		(net "T12_BLAD3_TXD")
	)
	(segment
		(start 43.572938 -439.712862)
		(end 30.49905 -439.712862)
		(width 0.127)
		(layer "In5.Cu")
		(net "T12_BLAD3_TXD")
	)
	(segment
		(start 21.293582 -372.118382)
		(end 21.293582 -350.985074)
		(width 0.127)
		(layer "In5.Cu")
		(net "T12_BLAD3_TXD")
	)
	(segment
		(start 99.57943 -482.472492)
		(end 99.57943 -452.794624)
		(width 0.127)
		(layer "In5.Cu")
		(net "T12_BLAD3_TXD")
	)
	(via
		(at 79.99476 -64.029082)
		(size 0.508)
		(drill 0.254)
		(layers "F.Cu" "B.Cu")
		(net "T2_BLAD1_EN")
	)
	(segment
		(start 79.99476 -64.029336)
		(end 53.981858 -90.042238)
		(width 0.127)
		(layer "In2.Cu")
		(net "T2_BLAD1_EN")
	)
	(segment
		(start 28.122626 -109.444536)
		(end 27.018234 -110.548928)
		(width 0.127)
		(layer "In2.Cu")
		(net "T2_BLAD1_EN")
	)
	(segment
		(start 27.585416 -101.690424)
		(end 27.585416 -106.842306)
		(width 0.127)
		(layer "In2.Cu")
		(net "T2_BLAD1_EN")
	)
	(segment
		(start 7.919466 -229.93731)
		(end 7.023608 -230.833168)
		(width 0.127)
		(layer "In2.Cu")
		(net "T2_BLAD1_EN")
	)
	(segment
		(start 87.477346 -54.810152)
		(end 88.17991 -54.107588)
		(width 0.127)
		(layer "In2.Cu")
		(net "T2_BLAD1_EN")
	)
	(segment
		(start 53.981858 -90.042238)
		(end 30.144212 -90.042238)
		(width 0.127)
		(layer "In2.Cu")
		(net "T2_BLAD1_EN")
	)
	(segment
		(start 88.17991 -54.107588)
		(end 88.17991 -53.26507)
		(width 0.127)
		(layer "In2.Cu")
		(net "T2_BLAD1_EN")
	)
	(segment
		(start 3.232912 -231.29367)
		(end 3.232912 -232.954576)
		(width 0.127)
		(layer "In2.Cu")
		(net "T2_BLAD1_EN")
	)
	(segment
		(start 22.710648 -201.506582)
		(end 22.710648 -219.1893)
		(width 0.127)
		(layer "In2.Cu")
		(net "T2_BLAD1_EN")
	)
	(segment
		(start 3.693414 -230.833168)
		(end 3.232912 -231.29367)
		(width 0.127)
		(layer "In2.Cu")
		(net "T2_BLAD1_EN")
	)
	(segment
		(start 79.99476 -64.029336)
		(end 87.477346 -56.54675)
		(width 0.127)
		(layer "In2.Cu")
		(net "T2_BLAD1_EN")
	)
	(segment
		(start 27.727656 -174.789338)
		(end 18.894298 -183.622696)
		(width 0.127)
		(layer "In2.Cu")
		(net "T2_BLAD1_EN")
	)
	(segment
		(start 28.122626 -107.379516)
		(end 28.122626 -109.444536)
		(width 0.127)
		(layer "In2.Cu")
		(net "T2_BLAD1_EN")
	)
	(segment
		(start 27.018234 -168.96207)
		(end 27.727656 -169.671492)
		(width 0.127)
		(layer "In2.Cu")
		(net "T2_BLAD1_EN")
	)
	(segment
		(start 27.585416 -106.842306)
		(end 28.122626 -107.379516)
		(width 0.127)
		(layer "In2.Cu")
		(net "T2_BLAD1_EN")
	)
	(segment
		(start 30.144212 -90.042238)
		(end 26.50871 -93.67774)
		(width 0.127)
		(layer "In2.Cu")
		(net "T2_BLAD1_EN")
	)
	(segment
		(start 18.894298 -197.690232)
		(end 22.710648 -201.506582)
		(width 0.127)
		(layer "In2.Cu")
		(net "T2_BLAD1_EN")
	)
	(segment
		(start 26.50871 -93.67774)
		(end 26.50871 -100.613718)
		(width 0.127)
		(layer "In2.Cu")
		(net "T2_BLAD1_EN")
	)
	(segment
		(start 11.962638 -229.93731)
		(end 7.919466 -229.93731)
		(width 0.127)
		(layer "In2.Cu")
		(net "T2_BLAD1_EN")
	)
	(segment
		(start 18.894298 -183.622696)
		(end 18.894298 -197.690232)
		(width 0.127)
		(layer "In2.Cu")
		(net "T2_BLAD1_EN")
	)
	(segment
		(start 87.477346 -56.54675)
		(end 87.477346 -54.810152)
		(width 0.127)
		(layer "In2.Cu")
		(net "T2_BLAD1_EN")
	)
	(segment
		(start 79.99476 -64.029082)
		(end 79.99476 -64.029336)
		(width 0.127)
		(layer "In2.Cu")
		(net "T2_BLAD1_EN")
	)
	(segment
		(start 26.50871 -100.613718)
		(end 27.585416 -101.690424)
		(width 0.127)
		(layer "In2.Cu")
		(net "T2_BLAD1_EN")
	)
	(segment
		(start 27.018234 -110.548928)
		(end 27.018234 -168.96207)
		(width 0.127)
		(layer "In2.Cu")
		(net "T2_BLAD1_EN")
	)
	(segment
		(start 27.727656 -169.671492)
		(end 27.727656 -174.789338)
		(width 0.127)
		(layer "In2.Cu")
		(net "T2_BLAD1_EN")
	)
	(segment
		(start 22.710648 -219.1893)
		(end 11.962638 -229.93731)
		(width 0.127)
		(layer "In2.Cu")
		(net "T2_BLAD1_EN")
	)
	(segment
		(start 3.232912 -232.954576)
		(end 3.948938 -233.670602)
		(width 0.127)
		(layer "In2.Cu")
		(net "T2_BLAD1_EN")
	)
	(segment
		(start 7.023608 -230.833168)
		(end 3.693414 -230.833168)
		(width 0.127)
		(layer "In2.Cu")
		(net "T2_BLAD1_EN")
	)
	(via
		(at 96.368362 -486.984294)
		(size 0.508)
		(drill 0.254)
		(layers "F.Cu" "B.Cu")
		(net "T12_BLAD4_RXD")
	)
	(segment
		(start 96.368362 -486.984294)
		(end 91.98991 -491.362746)
		(width 0.127)
		(layer "In5.Cu")
		(net "T12_BLAD4_RXD")
	)
	(segment
		(start 100.286058 -452.343774)
		(end 90.174826 -442.232542)
		(width 0.127)
		(layer "In5.Cu")
		(net "T12_BLAD4_RXD")
	)
	(segment
		(start 7.274052 -307.633624)
		(end 4.986274 -307.633624)
		(width 0.127)
		(layer "In5.Cu")
		(net "T12_BLAD4_RXD")
	)
	(segment
		(start 8.05688 -308.416452)
		(end 7.274052 -307.633624)
		(width 0.127)
		(layer "In5.Cu")
		(net "T12_BLAD4_RXD")
	)
	(segment
		(start 91.98991 -491.362746)
		(end 91.98991 -493.95507)
		(width 0.127)
		(layer "In5.Cu")
		(net "T12_BLAD4_RXD")
	)
	(segment
		(start 29.278326 -377.794012)
		(end 21.953982 -370.469668)
		(width 0.127)
		(layer "In5.Cu")
		(net "T12_BLAD4_RXD")
	)
	(segment
		(start 21.557996 -350.315276)
		(end 21.557996 -316.461902)
		(width 0.127)
		(layer "In5.Cu")
		(net "T12_BLAD4_RXD")
	)
	(segment
		(start 4.986274 -307.633624)
		(end 3.949954 -308.669944)
		(width 0.127)
		(layer "In5.Cu")
		(net "T12_BLAD4_RXD")
	)
	(segment
		(start 29.278326 -437.330088)
		(end 29.278326 -377.794012)
		(width 0.127)
		(layer "In5.Cu")
		(net "T12_BLAD4_RXD")
	)
	(segment
		(start 21.557996 -316.461902)
		(end 13.512546 -308.416452)
		(width 0.127)
		(layer "In5.Cu")
		(net "T12_BLAD4_RXD")
	)
	(segment
		(start 43.889676 -439.052462)
		(end 31.0007 -439.052462)
		(width 0.127)
		(layer "In5.Cu")
		(net "T12_BLAD4_RXD")
	)
	(segment
		(start 47.069756 -442.232542)
		(end 43.889676 -439.052462)
		(width 0.127)
		(layer "In5.Cu")
		(net "T12_BLAD4_RXD")
	)
	(segment
		(start 100.286058 -483.066598)
		(end 100.286058 -452.343774)
		(width 0.127)
		(layer "In5.Cu")
		(net "T12_BLAD4_RXD")
	)
	(segment
		(start 96.368362 -486.984294)
		(end 100.286058 -483.066598)
		(width 0.127)
		(layer "In5.Cu")
		(net "T12_BLAD4_RXD")
	)
	(segment
		(start 21.953982 -370.469668)
		(end 21.953982 -350.711262)
		(width 0.127)
		(layer "In5.Cu")
		(net "T12_BLAD4_RXD")
	)
	(segment
		(start 13.512546 -308.416452)
		(end 8.05688 -308.416452)
		(width 0.127)
		(layer "In5.Cu")
		(net "T12_BLAD4_RXD")
	)
	(segment
		(start 21.953982 -350.711262)
		(end 21.557996 -350.315276)
		(width 0.127)
		(layer "In5.Cu")
		(net "T12_BLAD4_RXD")
	)
	(segment
		(start 31.0007 -439.052462)
		(end 29.278326 -437.330088)
		(width 0.127)
		(layer "In5.Cu")
		(net "T12_BLAD4_RXD")
	)
	(segment
		(start 90.174826 -442.232542)
		(end 47.069756 -442.232542)
		(width 0.127)
		(layer "In5.Cu")
		(net "T12_BLAD4_RXD")
	)
	(via
		(at 80.794352 -58.88228)
		(size 0.508)
		(drill 0.254)
		(layers "F.Cu" "B.Cu")
		(net "T2_BLAD4_RXD")
	)
	(segment
		(start 14.74089 -198.189342)
		(end 9.799066 -203.131166)
		(width 0.127)
		(layer "In5.Cu")
		(net "T2_BLAD4_RXD")
	)
	(segment
		(start 91.98991 -49.45507)
		(end 91.942666 -49.45507)
		(width 0.127)
		(layer "In5.Cu")
		(net "T2_BLAD4_RXD")
	)
	(segment
		(start 4.749292 -220.870272)
		(end 3.948938 -221.670626)
		(width 0.127)
		(layer "In5.Cu")
		(net "T2_BLAD4_RXD")
	)
	(segment
		(start 25.088342 -163.488116)
		(end 14.74089 -173.835568)
		(width 0.127)
		(layer "In5.Cu")
		(net "T2_BLAD4_RXD")
	)
	(segment
		(start 19.376136 -93.016832)
		(end 19.376136 -110.595156)
		(width 0.127)
		(layer "In5.Cu")
		(net "T2_BLAD4_RXD")
	)
	(segment
		(start 76.914756 -61.890148)
		(end 51.335432 -87.469472)
		(width 0.127)
		(layer "In5.Cu")
		(net "T2_BLAD4_RXD")
	)
	(segment
		(start 25.088342 -116.307362)
		(end 25.088342 -163.488116)
		(width 0.127)
		(layer "In5.Cu")
		(net "T2_BLAD4_RXD")
	)
	(segment
		(start 91.007946 -48.52035)
		(end 86.229444 -48.52035)
		(width 0.127)
		(layer "In5.Cu")
		(net "T2_BLAD4_RXD")
	)
	(segment
		(start 9.799066 -203.131166)
		(end 9.799066 -219.00134)
		(width 0.127)
		(layer "In5.Cu")
		(net "T2_BLAD4_RXD")
	)
	(segment
		(start 9.799066 -219.00134)
		(end 9.02081 -219.779596)
		(width 0.127)
		(layer "In5.Cu")
		(net "T2_BLAD4_RXD")
	)
	(segment
		(start 84.194904 -55.481728)
		(end 80.794352 -58.88228)
		(width 0.127)
		(layer "In5.Cu")
		(net "T2_BLAD4_RXD")
	)
	(segment
		(start 14.74089 -173.835568)
		(end 14.74089 -198.189342)
		(width 0.127)
		(layer "In5.Cu")
		(net "T2_BLAD4_RXD")
	)
	(segment
		(start 19.376136 -110.595156)
		(end 25.088342 -116.307362)
		(width 0.127)
		(layer "In5.Cu")
		(net "T2_BLAD4_RXD")
	)
	(segment
		(start 9.02081 -219.779596)
		(end 7.992618 -219.779596)
		(width 0.127)
		(layer "In5.Cu")
		(net "T2_BLAD4_RXD")
	)
	(segment
		(start 91.942666 -49.45507)
		(end 91.007946 -48.52035)
		(width 0.127)
		(layer "In5.Cu")
		(net "T2_BLAD4_RXD")
	)
	(segment
		(start 6.901942 -220.870272)
		(end 4.749292 -220.870272)
		(width 0.127)
		(layer "In5.Cu")
		(net "T2_BLAD4_RXD")
	)
	(segment
		(start 51.335432 -87.469472)
		(end 24.923496 -87.469472)
		(width 0.127)
		(layer "In5.Cu")
		(net "T2_BLAD4_RXD")
	)
	(segment
		(start 80.794352 -58.88228)
		(end 77.786484 -61.890148)
		(width 0.127)
		(layer "In5.Cu")
		(net "T2_BLAD4_RXD")
	)
	(segment
		(start 84.194904 -50.55489)
		(end 84.194904 -55.481728)
		(width 0.127)
		(layer "In5.Cu")
		(net "T2_BLAD4_RXD")
	)
	(segment
		(start 86.229444 -48.52035)
		(end 84.194904 -50.55489)
		(width 0.127)
		(layer "In5.Cu")
		(net "T2_BLAD4_RXD")
	)
	(segment
		(start 77.786484 -61.890148)
		(end 76.914756 -61.890148)
		(width 0.127)
		(layer "In5.Cu")
		(net "T2_BLAD4_RXD")
	)
	(segment
		(start 7.992618 -219.779596)
		(end 6.901942 -220.870272)
		(width 0.127)
		(layer "In5.Cu")
		(net "T2_BLAD4_RXD")
	)
	(segment
		(start 24.923496 -87.469472)
		(end 19.376136 -93.016832)
		(width 0.127)
		(layer "In5.Cu")
		(net "T2_BLAD4_RXD")
	)
	(via
		(at 78.246478 -63.211202)
		(size 0.508)
		(drill 0.254)
		(layers "F.Cu" "B.Cu")
		(net "T2_BLAD1_RXD")
	)
	(segment
		(start 13.468604 -224.317052)
		(end 13.468604 -222.147638)
		(width 0.127)
		(layer "In2.Cu")
		(net "T2_BLAD1_RXD")
	)
	(segment
		(start 81.66354 -58.821066)
		(end 82.191352 -58.293254)
		(width 0.127)
		(layer "In2.Cu")
		(net "T2_BLAD1_RXD")
	)
	(segment
		(start 27.34056 -109.063028)
		(end 27.34056 -107.531662)
		(width 0.127)
		(layer "In2.Cu")
		(net "T2_BLAD1_RXD")
	)
	(segment
		(start 27.25674 -172.01261)
		(end 27.25674 -169.667682)
		(width 0.127)
		(layer "In2.Cu")
		(net "T2_BLAD1_RXD")
	)
	(segment
		(start 26.925016 -107.116118)
		(end 26.925016 -104.308148)
		(width 0.127)
		(layer "In2.Cu")
		(net "T2_BLAD1_RXD")
	)
	(segment
		(start 3.444494 -228.670612)
		(end 3.548634 -228.774752)
		(width 0.127)
		(layer "In2.Cu")
		(net "T2_BLAD1_RXD")
	)
	(segment
		(start 3.548634 -228.774752)
		(end 7.003542 -228.774752)
		(width 0.127)
		(layer "In2.Cu")
		(net "T2_BLAD1_RXD")
	)
	(segment
		(start 86.39302 -55.31739)
		(end 86.39302 -54.272688)
		(width 0.127)
		(layer "In2.Cu")
		(net "T2_BLAD1_RXD")
	)
	(segment
		(start 26.688034 -109.715554)
		(end 27.34056 -109.063028)
		(width 0.127)
		(layer "In2.Cu")
		(net "T2_BLAD1_RXD")
	)
	(segment
		(start 29.725874 -89.335102)
		(end 53.351684 -89.335102)
		(width 0.127)
		(layer "In2.Cu")
		(net "T2_BLAD1_RXD")
	)
	(segment
		(start 7.003542 -228.774752)
		(end 7.896098 -227.882196)
		(width 0.127)
		(layer "In2.Cu")
		(net "T2_BLAD1_RXD")
	)
	(segment
		(start 81.66354 -59.79414)
		(end 81.66354 -58.821066)
		(width 0.127)
		(layer "In2.Cu")
		(net "T2_BLAD1_RXD")
	)
	(segment
		(start 7.896098 -227.882196)
		(end 9.90346 -227.882196)
		(width 0.127)
		(layer "In2.Cu")
		(net "T2_BLAD1_RXD")
	)
	(segment
		(start 25.742392 -101.184202)
		(end 25.742392 -93.318584)
		(width 0.127)
		(layer "In2.Cu")
		(net "T2_BLAD1_RXD")
	)
	(segment
		(start 26.688034 -169.098976)
		(end 26.688034 -109.715554)
		(width 0.127)
		(layer "In2.Cu")
		(net "T2_BLAD1_RXD")
	)
	(segment
		(start 27.25674 -169.667682)
		(end 26.688034 -169.098976)
		(width 0.127)
		(layer "In2.Cu")
		(net "T2_BLAD1_RXD")
	)
	(segment
		(start 26.157174 -103.540306)
		(end 26.157174 -101.598984)
		(width 0.127)
		(layer "In2.Cu")
		(net "T2_BLAD1_RXD")
	)
	(segment
		(start 53.351684 -89.335102)
		(end 78.246478 -64.440308)
		(width 0.127)
		(layer "In2.Cu")
		(net "T2_BLAD1_RXD")
	)
	(segment
		(start 1.948942 -228.670612)
		(end 3.444494 -228.670612)
		(width 0.127)
		(layer "In2.Cu")
		(net "T2_BLAD1_RXD")
	)
	(segment
		(start 27.34056 -107.531662)
		(end 26.925016 -107.116118)
		(width 0.127)
		(layer "In2.Cu")
		(net "T2_BLAD1_RXD")
	)
	(segment
		(start 78.246478 -63.211202)
		(end 81.66354 -59.79414)
		(width 0.127)
		(layer "In2.Cu")
		(net "T2_BLAD1_RXD")
	)
	(segment
		(start 78.246478 -64.440308)
		(end 78.246478 -63.211202)
		(width 0.127)
		(layer "In2.Cu")
		(net "T2_BLAD1_RXD")
	)
	(segment
		(start 18.222468 -198.080884)
		(end 18.222468 -181.046882)
		(width 0.127)
		(layer "In2.Cu")
		(net "T2_BLAD1_RXD")
	)
	(segment
		(start 86.608412 -54.057296)
		(end 86.608412 -52.307236)
		(width 0.127)
		(layer "In2.Cu")
		(net "T2_BLAD1_RXD")
	)
	(segment
		(start 82.191352 -58.293254)
		(end 83.417156 -58.293254)
		(width 0.127)
		(layer "In2.Cu")
		(net "T2_BLAD1_RXD")
	)
	(segment
		(start 13.468604 -222.147638)
		(end 21.949664 -213.666578)
		(width 0.127)
		(layer "In2.Cu")
		(net "T2_BLAD1_RXD")
	)
	(segment
		(start 25.742392 -93.318584)
		(end 29.725874 -89.335102)
		(width 0.127)
		(layer "In2.Cu")
		(net "T2_BLAD1_RXD")
	)
	(segment
		(start 86.608412 -52.307236)
		(end 86.915244 -52.000404)
		(width 0.127)
		(layer "In2.Cu")
		(net "T2_BLAD1_RXD")
	)
	(segment
		(start 21.949664 -213.666578)
		(end 21.949664 -201.80808)
		(width 0.127)
		(layer "In2.Cu")
		(net "T2_BLAD1_RXD")
	)
	(segment
		(start 86.915244 -52.000404)
		(end 86.90991 -51.99507)
		(width 0.127)
		(layer "In2.Cu")
		(net "T2_BLAD1_RXD")
	)
	(segment
		(start 9.90346 -227.882196)
		(end 13.468604 -224.317052)
		(width 0.127)
		(layer "In2.Cu")
		(net "T2_BLAD1_RXD")
	)
	(segment
		(start 21.949664 -201.80808)
		(end 18.222468 -198.080884)
		(width 0.127)
		(layer "In2.Cu")
		(net "T2_BLAD1_RXD")
	)
	(segment
		(start 83.417156 -58.293254)
		(end 86.39302 -55.31739)
		(width 0.127)
		(layer "In2.Cu")
		(net "T2_BLAD1_RXD")
	)
	(segment
		(start 18.222468 -181.046882)
		(end 27.25674 -172.01261)
		(width 0.127)
		(layer "In2.Cu")
		(net "T2_BLAD1_RXD")
	)
	(segment
		(start 86.39302 -54.272688)
		(end 86.608412 -54.057296)
		(width 0.127)
		(layer "In2.Cu")
		(net "T2_BLAD1_RXD")
	)
	(segment
		(start 26.925016 -104.308148)
		(end 26.157174 -103.540306)
		(width 0.127)
		(layer "In2.Cu")
		(net "T2_BLAD1_RXD")
	)
	(segment
		(start 26.157174 -101.598984)
		(end 25.742392 -101.184202)
		(width 0.127)
		(layer "In2.Cu")
		(net "T2_BLAD1_RXD")
	)
	(via
		(at 87.766398 -486.805732)
		(size 0.508)
		(drill 0.254)
		(layers "F.Cu" "B.Cu")
		(net "T12_BLAD1_RXD")
	)
	(segment
		(start 87.766398 -486.805732)
		(end 90.278966 -489.3183)
		(width 0.127)
		(layer "In2.Cu")
		(net "T12_BLAD1_RXD")
	)
	(segment
		(start 90.41511 -496.09248)
		(end 90.41511 -496.820444)
		(width 0.127)
		(layer "In2.Cu")
		(net "T12_BLAD1_RXD")
	)
	(segment
		(start 12.757404 -323.037708)
		(end 12.757404 -320.92138)
		(width 0.127)
		(layer "In2.Cu")
		(net "T12_BLAD1_RXD")
	)
	(segment
		(start 81.073498 -446.922398)
		(end 42.89552 -446.922398)
		(width 0.127)
		(layer "In2.Cu")
		(net "T12_BLAD1_RXD")
	)
	(segment
		(start 89.939622 -494.763806)
		(end 89.939622 -495.616992)
		(width 0.127)
		(layer "In2.Cu")
		(net "T12_BLAD1_RXD")
	)
	(segment
		(start 14.299184 -324.579488)
		(end 12.757404 -323.037708)
		(width 0.127)
		(layer "In2.Cu")
		(net "T12_BLAD1_RXD")
	)
	(segment
		(start 8.589518 -316.753494)
		(end 7.861554 -316.753494)
		(width 0.127)
		(layer "In2.Cu")
		(net "T12_BLAD1_RXD")
	)
	(segment
		(start 4.226306 -315.66993)
		(end 1.949958 -315.66993)
		(width 0.127)
		(layer "In2.Cu")
		(net "T12_BLAD1_RXD")
	)
	(segment
		(start 12.757404 -320.92138)
		(end 8.589518 -316.753494)
		(width 0.127)
		(layer "In2.Cu")
		(net "T12_BLAD1_RXD")
	)
	(segment
		(start 89.939622 -495.616992)
		(end 90.41511 -496.09248)
		(width 0.127)
		(layer "In2.Cu")
		(net "T12_BLAD1_RXD")
	)
	(segment
		(start 4.49453 -315.938154)
		(end 4.226306 -315.66993)
		(width 0.127)
		(layer "In2.Cu")
		(net "T12_BLAD1_RXD")
	)
	(segment
		(start 90.278966 -489.3183)
		(end 90.278966 -494.424462)
		(width 0.127)
		(layer "In2.Cu")
		(net "T12_BLAD1_RXD")
	)
	(segment
		(start 7.046214 -315.938154)
		(end 4.49453 -315.938154)
		(width 0.127)
		(layer "In2.Cu")
		(net "T12_BLAD1_RXD")
	)
	(segment
		(start 90.278966 -494.424462)
		(end 89.939622 -494.763806)
		(width 0.127)
		(layer "In2.Cu")
		(net "T12_BLAD1_RXD")
	)
	(segment
		(start 84.970112 -484.009446)
		(end 84.970112 -467.085172)
		(width 0.127)
		(layer "In2.Cu")
		(net "T12_BLAD1_RXD")
	)
	(segment
		(start 24.917908 -438.077356)
		(end 24.917908 -380.027688)
		(width 0.127)
		(layer "In2.Cu")
		(net "T12_BLAD1_RXD")
	)
	(segment
		(start 90.41511 -496.820444)
		(end 89.754964 -497.48059)
		(width 0.127)
		(layer "In2.Cu")
		(net "T12_BLAD1_RXD")
	)
	(segment
		(start 24.917908 -380.027688)
		(end 14.299184 -369.408964)
		(width 0.127)
		(layer "In2.Cu")
		(net "T12_BLAD1_RXD")
	)
	(segment
		(start 7.861554 -316.753494)
		(end 7.046214 -315.938154)
		(width 0.127)
		(layer "In2.Cu")
		(net "T12_BLAD1_RXD")
	)
	(segment
		(start 29.616146 -442.775594)
		(end 24.917908 -438.077356)
		(width 0.127)
		(layer "In2.Cu")
		(net "T12_BLAD1_RXD")
	)
	(segment
		(start 84.970112 -467.085172)
		(end 83.688682 -465.803742)
		(width 0.127)
		(layer "In2.Cu")
		(net "T12_BLAD1_RXD")
	)
	(segment
		(start 38.748716 -442.775594)
		(end 29.616146 -442.775594)
		(width 0.127)
		(layer "In2.Cu")
		(net "T12_BLAD1_RXD")
	)
	(segment
		(start 42.89552 -446.922398)
		(end 38.748716 -442.775594)
		(width 0.127)
		(layer "In2.Cu")
		(net "T12_BLAD1_RXD")
	)
	(segment
		(start 88.138762 -496.49507)
		(end 86.90991 -496.49507)
		(width 0.127)
		(layer "In2.Cu")
		(net "T12_BLAD1_RXD")
	)
	(segment
		(start 89.754964 -497.48059)
		(end 89.124282 -497.48059)
		(width 0.127)
		(layer "In2.Cu")
		(net "T12_BLAD1_RXD")
	)
	(segment
		(start 87.766398 -486.805732)
		(end 84.970112 -484.009446)
		(width 0.127)
		(layer "In2.Cu")
		(net "T12_BLAD1_RXD")
	)
	(segment
		(start 14.299184 -369.408964)
		(end 14.299184 -324.579488)
		(width 0.127)
		(layer "In2.Cu")
		(net "T12_BLAD1_RXD")
	)
	(segment
		(start 83.688682 -449.537582)
		(end 81.073498 -446.922398)
		(width 0.127)
		(layer "In2.Cu")
		(net "T12_BLAD1_RXD")
	)
	(segment
		(start 89.124282 -497.48059)
		(end 88.138762 -496.49507)
		(width 0.127)
		(layer "In2.Cu")
		(net "T12_BLAD1_RXD")
	)
	(segment
		(start 83.688682 -465.803742)
		(end 83.688682 -449.537582)
		(width 0.127)
		(layer "In2.Cu")
		(net "T12_BLAD1_RXD")
	)
	(via
		(at 92.306394 -488.558586)
		(size 0.508)
		(drill 0.254)
		(layers "F.Cu" "B.Cu")
		(net "T12_BLAD3_RXD")
	)
	(segment
		(start 92.306394 -488.558586)
		(end 92.863924 -488.558586)
		(width 0.127)
		(layer "In5.Cu")
		(net "T12_BLAD3_RXD")
	)
	(segment
		(start 44.85894 -442.234066)
		(end 32.438848 -442.234066)
		(width 0.127)
		(layer "In5.Cu")
		(net "T12_BLAD3_RXD")
	)
	(segment
		(start 8.114538 -310.842914)
		(end 7.117588 -311.839864)
		(width 0.127)
		(layer "In5.Cu")
		(net "T12_BLAD3_RXD")
	)
	(segment
		(start 86.90991 -493.95507)
		(end 92.306394 -488.558586)
		(width 0.127)
		(layer "In5.Cu")
		(net "T12_BLAD3_RXD")
	)
	(segment
		(start 28.214066 -379.620272)
		(end 20.963382 -372.369588)
		(width 0.127)
		(layer "In5.Cu")
		(net "T12_BLAD3_RXD")
	)
	(segment
		(start 89.493344 -443.3189)
		(end 45.943774 -443.3189)
		(width 0.127)
		(layer "In5.Cu")
		(net "T12_BLAD3_RXD")
	)
	(segment
		(start 28.214066 -438.009284)
		(end 28.214066 -379.620272)
		(width 0.127)
		(layer "In5.Cu")
		(net "T12_BLAD3_RXD")
	)
	(segment
		(start 45.943774 -443.3189)
		(end 44.85894 -442.234066)
		(width 0.127)
		(layer "In5.Cu")
		(net "T12_BLAD3_RXD")
	)
	(segment
		(start 5.119878 -311.839864)
		(end 3.949954 -310.66994)
		(width 0.127)
		(layer "In5.Cu")
		(net "T12_BLAD3_RXD")
	)
	(segment
		(start 7.117588 -311.839864)
		(end 5.119878 -311.839864)
		(width 0.127)
		(layer "In5.Cu")
		(net "T12_BLAD3_RXD")
	)
	(segment
		(start 99.213924 -453.03948)
		(end 89.493344 -443.3189)
		(width 0.127)
		(layer "In5.Cu")
		(net "T12_BLAD3_RXD")
	)
	(segment
		(start 13.165328 -310.842914)
		(end 8.114538 -310.842914)
		(width 0.127)
		(layer "In5.Cu")
		(net "T12_BLAD3_RXD")
	)
	(segment
		(start 32.438848 -442.234066)
		(end 28.214066 -438.009284)
		(width 0.127)
		(layer "In5.Cu")
		(net "T12_BLAD3_RXD")
	)
	(segment
		(start 20.567396 -350.725994)
		(end 20.567396 -318.244982)
		(width 0.127)
		(layer "In5.Cu")
		(net "T12_BLAD3_RXD")
	)
	(segment
		(start 20.963382 -351.12198)
		(end 20.567396 -350.725994)
		(width 0.127)
		(layer "In5.Cu")
		(net "T12_BLAD3_RXD")
	)
	(segment
		(start 20.963382 -372.369588)
		(end 20.963382 -351.12198)
		(width 0.127)
		(layer "In5.Cu")
		(net "T12_BLAD3_RXD")
	)
	(segment
		(start 99.213924 -482.208586)
		(end 99.213924 -453.03948)
		(width 0.127)
		(layer "In5.Cu")
		(net "T12_BLAD3_RXD")
	)
	(segment
		(start 92.863924 -488.558586)
		(end 99.213924 -482.208586)
		(width 0.127)
		(layer "In5.Cu")
		(net "T12_BLAD3_RXD")
	)
	(segment
		(start 20.567396 -318.244982)
		(end 13.165328 -310.842914)
		(width 0.127)
		(layer "In5.Cu")
		(net "T12_BLAD3_RXD")
	)
	(via
		(at 91.012772 -487.85272)
		(size 0.508)
		(drill 0.254)
		(layers "F.Cu" "B.Cu")
		(net "T12_BLAD2_RXD")
	)
	(segment
		(start 7.121906 -313.902852)
		(end 2.182876 -313.902852)
		(width 0.127)
		(layer "In5.Cu")
		(net "T12_BLAD2_RXD")
	)
	(segment
		(start 2.182876 -313.902852)
		(end 1.949958 -313.669934)
		(width 0.127)
		(layer "In5.Cu")
		(net "T12_BLAD2_RXD")
	)
	(segment
		(start 45.217334 -444.035434)
		(end 44.127166 -442.945266)
		(width 0.127)
		(layer "In5.Cu")
		(net "T12_BLAD2_RXD")
	)
	(segment
		(start 89.171018 -444.035434)
		(end 45.217334 -444.035434)
		(width 0.127)
		(layer "In5.Cu")
		(net "T12_BLAD2_RXD")
	)
	(segment
		(start 91.98991 -496.49507)
		(end 91.98991 -497.849652)
		(width 0.127)
		(layer "In5.Cu")
		(net "T12_BLAD2_RXD")
	)
	(segment
		(start 98.518726 -453.383142)
		(end 89.171018 -444.035434)
		(width 0.127)
		(layer "In5.Cu")
		(net "T12_BLAD2_RXD")
	)
	(segment
		(start 31.827216 -442.945266)
		(end 27.453082 -438.571132)
		(width 0.127)
		(layer "In5.Cu")
		(net "T12_BLAD2_RXD")
	)
	(segment
		(start 98.518726 -481.907342)
		(end 98.518726 -453.383142)
		(width 0.127)
		(layer "In5.Cu")
		(net "T12_BLAD2_RXD")
	)
	(segment
		(start 12.339574 -312.871104)
		(end 8.153654 -312.871104)
		(width 0.127)
		(layer "In5.Cu")
		(net "T12_BLAD2_RXD")
	)
	(segment
		(start 92.366084 -486.499408)
		(end 93.92666 -486.499408)
		(width 0.127)
		(layer "In5.Cu")
		(net "T12_BLAD2_RXD")
	)
	(segment
		(start 44.127166 -442.945266)
		(end 31.827216 -442.945266)
		(width 0.127)
		(layer "In5.Cu")
		(net "T12_BLAD2_RXD")
	)
	(segment
		(start 84.290916 -494.574576)
		(end 91.012772 -487.85272)
		(width 0.127)
		(layer "In5.Cu")
		(net "T12_BLAD2_RXD")
	)
	(segment
		(start 84.290916 -498.140228)
		(end 84.290916 -494.574576)
		(width 0.127)
		(layer "In5.Cu")
		(net "T12_BLAD2_RXD")
	)
	(segment
		(start 19.906996 -320.438526)
		(end 12.339574 -312.871104)
		(width 0.127)
		(layer "In5.Cu")
		(net "T12_BLAD2_RXD")
	)
	(segment
		(start 91.012772 -487.85272)
		(end 92.366084 -486.499408)
		(width 0.127)
		(layer "In5.Cu")
		(net "T12_BLAD2_RXD")
	)
	(segment
		(start 8.153654 -312.871104)
		(end 7.121906 -313.902852)
		(width 0.127)
		(layer "In5.Cu")
		(net "T12_BLAD2_RXD")
	)
	(segment
		(start 20.228306 -351.321116)
		(end 19.906996 -350.999806)
		(width 0.127)
		(layer "In5.Cu")
		(net "T12_BLAD2_RXD")
	)
	(segment
		(start 93.92666 -486.499408)
		(end 98.518726 -481.907342)
		(width 0.127)
		(layer "In5.Cu")
		(net "T12_BLAD2_RXD")
	)
	(segment
		(start 27.453082 -380.18212)
		(end 20.228306 -372.957344)
		(width 0.127)
		(layer "In5.Cu")
		(net "T12_BLAD2_RXD")
	)
	(segment
		(start 91.98991 -497.849652)
		(end 90.631772 -499.20779)
		(width 0.127)
		(layer "In5.Cu")
		(net "T12_BLAD2_RXD")
	)
	(segment
		(start 85.358478 -499.20779)
		(end 84.290916 -498.140228)
		(width 0.127)
		(layer "In5.Cu")
		(net "T12_BLAD2_RXD")
	)
	(segment
		(start 27.453082 -438.571132)
		(end 27.453082 -380.18212)
		(width 0.127)
		(layer "In5.Cu")
		(net "T12_BLAD2_RXD")
	)
	(segment
		(start 90.631772 -499.20779)
		(end 85.358478 -499.20779)
		(width 0.127)
		(layer "In5.Cu")
		(net "T12_BLAD2_RXD")
	)
	(segment
		(start 20.228306 -372.957344)
		(end 20.228306 -351.321116)
		(width 0.127)
		(layer "In5.Cu")
		(net "T12_BLAD2_RXD")
	)
	(segment
		(start 19.906996 -350.999806)
		(end 19.906996 -320.438526)
		(width 0.127)
		(layer "In5.Cu")
		(net "T12_BLAD2_RXD")
	)
	(via
		(at 92.293694 -487.251502)
		(size 0.508)
		(drill 0.254)
		(layers "F.Cu" "B.Cu")
		(net "T12_BLAD2_TXD")
	)
	(segment
		(start 20.633182 -351.258886)
		(end 20.237196 -350.8629)
		(width 0.127)
		(layer "In5.Cu")
		(net "T12_BLAD2_TXD")
	)
	(segment
		(start 20.633182 -372.684548)
		(end 20.633182 -351.258886)
		(width 0.127)
		(layer "In5.Cu")
		(net "T12_BLAD2_TXD")
	)
	(segment
		(start 84.69884 -494.846356)
		(end 92.293694 -487.251502)
		(width 0.127)
		(layer "In5.Cu")
		(net "T12_BLAD2_TXD")
	)
	(segment
		(start 93.666818 -487.251502)
		(end 98.860356 -482.057964)
		(width 0.127)
		(layer "In5.Cu")
		(net "T12_BLAD2_TXD")
	)
	(segment
		(start 27.863546 -379.914912)
		(end 20.633182 -372.684548)
		(width 0.127)
		(layer "In5.Cu")
		(net "T12_BLAD2_TXD")
	)
	(segment
		(start 27.863546 -438.303924)
		(end 27.863546 -379.914912)
		(width 0.127)
		(layer "In5.Cu")
		(net "T12_BLAD2_TXD")
	)
	(segment
		(start 20.237196 -350.8629)
		(end 20.237196 -318.626744)
		(width 0.127)
		(layer "In5.Cu")
		(net "T12_BLAD2_TXD")
	)
	(segment
		(start 92.293694 -487.251502)
		(end 93.666818 -487.251502)
		(width 0.127)
		(layer "In5.Cu")
		(net "T12_BLAD2_TXD")
	)
	(segment
		(start 98.860356 -482.057964)
		(end 98.860356 -453.257666)
		(width 0.127)
		(layer "In5.Cu")
		(net "T12_BLAD2_TXD")
	)
	(segment
		(start 90.71991 -497.76507)
		(end 89.762584 -498.722396)
		(width 0.127)
		(layer "In5.Cu")
		(net "T12_BLAD2_TXD")
	)
	(segment
		(start 4.752848 -313.47283)
		(end 3.949954 -312.669936)
		(width 0.127)
		(layer "In5.Cu")
		(net "T12_BLAD2_TXD")
	)
	(segment
		(start 85.47481 -498.722396)
		(end 84.69884 -497.946426)
		(width 0.127)
		(layer "In5.Cu")
		(net "T12_BLAD2_TXD")
	)
	(segment
		(start 89.261188 -443.658498)
		(end 45.568108 -443.658498)
		(width 0.127)
		(layer "In5.Cu")
		(net "T12_BLAD2_TXD")
	)
	(segment
		(start 14.135354 -312.524902)
		(end 7.90956 -312.524902)
		(width 0.127)
		(layer "In5.Cu")
		(net "T12_BLAD2_TXD")
	)
	(segment
		(start 89.762584 -498.722396)
		(end 85.47481 -498.722396)
		(width 0.127)
		(layer "In5.Cu")
		(net "T12_BLAD2_TXD")
	)
	(segment
		(start 6.961632 -313.47283)
		(end 4.752848 -313.47283)
		(width 0.127)
		(layer "In5.Cu")
		(net "T12_BLAD2_TXD")
	)
	(segment
		(start 7.90956 -312.524902)
		(end 6.961632 -313.47283)
		(width 0.127)
		(layer "In5.Cu")
		(net "T12_BLAD2_TXD")
	)
	(segment
		(start 84.69884 -497.946426)
		(end 84.69884 -494.846356)
		(width 0.127)
		(layer "In5.Cu")
		(net "T12_BLAD2_TXD")
	)
	(segment
		(start 32.132016 -442.572394)
		(end 27.863546 -438.303924)
		(width 0.127)
		(layer "In5.Cu")
		(net "T12_BLAD2_TXD")
	)
	(segment
		(start 98.860356 -453.257666)
		(end 89.261188 -443.658498)
		(width 0.127)
		(layer "In5.Cu")
		(net "T12_BLAD2_TXD")
	)
	(segment
		(start 44.482004 -442.572394)
		(end 32.132016 -442.572394)
		(width 0.127)
		(layer "In5.Cu")
		(net "T12_BLAD2_TXD")
	)
	(segment
		(start 20.237196 -318.626744)
		(end 14.135354 -312.524902)
		(width 0.127)
		(layer "In5.Cu")
		(net "T12_BLAD2_TXD")
	)
	(segment
		(start 45.568108 -443.658498)
		(end 44.482004 -442.572394)
		(width 0.127)
		(layer "In5.Cu")
		(net "T12_BLAD2_TXD")
	)
	(via
		(at 95.19285 -487.487722)
		(size 0.508)
		(drill 0.254)
		(layers "F.Cu" "B.Cu")
		(net "T12_BLAD4_TXD")
	)
	(segment
		(start 99.916488 -452.573898)
		(end 89.905332 -442.562742)
		(width 0.127)
		(layer "In5.Cu")
		(net "T12_BLAD4_TXD")
	)
	(segment
		(start 99.916488 -482.764084)
		(end 99.916488 -452.573898)
		(width 0.127)
		(layer "In5.Cu")
		(net "T12_BLAD4_TXD")
	)
	(segment
		(start 90.71991 -491.960662)
		(end 90.71991 -495.22507)
		(width 0.127)
		(layer "In5.Cu")
		(net "T12_BLAD4_TXD")
	)
	(segment
		(start 43.741086 -439.382662)
		(end 30.814518 -439.382662)
		(width 0.127)
		(layer "In5.Cu")
		(net "T12_BLAD4_TXD")
	)
	(segment
		(start 21.623782 -371.826282)
		(end 21.623782 -350.848168)
		(width 0.127)
		(layer "In5.Cu")
		(net "T12_BLAD4_TXD")
	)
	(segment
		(start 30.814518 -439.382662)
		(end 28.932632 -437.500776)
		(width 0.127)
		(layer "In5.Cu")
		(net "T12_BLAD4_TXD")
	)
	(segment
		(start 28.932632 -379.135132)
		(end 21.623782 -371.826282)
		(width 0.127)
		(layer "In5.Cu")
		(net "T12_BLAD4_TXD")
	)
	(segment
		(start 7.239508 -308.882288)
		(end 6.702552 -309.419244)
		(width 0.127)
		(layer "In5.Cu")
		(net "T12_BLAD4_TXD")
	)
	(segment
		(start 13.461746 -308.882288)
		(end 7.239508 -308.882288)
		(width 0.127)
		(layer "In5.Cu")
		(net "T12_BLAD4_TXD")
	)
	(segment
		(start 3.699256 -309.419244)
		(end 1.949958 -307.669946)
		(width 0.127)
		(layer "In5.Cu")
		(net "T12_BLAD4_TXD")
	)
	(segment
		(start 6.702552 -309.419244)
		(end 3.699256 -309.419244)
		(width 0.127)
		(layer "In5.Cu")
		(net "T12_BLAD4_TXD")
	)
	(segment
		(start 95.19285 -487.487722)
		(end 99.916488 -482.764084)
		(width 0.127)
		(layer "In5.Cu")
		(net "T12_BLAD4_TXD")
	)
	(segment
		(start 21.623782 -350.848168)
		(end 21.227796 -350.452182)
		(width 0.127)
		(layer "In5.Cu")
		(net "T12_BLAD4_TXD")
	)
	(segment
		(start 21.227796 -316.648338)
		(end 13.461746 -308.882288)
		(width 0.127)
		(layer "In5.Cu")
		(net "T12_BLAD4_TXD")
	)
	(segment
		(start 46.921166 -442.562742)
		(end 43.741086 -439.382662)
		(width 0.127)
		(layer "In5.Cu")
		(net "T12_BLAD4_TXD")
	)
	(segment
		(start 21.227796 -350.452182)
		(end 21.227796 -316.648338)
		(width 0.127)
		(layer "In5.Cu")
		(net "T12_BLAD4_TXD")
	)
	(segment
		(start 95.19285 -487.487722)
		(end 90.71991 -491.960662)
		(width 0.127)
		(layer "In5.Cu")
		(net "T12_BLAD4_TXD")
	)
	(segment
		(start 89.905332 -442.562742)
		(end 46.921166 -442.562742)
		(width 0.127)
		(layer "In5.Cu")
		(net "T12_BLAD4_TXD")
	)
	(segment
		(start 28.932632 -437.500776)
		(end 28.932632 -379.135132)
		(width 0.127)
		(layer "In5.Cu")
		(net "T12_BLAD4_TXD")
	)
	(segment
		(start 28.738068 -108.226098)
		(end 29.011118 -108.226098)
		(width 0.508)
		(layer "F.Cu")
		(net "PSU2_REMOTE_N")
	)
	(segment
		(start 27.347672 -108.230416)
		(end 28.73375 -108.230416)
		(width 0.508)
		(layer "F.Cu")
		(net "PSU2_REMOTE_N")
	)
	(segment
		(start 29.011118 -108.226098)
		(end 29.014928 -108.229908)
		(width 0.508)
		(layer "F.Cu")
		(net "PSU2_REMOTE_N")
	)
	(segment
		(start 28.73375 -108.230416)
		(end 28.738068 -108.226098)
		(width 0.508)
		(layer "F.Cu")
		(net "PSU2_REMOTE_N")
	)
	(segment
		(start 29.014928 -108.229908)
		(end 30.45968 -108.229908)
		(width 0.508)
		(layer "F.Cu")
		(net "PSU2_REMOTE_N")
	)
	(via
		(at 84.807806 -14.229334)
		(size 0.508)
		(drill 0.254)
		(layers "F.Cu" "B.Cu")
		(net "T1_BLAD4_TXD")
	)
	(segment
		(start 74.964798 -60.130182)
		(end 80.733392 -54.361588)
		(width 0.127)
		(layer "In2.Cu")
		(net "T1_BLAD4_TXD")
	)
	(segment
		(start 84.560918 -15.706852)
		(end 84.807806 -15.459964)
		(width 0.127)
		(layer "In2.Cu")
		(net "T1_BLAD4_TXD")
	)
	(segment
		(start 84.560918 -48.829722)
		(end 84.560918 -15.706852)
		(width 0.127)
		(layer "In2.Cu")
		(net "T1_BLAD4_TXD")
	)
	(segment
		(start 84.807806 -5.754624)
		(end 86.357968 -4.204462)
		(width 0.127)
		(layer "In2.Cu")
		(net "T1_BLAD4_TXD")
	)
	(segment
		(start 6.448806 -219.984574)
		(end 7.977124 -221.512892)
		(width 0.127)
		(layer "In2.Cu")
		(net "T1_BLAD4_TXD")
	)
	(segment
		(start 90.71991 -5.082286)
		(end 90.71991 -6.27507)
		(width 0.127)
		(layer "In2.Cu")
		(net "T1_BLAD4_TXD")
	)
	(segment
		(start 22.865334 -92.239084)
		(end 28.399994 -86.704424)
		(width 0.127)
		(layer "In2.Cu")
		(net "T1_BLAD4_TXD")
	)
	(segment
		(start 24.783542 -107.56773)
		(end 24.783542 -105.338118)
		(width 0.127)
		(layer "In2.Cu")
		(net "T1_BLAD4_TXD")
	)
	(segment
		(start 80.733392 -54.361588)
		(end 82.051398 -54.361588)
		(width 0.127)
		(layer "In2.Cu")
		(net "T1_BLAD4_TXD")
	)
	(segment
		(start 24.783542 -105.338118)
		(end 22.865334 -103.41991)
		(width 0.127)
		(layer "In2.Cu")
		(net "T1_BLAD4_TXD")
	)
	(segment
		(start 24.525478 -168.383458)
		(end 24.525478 -107.825794)
		(width 0.127)
		(layer "In2.Cu")
		(net "T1_BLAD4_TXD")
	)
	(segment
		(start 22.865334 -103.41991)
		(end 22.865334 -92.239084)
		(width 0.127)
		(layer "In2.Cu")
		(net "T1_BLAD4_TXD")
	)
	(segment
		(start 6.448806 -219.67063)
		(end 6.448806 -219.984574)
		(width 0.127)
		(layer "In2.Cu")
		(net "T1_BLAD4_TXD")
	)
	(segment
		(start 84.807806 -14.229334)
		(end 84.807806 -5.754624)
		(width 0.127)
		(layer "In2.Cu")
		(net "T1_BLAD4_TXD")
	)
	(segment
		(start 52.48529 -86.704424)
		(end 74.964798 -64.224916)
		(width 0.127)
		(layer "In2.Cu")
		(net "T1_BLAD4_TXD")
	)
	(segment
		(start 89.842086 -4.204462)
		(end 90.71991 -5.082286)
		(width 0.127)
		(layer "In2.Cu")
		(net "T1_BLAD4_TXD")
	)
	(segment
		(start 83.508596 -49.882044)
		(end 84.560918 -48.829722)
		(width 0.127)
		(layer "In2.Cu")
		(net "T1_BLAD4_TXD")
	)
	(segment
		(start 7.977124 -221.512892)
		(end 8.793226 -221.512892)
		(width 0.127)
		(layer "In2.Cu")
		(net "T1_BLAD4_TXD")
	)
	(segment
		(start 84.807806 -15.459964)
		(end 84.807806 -14.229334)
		(width 0.127)
		(layer "In2.Cu")
		(net "T1_BLAD4_TXD")
	)
	(segment
		(start 8.793226 -221.512892)
		(end 9.490964 -220.815154)
		(width 0.127)
		(layer "In2.Cu")
		(net "T1_BLAD4_TXD")
	)
	(segment
		(start 82.051398 -54.361588)
		(end 83.508596 -52.90439)
		(width 0.127)
		(layer "In2.Cu")
		(net "T1_BLAD4_TXD")
	)
	(segment
		(start 15.959582 -176.949354)
		(end 24.525478 -168.383458)
		(width 0.127)
		(layer "In2.Cu")
		(net "T1_BLAD4_TXD")
	)
	(segment
		(start 83.508596 -52.90439)
		(end 83.508596 -49.882044)
		(width 0.127)
		(layer "In2.Cu")
		(net "T1_BLAD4_TXD")
	)
	(segment
		(start 28.399994 -86.704424)
		(end 52.48529 -86.704424)
		(width 0.127)
		(layer "In2.Cu")
		(net "T1_BLAD4_TXD")
	)
	(segment
		(start 9.490964 -203.839064)
		(end 15.959582 -197.370446)
		(width 0.127)
		(layer "In2.Cu")
		(net "T1_BLAD4_TXD")
	)
	(segment
		(start 86.357968 -4.204462)
		(end 89.842086 -4.204462)
		(width 0.127)
		(layer "In2.Cu")
		(net "T1_BLAD4_TXD")
	)
	(segment
		(start 15.959582 -197.370446)
		(end 15.959582 -176.949354)
		(width 0.127)
		(layer "In2.Cu")
		(net "T1_BLAD4_TXD")
	)
	(segment
		(start 9.490964 -220.815154)
		(end 9.490964 -203.839064)
		(width 0.127)
		(layer "In2.Cu")
		(net "T1_BLAD4_TXD")
	)
	(segment
		(start 24.525478 -107.825794)
		(end 24.783542 -107.56773)
		(width 0.127)
		(layer "In2.Cu")
		(net "T1_BLAD4_TXD")
	)
	(segment
		(start 74.964798 -64.224916)
		(end 74.964798 -60.130182)
		(width 0.127)
		(layer "In2.Cu")
		(net "T1_BLAD4_TXD")
	)
	(via
		(at 84.176362 -13.057886)
		(size 0.508)
		(drill 0.254)
		(layers "F.Cu" "B.Cu")
		(net "T1_BLAD4_RXD")
	)
	(segment
		(start 86.105746 -3.854958)
		(end 90.839798 -3.854958)
		(width 0.127)
		(layer "In2.Cu")
		(net "T1_BLAD4_RXD")
	)
	(segment
		(start 52.421282 -86.229444)
		(end 28.222956 -86.229444)
		(width 0.127)
		(layer "In2.Cu")
		(net "T1_BLAD4_RXD")
	)
	(segment
		(start 90.839798 -3.854958)
		(end 91.98991 -5.00507)
		(width 0.127)
		(layer "In2.Cu")
		(net "T1_BLAD4_RXD")
	)
	(segment
		(start 9.148826 -203.714096)
		(end 9.148826 -219.970604)
		(width 0.127)
		(layer "In2.Cu")
		(net "T1_BLAD4_RXD")
	)
	(segment
		(start 24.195278 -168.246298)
		(end 15.588234 -176.853342)
		(width 0.127)
		(layer "In2.Cu")
		(net "T1_BLAD4_RXD")
	)
	(segment
		(start 74.489818 -64.160908)
		(end 52.421282 -86.229444)
		(width 0.127)
		(layer "In2.Cu")
		(net "T1_BLAD4_RXD")
	)
	(segment
		(start 84.176362 -13.057886)
		(end 84.176362 -48.747172)
		(width 0.127)
		(layer "In2.Cu")
		(net "T1_BLAD4_RXD")
	)
	(segment
		(start 22.535134 -91.917266)
		(end 22.535134 -103.556816)
		(width 0.127)
		(layer "In2.Cu")
		(net "T1_BLAD4_RXD")
	)
	(segment
		(start 84.176362 -48.747172)
		(end 83.178396 -49.745138)
		(width 0.127)
		(layer "In2.Cu")
		(net "T1_BLAD4_RXD")
	)
	(segment
		(start 22.535134 -103.556816)
		(end 24.453342 -105.475024)
		(width 0.127)
		(layer "In2.Cu")
		(net "T1_BLAD4_RXD")
	)
	(segment
		(start 9.148826 -219.970604)
		(end 8.448802 -220.670628)
		(width 0.127)
		(layer "In2.Cu")
		(net "T1_BLAD4_RXD")
	)
	(segment
		(start 24.453342 -105.475024)
		(end 24.453342 -107.430824)
		(width 0.127)
		(layer "In2.Cu")
		(net "T1_BLAD4_RXD")
	)
	(segment
		(start 15.588234 -197.274688)
		(end 9.148826 -203.714096)
		(width 0.127)
		(layer "In2.Cu")
		(net "T1_BLAD4_RXD")
	)
	(segment
		(start 24.453342 -107.430824)
		(end 24.195278 -107.688888)
		(width 0.127)
		(layer "In2.Cu")
		(net "T1_BLAD4_RXD")
	)
	(segment
		(start 84.176362 -13.057886)
		(end 84.176362 -5.784342)
		(width 0.127)
		(layer "In2.Cu")
		(net "T1_BLAD4_RXD")
	)
	(segment
		(start 74.489818 -59.933332)
		(end 74.489818 -64.160908)
		(width 0.127)
		(layer "In2.Cu")
		(net "T1_BLAD4_RXD")
	)
	(segment
		(start 24.195278 -107.688888)
		(end 24.195278 -168.246298)
		(width 0.127)
		(layer "In2.Cu")
		(net "T1_BLAD4_RXD")
	)
	(segment
		(start 81.974182 -53.971444)
		(end 80.451706 -53.971444)
		(width 0.127)
		(layer "In2.Cu")
		(net "T1_BLAD4_RXD")
	)
	(segment
		(start 80.451706 -53.971444)
		(end 74.489818 -59.933332)
		(width 0.127)
		(layer "In2.Cu")
		(net "T1_BLAD4_RXD")
	)
	(segment
		(start 15.588234 -176.853342)
		(end 15.588234 -197.274688)
		(width 0.127)
		(layer "In2.Cu")
		(net "T1_BLAD4_RXD")
	)
	(segment
		(start 83.178396 -52.76723)
		(end 81.974182 -53.971444)
		(width 0.127)
		(layer "In2.Cu")
		(net "T1_BLAD4_RXD")
	)
	(segment
		(start 83.178396 -49.745138)
		(end 83.178396 -52.76723)
		(width 0.127)
		(layer "In2.Cu")
		(net "T1_BLAD4_RXD")
	)
	(segment
		(start 84.176362 -5.784342)
		(end 86.105746 -3.854958)
		(width 0.127)
		(layer "In2.Cu")
		(net "T1_BLAD4_RXD")
	)
	(segment
		(start 28.222956 -86.229444)
		(end 22.535134 -91.917266)
		(width 0.127)
		(layer "In2.Cu")
		(net "T1_BLAD4_RXD")
	)
	(segment
		(start 29.12999 -196.630036)
		(end 30.45968 -196.630036)
		(width 0.508)
		(layer "F.Cu")
		(net "PSU3_REMOTE_N")
	)
	(segment
		(start 27.329384 -196.622416)
		(end 29.12237 -196.622416)
		(width 0.508)
		(layer "F.Cu")
		(net "PSU3_REMOTE_N")
	)
	(segment
		(start 27.328368 -196.6214)
		(end 27.329384 -196.622416)
		(width 0.508)
		(layer "F.Cu")
		(net "PSU3_REMOTE_N")
	)
	(segment
		(start 29.12237 -196.622416)
		(end 29.12999 -196.630036)
		(width 0.508)
		(layer "F.Cu")
		(net "PSU3_REMOTE_N")
	)
	(segment
		(start 39.77894 -191.227202)
		(end 39.77894 -190.770002)
		(width 0.1524)
		(layer "F.Cu")
		(net "PSU3_RETURN")
	)
	(segment
		(start 39.5732 -192.216278)
		(end 39.5732 -191.432942)
		(width 0.1524)
		(layer "F.Cu")
		(net "PSU3_RETURN")
	)
	(segment
		(start 38.542214 -189.010036)
		(end 39.77894 -190.246762)
		(width 0.1524)
		(layer "F.Cu")
		(net "PSU3_RETURN")
	)
	(segment
		(start 39.5732 -191.432942)
		(end 39.77894 -191.227202)
		(width 0.1524)
		(layer "F.Cu")
		(net "PSU3_RETURN")
	)
	(segment
		(start 35.53968 -189.010036)
		(end 38.542214 -189.010036)
		(width 0.1524)
		(layer "F.Cu")
		(net "PSU3_RETURN")
	)
	(segment
		(start 39.77894 -190.246762)
		(end 39.77894 -190.770002)
		(width 0.1524)
		(layer "F.Cu")
		(net "PSU3_RETURN")
	)
	(via
		(at 39.77894 -190.770002)
		(size 0.508)
		(drill 0.254)
		(layers "F.Cu" "B.Cu")
		(net "PSU3_RETURN")
	)
	(via
		(at 86.454742 -13.101066)
		(size 0.508)
		(drill 0.254)
		(layers "F.Cu" "B.Cu")
		(net "T1_BLAD3_TXD")
	)
	(segment
		(start 52.480718 -87.19566)
		(end 28.603702 -87.19566)
		(width 0.127)
		(layer "In2.Cu")
		(net "T1_BLAD3_TXD")
	)
	(segment
		(start 86.454742 -14.29766)
		(end 84.891118 -15.861284)
		(width 0.127)
		(layer "In2.Cu")
		(net "T1_BLAD3_TXD")
	)
	(segment
		(start 28.603702 -87.19566)
		(end 23.195534 -92.603828)
		(width 0.127)
		(layer "In2.Cu")
		(net "T1_BLAD3_TXD")
	)
	(segment
		(start 24.855678 -107.9627)
		(end 24.855678 -172.077888)
		(width 0.127)
		(layer "In2.Cu")
		(net "T1_BLAD3_TXD")
	)
	(segment
		(start 75.456034 -64.220344)
		(end 52.480718 -87.19566)
		(width 0.127)
		(layer "In2.Cu")
		(net "T1_BLAD3_TXD")
	)
	(segment
		(start 86.454742 -13.101066)
		(end 86.454742 -14.29766)
		(width 0.127)
		(layer "In2.Cu")
		(net "T1_BLAD3_TXD")
	)
	(segment
		(start 25.113742 -107.704636)
		(end 24.855678 -107.9627)
		(width 0.127)
		(layer "In2.Cu")
		(net "T1_BLAD3_TXD")
	)
	(segment
		(start 25.113742 -105.201212)
		(end 25.113742 -107.704636)
		(width 0.127)
		(layer "In2.Cu")
		(net "T1_BLAD3_TXD")
	)
	(segment
		(start 9.833102 -203.964032)
		(end 9.833102 -221.286324)
		(width 0.127)
		(layer "In2.Cu")
		(net "T1_BLAD3_TXD")
	)
	(segment
		(start 23.195534 -92.603828)
		(end 23.195534 -103.283004)
		(width 0.127)
		(layer "In2.Cu")
		(net "T1_BLAD3_TXD")
	)
	(segment
		(start 24.855678 -172.077888)
		(end 16.316452 -180.617114)
		(width 0.127)
		(layer "In2.Cu")
		(net "T1_BLAD3_TXD")
	)
	(segment
		(start 82.214466 -54.859936)
		(end 80.929988 -54.859936)
		(width 0.127)
		(layer "In2.Cu")
		(net "T1_BLAD3_TXD")
	)
	(segment
		(start 86.454742 -8.46455)
		(end 86.454742 -13.101066)
		(width 0.127)
		(layer "In2.Cu")
		(net "T1_BLAD3_TXD")
	)
	(segment
		(start 9.833102 -221.286324)
		(end 8.448802 -222.670624)
		(width 0.127)
		(layer "In2.Cu")
		(net "T1_BLAD3_TXD")
	)
	(segment
		(start 16.316452 -180.617114)
		(end 16.316452 -197.480682)
		(width 0.127)
		(layer "In2.Cu")
		(net "T1_BLAD3_TXD")
	)
	(segment
		(start 83.838796 -53.235606)
		(end 82.214466 -54.859936)
		(width 0.127)
		(layer "In2.Cu")
		(net "T1_BLAD3_TXD")
	)
	(segment
		(start 85.63991 -6.27507)
		(end 85.63991 -7.649718)
		(width 0.127)
		(layer "In2.Cu")
		(net "T1_BLAD3_TXD")
	)
	(segment
		(start 84.891118 -15.861284)
		(end 84.891118 -48.966628)
		(width 0.127)
		(layer "In2.Cu")
		(net "T1_BLAD3_TXD")
	)
	(segment
		(start 23.195534 -103.283004)
		(end 25.113742 -105.201212)
		(width 0.127)
		(layer "In2.Cu")
		(net "T1_BLAD3_TXD")
	)
	(segment
		(start 80.929988 -54.859936)
		(end 75.456034 -60.33389)
		(width 0.127)
		(layer "In2.Cu")
		(net "T1_BLAD3_TXD")
	)
	(segment
		(start 84.891118 -48.966628)
		(end 83.838796 -50.01895)
		(width 0.127)
		(layer "In2.Cu")
		(net "T1_BLAD3_TXD")
	)
	(segment
		(start 75.456034 -60.33389)
		(end 75.456034 -64.220344)
		(width 0.127)
		(layer "In2.Cu")
		(net "T1_BLAD3_TXD")
	)
	(segment
		(start 85.63991 -7.649718)
		(end 86.454742 -8.46455)
		(width 0.127)
		(layer "In2.Cu")
		(net "T1_BLAD3_TXD")
	)
	(segment
		(start 83.838796 -50.01895)
		(end 83.838796 -53.235606)
		(width 0.127)
		(layer "In2.Cu")
		(net "T1_BLAD3_TXD")
	)
	(segment
		(start 16.316452 -197.480682)
		(end 9.833102 -203.964032)
		(width 0.127)
		(layer "In2.Cu")
		(net "T1_BLAD3_TXD")
	)
	(via
		(at 39.670482 -440.75096)
		(size 0.508)
		(drill 0.254)
		(layers "F.Cu" "B.Cu")
		(net "T11_BLAD3_RXD")
	)
	(segment
		(start 39.924228 -440.75096)
		(end 39.670482 -440.75096)
		(width 0.127)
		(layer "In2.Cu")
		(net "T11_BLAD3_RXD")
	)
	(segment
		(start 19.329654 -315.959744)
		(end 15.817088 -312.447178)
		(width 0.127)
		(layer "In2.Cu")
		(net "T11_BLAD3_RXD")
	)
	(segment
		(start 27.465274 -379.731016)
		(end 19.329654 -371.595396)
		(width 0.127)
		(layer "In2.Cu")
		(net "T11_BLAD3_RXD")
	)
	(segment
		(start 27.465274 -437.590946)
		(end 27.465274 -379.731016)
		(width 0.127)
		(layer "In2.Cu")
		(net "T11_BLAD3_RXD")
	)
	(segment
		(start 39.670482 -440.75096)
		(end 30.625288 -440.75096)
		(width 0.127)
		(layer "In2.Cu")
		(net "T11_BLAD3_RXD")
	)
	(segment
		(start 86.90991 -449.280026)
		(end 82.411062 -444.781178)
		(width 0.127)
		(layer "In2.Cu")
		(net "T11_BLAD3_RXD")
	)
	(segment
		(start 82.411062 -444.781178)
		(end 43.954446 -444.781178)
		(width 0.127)
		(layer "In2.Cu")
		(net "T11_BLAD3_RXD")
	)
	(segment
		(start 8.142986 -312.447178)
		(end 7.575296 -311.879488)
		(width 0.127)
		(layer "In2.Cu")
		(net "T11_BLAD3_RXD")
	)
	(segment
		(start 6.940296 -306.669948)
		(end 6.449822 -306.669948)
		(width 0.127)
		(layer "In2.Cu")
		(net "T11_BLAD3_RXD")
	)
	(segment
		(start 19.329654 -371.595396)
		(end 19.329654 -315.959744)
		(width 0.127)
		(layer "In2.Cu")
		(net "T11_BLAD3_RXD")
	)
	(segment
		(start 30.625288 -440.75096)
		(end 27.465274 -437.590946)
		(width 0.127)
		(layer "In2.Cu")
		(net "T11_BLAD3_RXD")
	)
	(segment
		(start 43.954446 -444.781178)
		(end 39.924228 -440.75096)
		(width 0.127)
		(layer "In2.Cu")
		(net "T11_BLAD3_RXD")
	)
	(segment
		(start 86.90991 -449.50507)
		(end 86.90991 -449.280026)
		(width 0.127)
		(layer "In2.Cu")
		(net "T11_BLAD3_RXD")
	)
	(segment
		(start 7.575296 -311.879488)
		(end 7.575296 -307.304948)
		(width 0.127)
		(layer "In2.Cu")
		(net "T11_BLAD3_RXD")
	)
	(segment
		(start 7.575296 -307.304948)
		(end 6.940296 -306.669948)
		(width 0.127)
		(layer "In2.Cu")
		(net "T11_BLAD3_RXD")
	)
	(segment
		(start 15.817088 -312.447178)
		(end 8.142986 -312.447178)
		(width 0.127)
		(layer "In2.Cu")
		(net "T11_BLAD3_RXD")
	)
	(via
		(at 85.909658 -15.635986)
		(size 0.508)
		(drill 0.254)
		(layers "F.Cu" "B.Cu")
		(net "T1_BLAD3_RXD")
	)
	(segment
		(start 23.525734 -93.177106)
		(end 23.525734 -102.945692)
		(width 0.127)
		(layer "In2.Cu")
		(net "T1_BLAD3_RXD")
	)
	(segment
		(start 85.221318 -49.103534)
		(end 84.168996 -50.155856)
		(width 0.127)
		(layer "In2.Cu")
		(net "T1_BLAD3_RXD")
	)
	(segment
		(start 8.958834 -223.543114)
		(end 6.576314 -223.543114)
		(width 0.127)
		(layer "In2.Cu")
		(net "T1_BLAD3_RXD")
	)
	(segment
		(start 81.116678 -55.221886)
		(end 75.843892 -60.494672)
		(width 0.127)
		(layer "In2.Cu")
		(net "T1_BLAD3_RXD")
	)
	(segment
		(start 87.80399 -8.018526)
		(end 87.053674 -8.768842)
		(width 0.127)
		(layer "In2.Cu")
		(net "T1_BLAD3_RXD")
	)
	(segment
		(start 25.200864 -108.101638)
		(end 25.200864 -172.199808)
		(width 0.127)
		(layer "In2.Cu")
		(net "T1_BLAD3_RXD")
	)
	(segment
		(start 87.053674 -14.49197)
		(end 85.909658 -15.635986)
		(width 0.127)
		(layer "In2.Cu")
		(net "T1_BLAD3_RXD")
	)
	(segment
		(start 84.168996 -50.155856)
		(end 84.168996 -53.585618)
		(width 0.127)
		(layer "In2.Cu")
		(net "T1_BLAD3_RXD")
	)
	(segment
		(start 84.168996 -53.585618)
		(end 82.532728 -55.221886)
		(width 0.127)
		(layer "In2.Cu")
		(net "T1_BLAD3_RXD")
	)
	(segment
		(start 87.053674 -8.768842)
		(end 87.053674 -14.49197)
		(width 0.127)
		(layer "In2.Cu")
		(net "T1_BLAD3_RXD")
	)
	(segment
		(start 23.525734 -102.945692)
		(end 25.443942 -104.8639)
		(width 0.127)
		(layer "In2.Cu")
		(net "T1_BLAD3_RXD")
	)
	(segment
		(start 6.576314 -223.543114)
		(end 6.448806 -223.670622)
		(width 0.127)
		(layer "In2.Cu")
		(net "T1_BLAD3_RXD")
	)
	(segment
		(start 75.843892 -64.381126)
		(end 52.6415 -87.583518)
		(width 0.127)
		(layer "In2.Cu")
		(net "T1_BLAD3_RXD")
	)
	(segment
		(start 16.709136 -197.555358)
		(end 10.18667 -204.077824)
		(width 0.127)
		(layer "In2.Cu")
		(net "T1_BLAD3_RXD")
	)
	(segment
		(start 10.18667 -204.077824)
		(end 10.18667 -222.315278)
		(width 0.127)
		(layer "In2.Cu")
		(net "T1_BLAD3_RXD")
	)
	(segment
		(start 52.6415 -87.583518)
		(end 29.119322 -87.583518)
		(width 0.127)
		(layer "In2.Cu")
		(net "T1_BLAD3_RXD")
	)
	(segment
		(start 82.532728 -55.221886)
		(end 81.116678 -55.221886)
		(width 0.127)
		(layer "In2.Cu")
		(net "T1_BLAD3_RXD")
	)
	(segment
		(start 86.90991 -5.00507)
		(end 86.90991 -6.35762)
		(width 0.127)
		(layer "In2.Cu")
		(net "T1_BLAD3_RXD")
	)
	(segment
		(start 75.843892 -60.494672)
		(end 75.843892 -64.381126)
		(width 0.127)
		(layer "In2.Cu")
		(net "T1_BLAD3_RXD")
	)
	(segment
		(start 25.443942 -104.8639)
		(end 25.443942 -107.85856)
		(width 0.127)
		(layer "In2.Cu")
		(net "T1_BLAD3_RXD")
	)
	(segment
		(start 25.200864 -172.199808)
		(end 16.709136 -180.691536)
		(width 0.127)
		(layer "In2.Cu")
		(net "T1_BLAD3_RXD")
	)
	(segment
		(start 86.90991 -6.35762)
		(end 87.80399 -7.2517)
		(width 0.127)
		(layer "In2.Cu")
		(net "T1_BLAD3_RXD")
	)
	(segment
		(start 87.80399 -7.2517)
		(end 87.80399 -8.018526)
		(width 0.127)
		(layer "In2.Cu")
		(net "T1_BLAD3_RXD")
	)
	(segment
		(start 29.119322 -87.583518)
		(end 23.525734 -93.177106)
		(width 0.127)
		(layer "In2.Cu")
		(net "T1_BLAD3_RXD")
	)
	(segment
		(start 85.221318 -16.324326)
		(end 85.221318 -49.103534)
		(width 0.127)
		(layer "In2.Cu")
		(net "T1_BLAD3_RXD")
	)
	(segment
		(start 25.443942 -107.85856)
		(end 25.200864 -108.101638)
		(width 0.127)
		(layer "In2.Cu")
		(net "T1_BLAD3_RXD")
	)
	(segment
		(start 10.18667 -222.315278)
		(end 8.958834 -223.543114)
		(width 0.127)
		(layer "In2.Cu")
		(net "T1_BLAD3_RXD")
	)
	(segment
		(start 16.709136 -180.691536)
		(end 16.709136 -197.555358)
		(width 0.127)
		(layer "In2.Cu")
		(net "T1_BLAD3_RXD")
	)
	(segment
		(start 85.909658 -15.635986)
		(end 85.221318 -16.324326)
		(width 0.127)
		(layer "In2.Cu")
		(net "T1_BLAD3_RXD")
	)
	(via
		(at 42.108628 -440.157362)
		(size 0.508)
		(drill 0.254)
		(layers "F.Cu" "B.Cu")
		(net "T11_BLAD4_RXD")
	)
	(segment
		(start 30.943042 -439.570368)
		(end 41.521888 -439.570368)
		(width 0.127)
		(layer "In2.Cu")
		(net "T11_BLAD4_RXD")
	)
	(segment
		(start 28.595828 -437.223154)
		(end 30.943042 -439.570368)
		(width 0.127)
		(layer "In2.Cu")
		(net "T11_BLAD4_RXD")
	)
	(segment
		(start 86.130384 -443.645544)
		(end 91.98991 -449.50507)
		(width 0.127)
		(layer "In2.Cu")
		(net "T11_BLAD4_RXD")
	)
	(segment
		(start 11.285728 -304.669952)
		(end 20.320254 -313.704478)
		(width 0.127)
		(layer "In2.Cu")
		(net "T11_BLAD4_RXD")
	)
	(segment
		(start 42.108628 -440.157108)
		(end 45.597064 -443.645544)
		(width 0.127)
		(layer "In2.Cu")
		(net "T11_BLAD4_RXD")
	)
	(segment
		(start 45.597064 -443.645544)
		(end 86.130384 -443.645544)
		(width 0.127)
		(layer "In2.Cu")
		(net "T11_BLAD4_RXD")
	)
	(segment
		(start 41.521888 -439.570368)
		(end 42.108628 -440.157108)
		(width 0.127)
		(layer "In2.Cu")
		(net "T11_BLAD4_RXD")
	)
	(segment
		(start 20.320254 -371.070378)
		(end 28.595828 -379.345952)
		(width 0.127)
		(layer "In2.Cu")
		(net "T11_BLAD4_RXD")
	)
	(segment
		(start 42.108628 -440.157108)
		(end 42.108628 -440.157362)
		(width 0.127)
		(layer "In2.Cu")
		(net "T11_BLAD4_RXD")
	)
	(segment
		(start 28.595828 -379.345952)
		(end 28.595828 -437.223154)
		(width 0.127)
		(layer "In2.Cu")
		(net "T11_BLAD4_RXD")
	)
	(segment
		(start 20.320254 -313.704478)
		(end 20.320254 -371.070378)
		(width 0.127)
		(layer "In2.Cu")
		(net "T11_BLAD4_RXD")
	)
	(segment
		(start 6.449822 -304.669952)
		(end 11.285728 -304.669952)
		(width 0.127)
		(layer "In2.Cu")
		(net "T11_BLAD4_RXD")
	)
	(via
		(at 42.710354 -441.758832)
		(size 0.508)
		(drill 0.254)
		(layers "F.Cu" "B.Cu")
		(net "T11_BLAD2_RXD")
	)
	(segment
		(start 88.342216 -449.579492)
		(end 88.342216 -448.819016)
		(width 0.127)
		(layer "In2.Cu")
		(net "T11_BLAD2_RXD")
	)
	(segment
		(start 90.807794 -452.04507)
		(end 88.342216 -449.579492)
		(width 0.127)
		(layer "In2.Cu")
		(net "T11_BLAD2_RXD")
	)
	(segment
		(start 83.506818 -443.983618)
		(end 44.93514 -443.983618)
		(width 0.127)
		(layer "In2.Cu")
		(net "T11_BLAD2_RXD")
	)
	(segment
		(start 19.990054 -314.160662)
		(end 19.990054 -371.229382)
		(width 0.127)
		(layer "In2.Cu")
		(net "T11_BLAD2_RXD")
	)
	(segment
		(start 88.342216 -448.819016)
		(end 83.506818 -443.983618)
		(width 0.127)
		(layer "In2.Cu")
		(net "T11_BLAD2_RXD")
	)
	(segment
		(start 40.921686 -439.970164)
		(end 42.710354 -441.758832)
		(width 0.127)
		(layer "In2.Cu")
		(net "T11_BLAD2_RXD")
	)
	(segment
		(start 91.98991 -452.04507)
		(end 90.807794 -452.04507)
		(width 0.127)
		(layer "In2.Cu")
		(net "T11_BLAD2_RXD")
	)
	(segment
		(start 15.499334 -309.669942)
		(end 19.990054 -314.160662)
		(width 0.127)
		(layer "In2.Cu")
		(net "T11_BLAD2_RXD")
	)
	(segment
		(start 28.222194 -437.332628)
		(end 30.85973 -439.970164)
		(width 0.127)
		(layer "In2.Cu")
		(net "T11_BLAD2_RXD")
	)
	(segment
		(start 28.222194 -379.461522)
		(end 28.222194 -437.332628)
		(width 0.127)
		(layer "In2.Cu")
		(net "T11_BLAD2_RXD")
	)
	(segment
		(start 19.990054 -371.229382)
		(end 28.222194 -379.461522)
		(width 0.127)
		(layer "In2.Cu")
		(net "T11_BLAD2_RXD")
	)
	(segment
		(start 44.93514 -443.983618)
		(end 42.710354 -441.758832)
		(width 0.127)
		(layer "In2.Cu")
		(net "T11_BLAD2_RXD")
	)
	(segment
		(start 30.85973 -439.970164)
		(end 40.921686 -439.970164)
		(width 0.127)
		(layer "In2.Cu")
		(net "T11_BLAD2_RXD")
	)
	(segment
		(start 8.449818 -309.669942)
		(end 15.499334 -309.669942)
		(width 0.127)
		(layer "In2.Cu")
		(net "T11_BLAD2_RXD")
	)
	(segment
		(start 4.760214 -252.481842)
		(end 7.18312 -252.481842)
		(width 0.1524)
		(layer "F.Cu")
		(net "I2C_PSU2_SDA")
	)
	(segment
		(start 3.948938 -251.670566)
		(end 4.760214 -252.481842)
		(width 0.1524)
		(layer "F.Cu")
		(net "I2C_PSU2_SDA")
	)
	(segment
		(start 7.769606 -251.895356)
		(end 24.735536 -251.895356)
		(width 0.1524)
		(layer "F.Cu")
		(net "I2C_PSU2_SDA")
	)
	(segment
		(start 24.735536 -251.895356)
		(end 24.927306 -251.703586)
		(width 0.1524)
		(layer "F.Cu")
		(net "I2C_PSU2_SDA")
	)
	(segment
		(start 7.18312 -252.481842)
		(end 7.769606 -251.895356)
		(width 0.1524)
		(layer "F.Cu")
		(net "I2C_PSU2_SDA")
	)
	(via
		(at 24.927306 -251.703586)
		(size 0.508)
		(drill 0.254)
		(layers "F.Cu" "B.Cu")
		(net "I2C_PSU2_SDA")
	)
	(segment
		(start 24.239982 -204.457046)
		(end 24.239982 -251.016262)
		(width 0.1524)
		(layer "B.Cu")
		(net "I2C_PSU2_SDA")
	)
	(segment
		(start 33.576768 -198.414386)
		(end 31.805118 -200.186036)
		(width 0.1524)
		(layer "B.Cu")
		(net "I2C_PSU2_SDA")
	)
	(segment
		(start 35.53968 -181.390036)
		(end 33.576768 -183.352948)
		(width 0.1524)
		(layer "B.Cu")
		(net "I2C_PSU2_SDA")
	)
	(segment
		(start 28.510992 -200.186036)
		(end 24.239982 -204.457046)
		(width 0.1524)
		(layer "B.Cu")
		(net "I2C_PSU2_SDA")
	)
	(segment
		(start 24.927306 -251.703586)
		(end 24.927306 -259.177536)
		(width 0.1524)
		(layer "B.Cu")
		(net "I2C_PSU2_SDA")
	)
	(segment
		(start 24.239982 -251.016262)
		(end 24.927306 -251.703586)
		(width 0.1524)
		(layer "B.Cu")
		(net "I2C_PSU2_SDA")
	)
	(segment
		(start 33.576768 -183.352948)
		(end 33.576768 -198.414386)
		(width 0.1524)
		(layer "B.Cu")
		(net "I2C_PSU2_SDA")
	)
	(segment
		(start 31.805118 -200.186036)
		(end 28.510992 -200.186036)
		(width 0.1524)
		(layer "B.Cu")
		(net "I2C_PSU2_SDA")
	)
	(segment
		(start 24.927306 -259.177536)
		(end 35.53968 -269.78991)
		(width 0.1524)
		(layer "B.Cu")
		(net "I2C_PSU2_SDA")
	)
	(via
		(at 87.652606 -14.27226)
		(size 0.508)
		(drill 0.254)
		(layers "F.Cu" "B.Cu")
		(net "T1_BLAD2_RXD")
	)
	(segment
		(start 17.094454 -197.637146)
		(end 17.094454 -180.773324)
		(width 0.127)
		(layer "In2.Cu")
		(net "T1_BLAD2_RXD")
	)
	(segment
		(start 17.094454 -180.773324)
		(end 25.608026 -172.259752)
		(width 0.127)
		(layer "In2.Cu")
		(net "T1_BLAD2_RXD")
	)
	(segment
		(start 52.81422 -88.000078)
		(end 76.260452 -64.553846)
		(width 0.127)
		(layer "In2.Cu")
		(net "T1_BLAD2_RXD")
	)
	(segment
		(start 81.355946 -55.571898)
		(end 82.800698 -55.571898)
		(width 0.127)
		(layer "In2.Cu")
		(net "T1_BLAD2_RXD")
	)
	(segment
		(start 90.772234 -7.54507)
		(end 87.652606 -10.664698)
		(width 0.127)
		(layer "In2.Cu")
		(net "T1_BLAD2_RXD")
	)
	(segment
		(start 84.499196 -53.8734)
		(end 84.499196 -50.292762)
		(width 0.127)
		(layer "In2.Cu")
		(net "T1_BLAD2_RXD")
	)
	(segment
		(start 25.774142 -104.5591)
		(end 23.898352 -102.68331)
		(width 0.127)
		(layer "In2.Cu")
		(net "T1_BLAD2_RXD")
	)
	(segment
		(start 25.608026 -109.211872)
		(end 26.34996 -108.469938)
		(width 0.127)
		(layer "In2.Cu")
		(net "T1_BLAD2_RXD")
	)
	(segment
		(start 85.551518 -49.24044)
		(end 85.551518 -16.840708)
		(width 0.127)
		(layer "In2.Cu")
		(net "T1_BLAD2_RXD")
	)
	(segment
		(start 87.652606 -10.664698)
		(end 87.652606 -14.27226)
		(width 0.127)
		(layer "In2.Cu")
		(net "T1_BLAD2_RXD")
	)
	(segment
		(start 26.34996 -107.94238)
		(end 25.774142 -107.366562)
		(width 0.127)
		(layer "In2.Cu")
		(net "T1_BLAD2_RXD")
	)
	(segment
		(start 23.898352 -102.68331)
		(end 23.898352 -93.481398)
		(width 0.127)
		(layer "In2.Cu")
		(net "T1_BLAD2_RXD")
	)
	(segment
		(start 25.774142 -107.366562)
		(end 25.774142 -104.5591)
		(width 0.127)
		(layer "In2.Cu")
		(net "T1_BLAD2_RXD")
	)
	(segment
		(start 25.608026 -172.259752)
		(end 25.608026 -109.211872)
		(width 0.127)
		(layer "In2.Cu")
		(net "T1_BLAD2_RXD")
	)
	(segment
		(start 85.551518 -16.840708)
		(end 87.652606 -14.73962)
		(width 0.127)
		(layer "In2.Cu")
		(net "T1_BLAD2_RXD")
	)
	(segment
		(start 29.379672 -88.000078)
		(end 52.81422 -88.000078)
		(width 0.127)
		(layer "In2.Cu")
		(net "T1_BLAD2_RXD")
	)
	(segment
		(start 9.133586 -223.902524)
		(end 10.529062 -222.507048)
		(width 0.127)
		(layer "In2.Cu")
		(net "T1_BLAD2_RXD")
	)
	(segment
		(start 26.34996 -108.469938)
		(end 26.34996 -107.94238)
		(width 0.127)
		(layer "In2.Cu")
		(net "T1_BLAD2_RXD")
	)
	(segment
		(start 76.260452 -60.667392)
		(end 81.355946 -55.571898)
		(width 0.127)
		(layer "In2.Cu")
		(net "T1_BLAD2_RXD")
	)
	(segment
		(start 6.448806 -225.670618)
		(end 8.2169 -223.902524)
		(width 0.127)
		(layer "In2.Cu")
		(net "T1_BLAD2_RXD")
	)
	(segment
		(start 87.652606 -14.73962)
		(end 87.652606 -14.27226)
		(width 0.127)
		(layer "In2.Cu")
		(net "T1_BLAD2_RXD")
	)
	(segment
		(start 91.98991 -7.54507)
		(end 90.772234 -7.54507)
		(width 0.127)
		(layer "In2.Cu")
		(net "T1_BLAD2_RXD")
	)
	(segment
		(start 10.529062 -222.507048)
		(end 10.529062 -204.202538)
		(width 0.127)
		(layer "In2.Cu")
		(net "T1_BLAD2_RXD")
	)
	(segment
		(start 82.800698 -55.571898)
		(end 84.499196 -53.8734)
		(width 0.127)
		(layer "In2.Cu")
		(net "T1_BLAD2_RXD")
	)
	(segment
		(start 84.499196 -50.292762)
		(end 85.551518 -49.24044)
		(width 0.127)
		(layer "In2.Cu")
		(net "T1_BLAD2_RXD")
	)
	(segment
		(start 10.529062 -204.202538)
		(end 17.094454 -197.637146)
		(width 0.127)
		(layer "In2.Cu")
		(net "T1_BLAD2_RXD")
	)
	(segment
		(start 23.898352 -93.481398)
		(end 29.379672 -88.000078)
		(width 0.127)
		(layer "In2.Cu")
		(net "T1_BLAD2_RXD")
	)
	(segment
		(start 8.2169 -223.902524)
		(end 9.133586 -223.902524)
		(width 0.127)
		(layer "In2.Cu")
		(net "T1_BLAD2_RXD")
	)
	(segment
		(start 76.260452 -64.553846)
		(end 76.260452 -60.667392)
		(width 0.127)
		(layer "In2.Cu")
		(net "T1_BLAD2_RXD")
	)
	(segment
		(start 39.090854 -370.890038)
		(end 39.71417 -371.513354)
		(width 0.1524)
		(layer "F.Cu")
		(net "PSU5_AD0")
	)
	(segment
		(start 35.53968 -370.890038)
		(end 39.090854 -370.890038)
		(width 0.1524)
		(layer "F.Cu")
		(net "PSU5_AD0")
	)
	(via
		(at 38.178486 -441.200286)
		(size 0.508)
		(drill 0.254)
		(layers "F.Cu" "B.Cu")
		(net "T11_BLAD3_TXD")
	)
	(segment
		(start 6.631178 -307.560218)
		(end 7.167118 -308.096158)
		(width 0.127)
		(layer "In2.Cu")
		(net "T11_BLAD3_TXD")
	)
	(segment
		(start 15.560802 -312.88101)
		(end 18.999454 -316.319662)
		(width 0.127)
		(layer "In2.Cu")
		(net "T11_BLAD3_TXD")
	)
	(segment
		(start 6.171946 -307.560218)
		(end 6.631178 -307.560218)
		(width 0.127)
		(layer "In2.Cu")
		(net "T11_BLAD3_TXD")
	)
	(segment
		(start 27.090116 -379.903228)
		(end 27.090116 -437.733186)
		(width 0.127)
		(layer "In2.Cu")
		(net "T11_BLAD3_TXD")
	)
	(segment
		(start 44.018962 -445.472312)
		(end 39.746936 -441.200286)
		(width 0.127)
		(layer "In2.Cu")
		(net "T11_BLAD3_TXD")
	)
	(segment
		(start 85.63991 -449.446396)
		(end 81.665826 -445.472312)
		(width 0.127)
		(layer "In2.Cu")
		(net "T11_BLAD3_TXD")
	)
	(segment
		(start 7.989824 -312.88101)
		(end 15.560802 -312.88101)
		(width 0.127)
		(layer "In2.Cu")
		(net "T11_BLAD3_TXD")
	)
	(segment
		(start 30.557216 -441.200286)
		(end 38.178486 -441.200286)
		(width 0.127)
		(layer "In2.Cu")
		(net "T11_BLAD3_TXD")
	)
	(segment
		(start 5.508244 -306.896516)
		(end 6.171946 -307.560218)
		(width 0.127)
		(layer "In2.Cu")
		(net "T11_BLAD3_TXD")
	)
	(segment
		(start 39.746936 -441.200286)
		(end 38.178486 -441.200286)
		(width 0.127)
		(layer "In2.Cu")
		(net "T11_BLAD3_TXD")
	)
	(segment
		(start 8.449818 -305.66995)
		(end 6.071616 -305.66995)
		(width 0.127)
		(layer "In2.Cu")
		(net "T11_BLAD3_TXD")
	)
	(segment
		(start 81.665826 -445.472312)
		(end 44.018962 -445.472312)
		(width 0.127)
		(layer "In2.Cu")
		(net "T11_BLAD3_TXD")
	)
	(segment
		(start 7.167118 -308.096158)
		(end 7.167118 -312.058304)
		(width 0.127)
		(layer "In2.Cu")
		(net "T11_BLAD3_TXD")
	)
	(segment
		(start 27.090116 -437.733186)
		(end 30.557216 -441.200286)
		(width 0.127)
		(layer "In2.Cu")
		(net "T11_BLAD3_TXD")
	)
	(segment
		(start 18.999454 -371.812566)
		(end 27.090116 -379.903228)
		(width 0.127)
		(layer "In2.Cu")
		(net "T11_BLAD3_TXD")
	)
	(segment
		(start 85.63991 -450.77507)
		(end 85.63991 -449.446396)
		(width 0.127)
		(layer "In2.Cu")
		(net "T11_BLAD3_TXD")
	)
	(segment
		(start 6.071616 -305.66995)
		(end 5.508244 -306.233322)
		(width 0.127)
		(layer "In2.Cu")
		(net "T11_BLAD3_TXD")
	)
	(segment
		(start 7.167118 -312.058304)
		(end 7.989824 -312.88101)
		(width 0.127)
		(layer "In2.Cu")
		(net "T11_BLAD3_TXD")
	)
	(segment
		(start 18.999454 -316.319662)
		(end 18.999454 -371.812566)
		(width 0.127)
		(layer "In2.Cu")
		(net "T11_BLAD3_TXD")
	)
	(segment
		(start 5.508244 -306.233322)
		(end 5.508244 -306.896516)
		(width 0.127)
		(layer "In2.Cu")
		(net "T11_BLAD3_TXD")
	)
	(via
		(at 88.465406 -12.919202)
		(size 0.508)
		(drill 0.254)
		(layers "F.Cu" "B.Cu")
		(net "T1_BLAD2_TXD")
	)
	(segment
		(start 26.104342 -107.229656)
		(end 26.68016 -107.805474)
		(width 0.127)
		(layer "In2.Cu")
		(net "T1_BLAD2_TXD")
	)
	(segment
		(start 82.907632 -55.93207)
		(end 81.609184 -55.93207)
		(width 0.127)
		(layer "In2.Cu")
		(net "T1_BLAD2_TXD")
	)
	(segment
		(start 17.528032 -197.670928)
		(end 10.85977 -204.33919)
		(width 0.127)
		(layer "In2.Cu")
		(net "T1_BLAD2_TXD")
	)
	(segment
		(start 17.528032 -180.806852)
		(end 17.528032 -197.670928)
		(width 0.127)
		(layer "In2.Cu")
		(net "T1_BLAD2_TXD")
	)
	(segment
		(start 88.465406 -11.069574)
		(end 90.71991 -8.81507)
		(width 0.127)
		(layer "In2.Cu")
		(net "T1_BLAD2_TXD")
	)
	(segment
		(start 85.881718 -17.049496)
		(end 85.881718 -49.377346)
		(width 0.127)
		(layer "In2.Cu")
		(net "T1_BLAD2_TXD")
	)
	(segment
		(start 26.104342 -104.422194)
		(end 26.104342 -107.229656)
		(width 0.127)
		(layer "In2.Cu")
		(net "T1_BLAD2_TXD")
	)
	(segment
		(start 8.928862 -224.67062)
		(end 8.448802 -224.67062)
		(width 0.127)
		(layer "In2.Cu")
		(net "T1_BLAD2_TXD")
	)
	(segment
		(start 84.829396 -54.010306)
		(end 82.907632 -55.93207)
		(width 0.127)
		(layer "In2.Cu")
		(net "T1_BLAD2_TXD")
	)
	(segment
		(start 24.273002 -102.590854)
		(end 26.104342 -104.422194)
		(width 0.127)
		(layer "In2.Cu")
		(net "T1_BLAD2_TXD")
	)
	(segment
		(start 10.85977 -222.739712)
		(end 8.928862 -224.67062)
		(width 0.127)
		(layer "In2.Cu")
		(net "T1_BLAD2_TXD")
	)
	(segment
		(start 76.69403 -64.733678)
		(end 52.994052 -88.433656)
		(width 0.127)
		(layer "In2.Cu")
		(net "T1_BLAD2_TXD")
	)
	(segment
		(start 52.994052 -88.433656)
		(end 29.559504 -88.433656)
		(width 0.127)
		(layer "In2.Cu")
		(net "T1_BLAD2_TXD")
	)
	(segment
		(start 88.465406 -14.465808)
		(end 85.881718 -17.049496)
		(width 0.127)
		(layer "In2.Cu")
		(net "T1_BLAD2_TXD")
	)
	(segment
		(start 76.69403 -60.847224)
		(end 76.69403 -64.733678)
		(width 0.127)
		(layer "In2.Cu")
		(net "T1_BLAD2_TXD")
	)
	(segment
		(start 24.273002 -93.720158)
		(end 24.273002 -102.590854)
		(width 0.127)
		(layer "In2.Cu")
		(net "T1_BLAD2_TXD")
	)
	(segment
		(start 84.829396 -50.429668)
		(end 84.829396 -54.010306)
		(width 0.127)
		(layer "In2.Cu")
		(net "T1_BLAD2_TXD")
	)
	(segment
		(start 26.59634 -171.738544)
		(end 17.528032 -180.806852)
		(width 0.127)
		(layer "In2.Cu")
		(net "T1_BLAD2_TXD")
	)
	(segment
		(start 88.465406 -12.919202)
		(end 88.465406 -11.069574)
		(width 0.127)
		(layer "In2.Cu")
		(net "T1_BLAD2_TXD")
	)
	(segment
		(start 26.59634 -169.941494)
		(end 26.59634 -171.738544)
		(width 0.127)
		(layer "In2.Cu")
		(net "T1_BLAD2_TXD")
	)
	(segment
		(start 88.465406 -12.919202)
		(end 88.465406 -14.465808)
		(width 0.127)
		(layer "In2.Cu")
		(net "T1_BLAD2_TXD")
	)
	(segment
		(start 25.961594 -109.346238)
		(end 25.961594 -169.306748)
		(width 0.127)
		(layer "In2.Cu")
		(net "T1_BLAD2_TXD")
	)
	(segment
		(start 29.559504 -88.433656)
		(end 24.273002 -93.720158)
		(width 0.127)
		(layer "In2.Cu")
		(net "T1_BLAD2_TXD")
	)
	(segment
		(start 10.85977 -204.33919)
		(end 10.85977 -222.739712)
		(width 0.127)
		(layer "In2.Cu")
		(net "T1_BLAD2_TXD")
	)
	(segment
		(start 81.609184 -55.93207)
		(end 76.69403 -60.847224)
		(width 0.127)
		(layer "In2.Cu")
		(net "T1_BLAD2_TXD")
	)
	(segment
		(start 85.881718 -49.377346)
		(end 84.829396 -50.429668)
		(width 0.127)
		(layer "In2.Cu")
		(net "T1_BLAD2_TXD")
	)
	(segment
		(start 26.68016 -108.627672)
		(end 25.961594 -109.346238)
		(width 0.127)
		(layer "In2.Cu")
		(net "T1_BLAD2_TXD")
	)
	(segment
		(start 25.961594 -169.306748)
		(end 26.59634 -169.941494)
		(width 0.127)
		(layer "In2.Cu")
		(net "T1_BLAD2_TXD")
	)
	(segment
		(start 26.68016 -107.805474)
		(end 26.68016 -108.627672)
		(width 0.127)
		(layer "In2.Cu")
		(net "T1_BLAD2_TXD")
	)
	(via
		(at 12.558014 -314.696348)
		(size 0.508)
		(drill 0.254)
		(layers "F.Cu" "B.Cu")
		(net "T11_BLAD2_TXD")
	)
	(segment
		(start 39.089076 -442.115194)
		(end 30.282642 -442.115194)
		(width 0.127)
		(layer "In2.Cu")
		(net "T11_BLAD2_TXD")
	)
	(segment
		(start 26.360628 -438.19318)
		(end 26.360628 -380.421896)
		(width 0.127)
		(layer "In2.Cu")
		(net "T11_BLAD2_TXD")
	)
	(segment
		(start 17.670272 -332.488032)
		(end 17.670272 -323.248274)
		(width 0.127)
		(layer "In2.Cu")
		(net "T11_BLAD2_TXD")
	)
	(segment
		(start 12.558014 -314.696348)
		(end 10.293096 -314.696348)
		(width 0.127)
		(layer "In2.Cu")
		(net "T11_BLAD2_TXD")
	)
	(segment
		(start 81.355438 -446.175892)
		(end 43.149774 -446.175892)
		(width 0.127)
		(layer "In2.Cu")
		(net "T11_BLAD2_TXD")
	)
	(segment
		(start 6.127242 -313.914536)
		(end 5.329682 -313.116976)
		(width 0.127)
		(layer "In2.Cu")
		(net "T11_BLAD2_TXD")
	)
	(segment
		(start 5.329682 -309.790084)
		(end 6.449822 -308.669944)
		(width 0.127)
		(layer "In2.Cu")
		(net "T11_BLAD2_TXD")
	)
	(segment
		(start 85.643974 -454.500234)
		(end 84.41055 -453.26681)
		(width 0.127)
		(layer "In2.Cu")
		(net "T11_BLAD2_TXD")
	)
	(segment
		(start 30.282642 -442.115194)
		(end 26.360628 -438.19318)
		(width 0.127)
		(layer "In2.Cu")
		(net "T11_BLAD2_TXD")
	)
	(segment
		(start 84.41055 -453.26681)
		(end 84.41055 -449.231004)
		(width 0.127)
		(layer "In2.Cu")
		(net "T11_BLAD2_TXD")
	)
	(segment
		(start 7.058406 -313.914536)
		(end 6.127242 -313.914536)
		(width 0.127)
		(layer "In2.Cu")
		(net "T11_BLAD2_TXD")
	)
	(segment
		(start 43.149774 -446.175892)
		(end 39.089076 -442.115194)
		(width 0.127)
		(layer "In2.Cu")
		(net "T11_BLAD2_TXD")
	)
	(segment
		(start 17.670272 -323.248274)
		(end 15.673832 -321.251834)
		(width 0.127)
		(layer "In2.Cu")
		(net "T11_BLAD2_TXD")
	)
	(segment
		(start 84.41055 -449.231004)
		(end 81.355438 -446.175892)
		(width 0.127)
		(layer "In2.Cu")
		(net "T11_BLAD2_TXD")
	)
	(segment
		(start 5.329682 -313.116976)
		(end 5.329682 -309.790084)
		(width 0.127)
		(layer "In2.Cu")
		(net "T11_BLAD2_TXD")
	)
	(segment
		(start 15.673832 -321.251834)
		(end 15.673832 -317.812166)
		(width 0.127)
		(layer "In2.Cu")
		(net "T11_BLAD2_TXD")
	)
	(segment
		(start 26.360628 -380.421896)
		(end 15.153894 -369.215162)
		(width 0.127)
		(layer "In2.Cu")
		(net "T11_BLAD2_TXD")
	)
	(segment
		(start 90.71991 -453.31507)
		(end 89.706958 -453.31507)
		(width 0.127)
		(layer "In2.Cu")
		(net "T11_BLAD2_TXD")
	)
	(segment
		(start 10.124186 -314.865258)
		(end 8.009128 -314.865258)
		(width 0.127)
		(layer "In2.Cu")
		(net "T11_BLAD2_TXD")
	)
	(segment
		(start 17.0434 -333.114904)
		(end 17.670272 -332.488032)
		(width 0.127)
		(layer "In2.Cu")
		(net "T11_BLAD2_TXD")
	)
	(segment
		(start 89.706958 -453.31507)
		(end 88.521794 -454.500234)
		(width 0.127)
		(layer "In2.Cu")
		(net "T11_BLAD2_TXD")
	)
	(segment
		(start 15.673832 -317.812166)
		(end 12.558014 -314.696348)
		(width 0.127)
		(layer "In2.Cu")
		(net "T11_BLAD2_TXD")
	)
	(segment
		(start 10.293096 -314.696348)
		(end 10.124186 -314.865258)
		(width 0.127)
		(layer "In2.Cu")
		(net "T11_BLAD2_TXD")
	)
	(segment
		(start 17.0434 -335.47431)
		(end 17.0434 -333.114904)
		(width 0.127)
		(layer "In2.Cu")
		(net "T11_BLAD2_TXD")
	)
	(segment
		(start 15.153894 -337.363816)
		(end 17.0434 -335.47431)
		(width 0.127)
		(layer "In2.Cu")
		(net "T11_BLAD2_TXD")
	)
	(segment
		(start 15.153894 -369.215162)
		(end 15.153894 -337.363816)
		(width 0.127)
		(layer "In2.Cu")
		(net "T11_BLAD2_TXD")
	)
	(segment
		(start 88.521794 -454.500234)
		(end 85.643974 -454.500234)
		(width 0.127)
		(layer "In2.Cu")
		(net "T11_BLAD2_TXD")
	)
	(segment
		(start 8.009128 -314.865258)
		(end 7.058406 -313.914536)
		(width 0.127)
		(layer "In2.Cu")
		(net "T11_BLAD2_TXD")
	)
	(via
		(at 36.799012 -441.670694)
		(size 0.508)
		(drill 0.254)
		(layers "F.Cu" "B.Cu")
		(net "T11_BLAD1_TXD")
	)
	(segment
		(start 16.20901 -321.030092)
		(end 18.669254 -323.490336)
		(width 0.127)
		(layer "In2.Cu")
		(net "T11_BLAD1_TXD")
	)
	(segment
		(start 26.759916 -438.027572)
		(end 30.403038 -441.670694)
		(width 0.127)
		(layer "In2.Cu")
		(net "T11_BLAD1_TXD")
	)
	(segment
		(start 84.74075 -452.41591)
		(end 84.74075 -449.071746)
		(width 0.127)
		(layer "In2.Cu")
		(net "T11_BLAD1_TXD")
	)
	(segment
		(start 30.403038 -441.670694)
		(end 36.799012 -441.670694)
		(width 0.127)
		(layer "In2.Cu")
		(net "T11_BLAD1_TXD")
	)
	(segment
		(start 5.73786 -311.655968)
		(end 5.73786 -312.957464)
		(width 0.127)
		(layer "In2.Cu")
		(net "T11_BLAD1_TXD")
	)
	(segment
		(start 6.2484 -313.468004)
		(end 7.116064 -313.468004)
		(width 0.127)
		(layer "In2.Cu")
		(net "T11_BLAD1_TXD")
	)
	(segment
		(start 85.63991 -453.31507)
		(end 84.74075 -452.41591)
		(width 0.127)
		(layer "In2.Cu")
		(net "T11_BLAD1_TXD")
	)
	(segment
		(start 7.116064 -313.468004)
		(end 8.047482 -314.399422)
		(width 0.127)
		(layer "In2.Cu")
		(net "T11_BLAD1_TXD")
	)
	(segment
		(start 6.449822 -310.66994)
		(end 6.449822 -310.944006)
		(width 0.127)
		(layer "In2.Cu")
		(net "T11_BLAD1_TXD")
	)
	(segment
		(start 18.669254 -323.490336)
		(end 18.669254 -372.23954)
		(width 0.127)
		(layer "In2.Cu")
		(net "T11_BLAD1_TXD")
	)
	(segment
		(start 8.047482 -314.399422)
		(end 10.006076 -314.399422)
		(width 0.127)
		(layer "In2.Cu")
		(net "T11_BLAD1_TXD")
	)
	(segment
		(start 84.74075 -449.071746)
		(end 81.514696 -445.845692)
		(width 0.127)
		(layer "In2.Cu")
		(net "T11_BLAD1_TXD")
	)
	(segment
		(start 10.006076 -314.399422)
		(end 10.210292 -314.195206)
		(width 0.127)
		(layer "In2.Cu")
		(net "T11_BLAD1_TXD")
	)
	(segment
		(start 5.73786 -312.957464)
		(end 6.2484 -313.468004)
		(width 0.127)
		(layer "In2.Cu")
		(net "T11_BLAD1_TXD")
	)
	(segment
		(start 81.514696 -445.845692)
		(end 43.28668 -445.845692)
		(width 0.127)
		(layer "In2.Cu")
		(net "T11_BLAD1_TXD")
	)
	(segment
		(start 16.20901 -317.718694)
		(end 16.20901 -321.030092)
		(width 0.127)
		(layer "In2.Cu")
		(net "T11_BLAD1_TXD")
	)
	(segment
		(start 39.111682 -441.670694)
		(end 36.799012 -441.670694)
		(width 0.127)
		(layer "In2.Cu")
		(net "T11_BLAD1_TXD")
	)
	(segment
		(start 10.210292 -314.195206)
		(end 12.685522 -314.195206)
		(width 0.127)
		(layer "In2.Cu")
		(net "T11_BLAD1_TXD")
	)
	(segment
		(start 26.759916 -380.330202)
		(end 26.759916 -438.027572)
		(width 0.127)
		(layer "In2.Cu")
		(net "T11_BLAD1_TXD")
	)
	(segment
		(start 43.28668 -445.845692)
		(end 39.111682 -441.670694)
		(width 0.127)
		(layer "In2.Cu")
		(net "T11_BLAD1_TXD")
	)
	(segment
		(start 12.685522 -314.195206)
		(end 16.20901 -317.718694)
		(width 0.127)
		(layer "In2.Cu")
		(net "T11_BLAD1_TXD")
	)
	(segment
		(start 18.669254 -372.23954)
		(end 26.759916 -380.330202)
		(width 0.127)
		(layer "In2.Cu")
		(net "T11_BLAD1_TXD")
	)
	(segment
		(start 6.449822 -310.944006)
		(end 5.73786 -311.655968)
		(width 0.127)
		(layer "In2.Cu")
		(net "T11_BLAD1_TXD")
	)
	(segment
		(start 10.184638 -218.670632)
		(end 12.310618 -220.796612)
		(width 0.1524)
		(layer "F.Cu")
		(net "T1_BLAD1_RXD")
	)
	(segment
		(start 8.448802 -218.670632)
		(end 10.184638 -218.670632)
		(width 0.1524)
		(layer "F.Cu")
		(net "T1_BLAD1_RXD")
	)
	(via
		(at 98.431096 -19.519138)
		(size 0.508)
		(drill 0.254)
		(layers "F.Cu" "B.Cu")
		(net "T1_BLAD1_RXD")
	)
	(via
		(at 12.310618 -220.796612)
		(size 0.508)
		(drill 0.254)
		(layers "F.Cu" "B.Cu")
		(net "T1_BLAD1_RXD")
	)
	(segment
		(start 27.180794 -114.247168)
		(end 27.180794 -164.198808)
		(width 0.127)
		(layer "In5.Cu")
		(net "T1_BLAD1_RXD")
	)
	(segment
		(start 99.991672 -21.079714)
		(end 99.991672 -51.562508)
		(width 0.127)
		(layer "In5.Cu")
		(net "T1_BLAD1_RXD")
	)
	(segment
		(start 98.431096 -19.519138)
		(end 99.991672 -21.079714)
		(width 0.127)
		(layer "In5.Cu")
		(net "T1_BLAD1_RXD")
	)
	(segment
		(start 89.62009 -10.708132)
		(end 98.431096 -19.519138)
		(width 0.127)
		(layer "In5.Cu")
		(net "T1_BLAD1_RXD")
	)
	(segment
		(start 54.953408 -89.529666)
		(end 26.628344 -89.529666)
		(width 0.127)
		(layer "In5.Cu")
		(net "T1_BLAD1_RXD")
	)
	(segment
		(start 89.625424 -56.908446)
		(end 79.055976 -67.477894)
		(width 0.127)
		(layer "In5.Cu")
		(net "T1_BLAD1_RXD")
	)
	(segment
		(start 77.00518 -67.477894)
		(end 54.953408 -89.529666)
		(width 0.127)
		(layer "In5.Cu")
		(net "T1_BLAD1_RXD")
	)
	(segment
		(start 94.645734 -56.908446)
		(end 89.625424 -56.908446)
		(width 0.127)
		(layer "In5.Cu")
		(net "T1_BLAD1_RXD")
	)
	(segment
		(start 86.90991 -9.375648)
		(end 88.242394 -10.708132)
		(width 0.127)
		(layer "In5.Cu")
		(net "T1_BLAD1_RXD")
	)
	(segment
		(start 26.628344 -89.529666)
		(end 21.7043 -94.45371)
		(width 0.127)
		(layer "In5.Cu")
		(net "T1_BLAD1_RXD")
	)
	(segment
		(start 99.991672 -51.562508)
		(end 94.645734 -56.908446)
		(width 0.127)
		(layer "In5.Cu")
		(net "T1_BLAD1_RXD")
	)
	(segment
		(start 21.7043 -108.770674)
		(end 27.180794 -114.247168)
		(width 0.127)
		(layer "In5.Cu")
		(net "T1_BLAD1_RXD")
	)
	(segment
		(start 88.242394 -10.708132)
		(end 89.62009 -10.708132)
		(width 0.127)
		(layer "In5.Cu")
		(net "T1_BLAD1_RXD")
	)
	(segment
		(start 18.196814 -199.026018)
		(end 22.36978 -203.198984)
		(width 0.127)
		(layer "In5.Cu")
		(net "T1_BLAD1_RXD")
	)
	(segment
		(start 79.055976 -67.477894)
		(end 77.00518 -67.477894)
		(width 0.127)
		(layer "In5.Cu")
		(net "T1_BLAD1_RXD")
	)
	(segment
		(start 21.7043 -94.45371)
		(end 21.7043 -108.770674)
		(width 0.127)
		(layer "In5.Cu")
		(net "T1_BLAD1_RXD")
	)
	(segment
		(start 18.196814 -173.182788)
		(end 18.196814 -199.026018)
		(width 0.127)
		(layer "In5.Cu")
		(net "T1_BLAD1_RXD")
	)
	(segment
		(start 27.180794 -164.198808)
		(end 18.196814 -173.182788)
		(width 0.127)
		(layer "In5.Cu")
		(net "T1_BLAD1_RXD")
	)
	(segment
		(start 12.82065 -220.796612)
		(end 12.310618 -220.796612)
		(width 0.127)
		(layer "In5.Cu")
		(net "T1_BLAD1_RXD")
	)
	(segment
		(start 86.90991 -7.54507)
		(end 86.90991 -9.375648)
		(width 0.127)
		(layer "In5.Cu")
		(net "T1_BLAD1_RXD")
	)
	(segment
		(start 22.36978 -211.247482)
		(end 12.82065 -220.796612)
		(width 0.127)
		(layer "In5.Cu")
		(net "T1_BLAD1_RXD")
	)
	(segment
		(start 22.36978 -203.198984)
		(end 22.36978 -211.247482)
		(width 0.127)
		(layer "In5.Cu")
		(net "T1_BLAD1_RXD")
	)
	(via
		(at 44.042076 -440.956954)
		(size 0.508)
		(drill 0.254)
		(layers "F.Cu" "B.Cu")
		(net "T11_BLAD4_TXD")
	)
	(segment
		(start 44.042076 -440.956954)
		(end 46.344586 -443.259464)
		(width 0.127)
		(layer "In2.Cu")
		(net "T11_BLAD4_TXD")
	)
	(segment
		(start 31.163514 -439.240168)
		(end 42.32529 -439.240168)
		(width 0.127)
		(layer "In2.Cu")
		(net "T11_BLAD4_TXD")
	)
	(segment
		(start 28.936442 -379.138942)
		(end 28.936442 -437.013096)
		(width 0.127)
		(layer "In2.Cu")
		(net "T11_BLAD4_TXD")
	)
	(segment
		(start 11.028426 -303.669954)
		(end 20.650454 -313.291982)
		(width 0.127)
		(layer "In2.Cu")
		(net "T11_BLAD4_TXD")
	)
	(segment
		(start 92.938346 -449.792344)
		(end 91.95562 -450.77507)
		(width 0.127)
		(layer "In2.Cu")
		(net "T11_BLAD4_TXD")
	)
	(segment
		(start 20.650454 -313.291982)
		(end 20.650454 -370.852954)
		(width 0.127)
		(layer "In2.Cu")
		(net "T11_BLAD4_TXD")
	)
	(segment
		(start 91.95562 -450.77507)
		(end 90.71991 -450.77507)
		(width 0.127)
		(layer "In2.Cu")
		(net "T11_BLAD4_TXD")
	)
	(segment
		(start 46.344586 -443.259464)
		(end 86.884256 -443.259464)
		(width 0.127)
		(layer "In2.Cu")
		(net "T11_BLAD4_TXD")
	)
	(segment
		(start 8.449818 -303.669954)
		(end 11.028426 -303.669954)
		(width 0.127)
		(layer "In2.Cu")
		(net "T11_BLAD4_TXD")
	)
	(segment
		(start 42.32529 -439.240168)
		(end 44.042076 -440.956954)
		(width 0.127)
		(layer "In2.Cu")
		(net "T11_BLAD4_TXD")
	)
	(segment
		(start 86.884256 -443.259464)
		(end 92.938346 -449.313554)
		(width 0.127)
		(layer "In2.Cu")
		(net "T11_BLAD4_TXD")
	)
	(segment
		(start 92.938346 -449.313554)
		(end 92.938346 -449.792344)
		(width 0.127)
		(layer "In2.Cu")
		(net "T11_BLAD4_TXD")
	)
	(segment
		(start 28.936442 -437.013096)
		(end 31.163514 -439.240168)
		(width 0.127)
		(layer "In2.Cu")
		(net "T11_BLAD4_TXD")
	)
	(segment
		(start 20.650454 -370.852954)
		(end 28.936442 -379.138942)
		(width 0.127)
		(layer "In2.Cu")
		(net "T11_BLAD4_TXD")
	)
	(segment
		(start 10.106914 -217.814398)
		(end 6.59257 -217.814398)
		(width 0.1524)
		(layer "F.Cu")
		(net "T1_BLAD1_TXD")
	)
	(segment
		(start 12.301982 -220.009466)
		(end 10.106914 -217.814398)
		(width 0.1524)
		(layer "F.Cu")
		(net "T1_BLAD1_TXD")
	)
	(segment
		(start 6.59257 -217.814398)
		(end 6.448806 -217.670634)
		(width 0.1524)
		(layer "F.Cu")
		(net "T1_BLAD1_TXD")
	)
	(via
		(at 12.301982 -220.009466)
		(size 0.508)
		(drill 0.254)
		(layers "F.Cu" "B.Cu")
		(net "T1_BLAD1_TXD")
	)
	(via
		(at 91.422474 -13.256006)
		(size 0.508)
		(drill 0.254)
		(layers "F.Cu" "B.Cu")
		(net "T1_BLAD1_TXD")
	)
	(segment
		(start 26.82494 -164.087556)
		(end 26.82494 -114.544856)
		(width 0.127)
		(layer "In5.Cu")
		(net "T1_BLAD1_TXD")
	)
	(segment
		(start 85.63991 -8.81507)
		(end 87.950294 -11.125454)
		(width 0.127)
		(layer "In5.Cu")
		(net "T1_BLAD1_TXD")
	)
	(segment
		(start 17.866614 -173.045882)
		(end 26.82494 -164.087556)
		(width 0.127)
		(layer "In5.Cu")
		(net "T1_BLAD1_TXD")
	)
	(segment
		(start 99.62769 -51.330606)
		(end 99.62769 -21.461222)
		(width 0.127)
		(layer "In5.Cu")
		(net "T1_BLAD1_TXD")
	)
	(segment
		(start 21.990558 -211.08035)
		(end 21.990558 -203.445872)
		(width 0.127)
		(layer "In5.Cu")
		(net "T1_BLAD1_TXD")
	)
	(segment
		(start 21.364956 -94.230444)
		(end 26.429716 -89.165684)
		(width 0.127)
		(layer "In5.Cu")
		(net "T1_BLAD1_TXD")
	)
	(segment
		(start 26.429716 -89.165684)
		(end 54.738016 -89.165684)
		(width 0.127)
		(layer "In5.Cu")
		(net "T1_BLAD1_TXD")
	)
	(segment
		(start 94.530164 -56.428132)
		(end 99.62769 -51.330606)
		(width 0.127)
		(layer "In5.Cu")
		(net "T1_BLAD1_TXD")
	)
	(segment
		(start 13.061442 -220.009466)
		(end 21.990558 -211.08035)
		(width 0.127)
		(layer "In5.Cu")
		(net "T1_BLAD1_TXD")
	)
	(segment
		(start 87.950294 -11.125454)
		(end 89.291922 -11.125454)
		(width 0.127)
		(layer "In5.Cu")
		(net "T1_BLAD1_TXD")
	)
	(segment
		(start 76.762864 -67.140836)
		(end 78.925928 -67.140836)
		(width 0.127)
		(layer "In5.Cu")
		(net "T1_BLAD1_TXD")
	)
	(segment
		(start 89.291922 -11.125454)
		(end 91.422474 -13.256006)
		(width 0.127)
		(layer "In5.Cu")
		(net "T1_BLAD1_TXD")
	)
	(segment
		(start 89.638632 -56.428132)
		(end 94.530164 -56.428132)
		(width 0.127)
		(layer "In5.Cu")
		(net "T1_BLAD1_TXD")
	)
	(segment
		(start 78.925928 -67.140836)
		(end 89.638632 -56.428132)
		(width 0.127)
		(layer "In5.Cu")
		(net "T1_BLAD1_TXD")
	)
	(segment
		(start 21.364956 -109.084872)
		(end 21.364956 -94.230444)
		(width 0.127)
		(layer "In5.Cu")
		(net "T1_BLAD1_TXD")
	)
	(segment
		(start 17.866614 -199.321928)
		(end 17.866614 -173.045882)
		(width 0.127)
		(layer "In5.Cu")
		(net "T1_BLAD1_TXD")
	)
	(segment
		(start 54.738016 -89.165684)
		(end 76.762864 -67.140836)
		(width 0.127)
		(layer "In5.Cu")
		(net "T1_BLAD1_TXD")
	)
	(segment
		(start 12.301982 -220.009466)
		(end 13.061442 -220.009466)
		(width 0.127)
		(layer "In5.Cu")
		(net "T1_BLAD1_TXD")
	)
	(segment
		(start 99.62769 -21.461222)
		(end 91.422474 -13.256006)
		(width 0.127)
		(layer "In5.Cu")
		(net "T1_BLAD1_TXD")
	)
	(segment
		(start 21.990558 -203.445872)
		(end 17.866614 -199.321928)
		(width 0.127)
		(layer "In5.Cu")
		(net "T1_BLAD1_TXD")
	)
	(segment
		(start 26.82494 -114.544856)
		(end 21.364956 -109.084872)
		(width 0.127)
		(layer "In5.Cu")
		(net "T1_BLAD1_TXD")
	)
	(via
		(at 83.791298 -445.028574)
		(size 0.508)
		(drill 0.254)
		(layers "F.Cu" "B.Cu")
		(net "T11_BLAD3_EN")
	)
	(segment
		(start 8.855964 -314.669932)
		(end 6.449822 -314.669932)
		(width 0.127)
		(layer "In5.Cu")
		(net "T11_BLAD3_EN")
	)
	(segment
		(start 16.49476 -370.294408)
		(end 16.49476 -322.56984)
		(width 0.127)
		(layer "In5.Cu")
		(net "T11_BLAD3_EN")
	)
	(segment
		(start 83.791298 -445.028574)
		(end 88.17991 -449.417186)
		(width 0.127)
		(layer "In5.Cu")
		(net "T11_BLAD3_EN")
	)
	(segment
		(start 83.128358 -444.365634)
		(end 44.565824 -444.365634)
		(width 0.127)
		(layer "In5.Cu")
		(net "T11_BLAD3_EN")
	)
	(segment
		(start 26.696162 -438.884822)
		(end 26.696162 -380.49581)
		(width 0.127)
		(layer "In5.Cu")
		(net "T11_BLAD3_EN")
	)
	(segment
		(start 88.17991 -449.417186)
		(end 88.17991 -450.77507)
		(width 0.127)
		(layer "In5.Cu")
		(net "T11_BLAD3_EN")
	)
	(segment
		(start 26.696162 -380.49581)
		(end 16.49476 -370.294408)
		(width 0.127)
		(layer "In5.Cu")
		(net "T11_BLAD3_EN")
	)
	(segment
		(start 83.791298 -445.028574)
		(end 83.128358 -444.365634)
		(width 0.127)
		(layer "In5.Cu")
		(net "T11_BLAD3_EN")
	)
	(segment
		(start 44.565824 -444.365634)
		(end 43.6118 -443.41161)
		(width 0.127)
		(layer "In5.Cu")
		(net "T11_BLAD3_EN")
	)
	(segment
		(start 11.016996 -316.830964)
		(end 8.855964 -314.669932)
		(width 0.127)
		(layer "In5.Cu")
		(net "T11_BLAD3_EN")
	)
	(segment
		(start 11.016996 -317.092076)
		(end 11.016996 -316.830964)
		(width 0.127)
		(layer "In5.Cu")
		(net "T11_BLAD3_EN")
	)
	(segment
		(start 31.22295 -443.41161)
		(end 26.696162 -438.884822)
		(width 0.127)
		(layer "In5.Cu")
		(net "T11_BLAD3_EN")
	)
	(segment
		(start 16.49476 -322.56984)
		(end 11.016996 -317.092076)
		(width 0.127)
		(layer "In5.Cu")
		(net "T11_BLAD3_EN")
	)
	(segment
		(start 43.6118 -443.41161)
		(end 31.22295 -443.41161)
		(width 0.127)
		(layer "In5.Cu")
		(net "T11_BLAD3_EN")
	)
	(via
		(at 82.248502 -445.320674)
		(size 0.508)
		(drill 0.254)
		(layers "F.Cu" "B.Cu")
		(net "T11_BLAD1_EN")
	)
	(segment
		(start 42.755566 -443.762638)
		(end 43.688762 -444.695834)
		(width 0.127)
		(layer "In5.Cu")
		(net "T11_BLAD1_EN")
	)
	(segment
		(start 30.48254 -443.762638)
		(end 42.755566 -443.762638)
		(width 0.127)
		(layer "In5.Cu")
		(net "T11_BLAD1_EN")
	)
	(segment
		(start 85.530944 -448.603116)
		(end 85.530944 -449.394072)
		(width 0.127)
		(layer "In5.Cu")
		(net "T11_BLAD1_EN")
	)
	(segment
		(start 14.958822 -331.601318)
		(end 14.958822 -332.942692)
		(width 0.127)
		(layer "In5.Cu")
		(net "T11_BLAD1_EN")
	)
	(segment
		(start 14.958822 -332.942692)
		(end 14.735302 -333.166212)
		(width 0.127)
		(layer "In5.Cu")
		(net "T11_BLAD1_EN")
	)
	(segment
		(start 14.735302 -333.166212)
		(end 14.735302 -369.626388)
		(width 0.127)
		(layer "In5.Cu")
		(net "T11_BLAD1_EN")
	)
	(segment
		(start 14.298422 -321.838828)
		(end 14.298422 -330.940918)
		(width 0.127)
		(layer "In5.Cu")
		(net "T11_BLAD1_EN")
	)
	(segment
		(start 14.298422 -330.940918)
		(end 14.958822 -331.601318)
		(width 0.127)
		(layer "In5.Cu")
		(net "T11_BLAD1_EN")
	)
	(segment
		(start 25.92451 -380.815596)
		(end 25.92451 -439.204608)
		(width 0.127)
		(layer "In5.Cu")
		(net "T11_BLAD1_EN")
	)
	(segment
		(start 81.623662 -444.695834)
		(end 82.248502 -445.320674)
		(width 0.127)
		(layer "In5.Cu")
		(net "T11_BLAD1_EN")
	)
	(segment
		(start 82.248502 -445.320674)
		(end 85.530944 -448.603116)
		(width 0.127)
		(layer "In5.Cu")
		(net "T11_BLAD1_EN")
	)
	(segment
		(start 88.17991 -452.043038)
		(end 88.17991 -453.31507)
		(width 0.127)
		(layer "In5.Cu")
		(net "T11_BLAD1_EN")
	)
	(segment
		(start 25.92451 -439.204608)
		(end 30.48254 -443.762638)
		(width 0.127)
		(layer "In5.Cu")
		(net "T11_BLAD1_EN")
	)
	(segment
		(start 6.449822 -316.669928)
		(end 9.129522 -316.669928)
		(width 0.127)
		(layer "In5.Cu")
		(net "T11_BLAD1_EN")
	)
	(segment
		(start 43.688762 -444.695834)
		(end 81.623662 -444.695834)
		(width 0.127)
		(layer "In5.Cu")
		(net "T11_BLAD1_EN")
	)
	(segment
		(start 9.129522 -316.669928)
		(end 14.298422 -321.838828)
		(width 0.127)
		(layer "In5.Cu")
		(net "T11_BLAD1_EN")
	)
	(segment
		(start 14.735302 -369.626388)
		(end 25.92451 -380.815596)
		(width 0.127)
		(layer "In5.Cu")
		(net "T11_BLAD1_EN")
	)
	(segment
		(start 85.530944 -449.394072)
		(end 88.17991 -452.043038)
		(width 0.127)
		(layer "In5.Cu")
		(net "T11_BLAD1_EN")
	)
	(via
		(at 41.467278 -441.355226)
		(size 0.508)
		(drill 0.254)
		(layers "F.Cu" "B.Cu")
		(net "T11_BLAD1_RXD")
	)
	(segment
		(start 8.449818 -311.669938)
		(end 16.952214 -311.669938)
		(width 0.127)
		(layer "In2.Cu")
		(net "T11_BLAD1_RXD")
	)
	(segment
		(start 87.81923 -449.209414)
		(end 86.966044 -448.356228)
		(width 0.127)
		(layer "In2.Cu")
		(net "T11_BLAD1_RXD")
	)
	(segment
		(start 30.642814 -440.300364)
		(end 40.412416 -440.300364)
		(width 0.127)
		(layer "In2.Cu")
		(net "T11_BLAD1_RXD")
	)
	(segment
		(start 86.90991 -452.04507)
		(end 86.90991 -450.807582)
		(width 0.127)
		(layer "In2.Cu")
		(net "T11_BLAD1_RXD")
	)
	(segment
		(start 87.81923 -449.898262)
		(end 87.81923 -449.209414)
		(width 0.127)
		(layer "In2.Cu")
		(net "T11_BLAD1_RXD")
	)
	(segment
		(start 27.835352 -379.621796)
		(end 27.835352 -437.492902)
		(width 0.127)
		(layer "In2.Cu")
		(net "T11_BLAD1_RXD")
	)
	(segment
		(start 19.659854 -314.377578)
		(end 19.659854 -371.446298)
		(width 0.127)
		(layer "In2.Cu")
		(net "T11_BLAD1_RXD")
	)
	(segment
		(start 19.659854 -371.446298)
		(end 27.835352 -379.621796)
		(width 0.127)
		(layer "In2.Cu")
		(net "T11_BLAD1_RXD")
	)
	(segment
		(start 82.455512 -444.334392)
		(end 44.446444 -444.334392)
		(width 0.127)
		(layer "In2.Cu")
		(net "T11_BLAD1_RXD")
	)
	(segment
		(start 16.952214 -311.669938)
		(end 19.659854 -314.377578)
		(width 0.127)
		(layer "In2.Cu")
		(net "T11_BLAD1_RXD")
	)
	(segment
		(start 86.90991 -450.807582)
		(end 87.81923 -449.898262)
		(width 0.127)
		(layer "In2.Cu")
		(net "T11_BLAD1_RXD")
	)
	(segment
		(start 44.446444 -444.334392)
		(end 41.467278 -441.355226)
		(width 0.127)
		(layer "In2.Cu")
		(net "T11_BLAD1_RXD")
	)
	(segment
		(start 86.477348 -448.356228)
		(end 82.455512 -444.334392)
		(width 0.127)
		(layer "In2.Cu")
		(net "T11_BLAD1_RXD")
	)
	(segment
		(start 86.966044 -448.356228)
		(end 86.477348 -448.356228)
		(width 0.127)
		(layer "In2.Cu")
		(net "T11_BLAD1_RXD")
	)
	(segment
		(start 27.835352 -437.492902)
		(end 30.642814 -440.300364)
		(width 0.127)
		(layer "In2.Cu")
		(net "T11_BLAD1_RXD")
	)
	(segment
		(start 40.412416 -440.300364)
		(end 41.467278 -441.355226)
		(width 0.127)
		(layer "In2.Cu")
		(net "T11_BLAD1_RXD")
	)
	(via
		(at 96.331278 -13.248132)
		(size 0.508)
		(drill 0.254)
		(layers "F.Cu" "B.Cu")
		(net "T1_BLAD3_EN")
	)
	(segment
		(start 15.908782 -222.711264)
		(end 16.065246 -222.711264)
		(width 0.127)
		(layer "In5.Cu")
		(net "T1_BLAD3_EN")
	)
	(segment
		(start 96.331278 -13.245592)
		(end 89.360756 -6.27507)
		(width 0.127)
		(layer "In5.Cu")
		(net "T1_BLAD3_EN")
	)
	(segment
		(start 23.234142 -108.366052)
		(end 23.234142 -94.866206)
		(width 0.127)
		(layer "In5.Cu")
		(net "T1_BLAD3_EN")
	)
	(segment
		(start 89.735406 -57.732676)
		(end 96.333564 -57.732676)
		(width 0.127)
		(layer "In5.Cu")
		(net "T1_BLAD3_EN")
	)
	(segment
		(start 77.180186 -68.309236)
		(end 79.158846 -68.309236)
		(width 0.127)
		(layer "In5.Cu")
		(net "T1_BLAD3_EN")
	)
	(segment
		(start 23.234142 -94.866206)
		(end 26.797254 -91.303094)
		(width 0.127)
		(layer "In5.Cu")
		(net "T1_BLAD3_EN")
	)
	(segment
		(start 23.82901 -201.972164)
		(end 19.604228 -197.747382)
		(width 0.127)
		(layer "In5.Cu")
		(net "T1_BLAD3_EN")
	)
	(segment
		(start 16.065246 -222.711264)
		(end 23.82901 -214.9475)
		(width 0.127)
		(layer "In5.Cu")
		(net "T1_BLAD3_EN")
	)
	(segment
		(start 19.604228 -197.747382)
		(end 19.604228 -182.572406)
		(width 0.127)
		(layer "In5.Cu")
		(net "T1_BLAD3_EN")
	)
	(segment
		(start 79.158846 -68.309236)
		(end 89.735406 -57.732676)
		(width 0.127)
		(layer "In5.Cu")
		(net "T1_BLAD3_EN")
	)
	(segment
		(start 28.566618 -173.610016)
		(end 28.566618 -113.698528)
		(width 0.127)
		(layer "In5.Cu")
		(net "T1_BLAD3_EN")
	)
	(segment
		(start 96.333564 -57.732676)
		(end 101.493066 -52.573174)
		(width 0.127)
		(layer "In5.Cu")
		(net "T1_BLAD3_EN")
	)
	(segment
		(start 23.82901 -214.9475)
		(end 23.82901 -201.972164)
		(width 0.127)
		(layer "In5.Cu")
		(net "T1_BLAD3_EN")
	)
	(segment
		(start 89.360756 -6.27507)
		(end 88.17991 -6.27507)
		(width 0.127)
		(layer "In5.Cu")
		(net "T1_BLAD3_EN")
	)
	(segment
		(start 9.949434 -228.670612)
		(end 15.908782 -222.711264)
		(width 0.127)
		(layer "In5.Cu")
		(net "T1_BLAD3_EN")
	)
	(segment
		(start 54.186328 -91.303094)
		(end 77.180186 -68.309236)
		(width 0.127)
		(layer "In5.Cu")
		(net "T1_BLAD3_EN")
	)
	(segment
		(start 101.493066 -52.573174)
		(end 101.493066 -18.40738)
		(width 0.127)
		(layer "In5.Cu")
		(net "T1_BLAD3_EN")
	)
	(segment
		(start 26.797254 -91.303094)
		(end 54.186328 -91.303094)
		(width 0.127)
		(layer "In5.Cu")
		(net "T1_BLAD3_EN")
	)
	(segment
		(start 96.331278 -13.248132)
		(end 96.331278 -13.245592)
		(width 0.127)
		(layer "In5.Cu")
		(net "T1_BLAD3_EN")
	)
	(segment
		(start 19.604228 -182.572406)
		(end 28.566618 -173.610016)
		(width 0.127)
		(layer "In5.Cu")
		(net "T1_BLAD3_EN")
	)
	(segment
		(start 101.493066 -18.40738)
		(end 96.331278 -13.245592)
		(width 0.127)
		(layer "In5.Cu")
		(net "T1_BLAD3_EN")
	)
	(segment
		(start 28.566618 -113.698528)
		(end 23.234142 -108.366052)
		(width 0.127)
		(layer "In5.Cu")
		(net "T1_BLAD3_EN")
	)
	(segment
		(start 8.448802 -228.670612)
		(end 9.949434 -228.670612)
		(width 0.127)
		(layer "In5.Cu")
		(net "T1_BLAD3_EN")
	)
	(segment
		(start 11.689842 -229.67061)
		(end 6.448806 -229.67061)
		(width 0.1524)
		(layer "F.Cu")
		(net "T1_BLAD2_EN")
	)
	(segment
		(start 12.91463 -229.67061)
		(end 11.689842 -229.67061)
		(width 0.1524)
		(layer "F.Cu")
		(net "T1_BLAD2_EN")
	)
	(segment
		(start 12.919456 -229.665784)
		(end 12.91463 -229.67061)
		(width 0.1524)
		(layer "F.Cu")
		(net "T1_BLAD2_EN")
	)
	(via
		(at 11.689842 -229.67061)
		(size 0.762)
		(drill 0.381)
		(layers "F.Cu" "B.Cu")
		(net "T1_BLAD2_EN")
	)
	(via
		(at 94.539816 -14.256004)
		(size 0.508)
		(drill 0.254)
		(layers "F.Cu" "B.Cu")
		(net "T1_BLAD1_EN")
	)
	(segment
		(start 6.328664 -228.384354)
		(end 5.678424 -229.034594)
		(width 0.127)
		(layer "In5.Cu")
		(net "T1_BLAD1_EN")
	)
	(segment
		(start 7.862316 -227.404168)
		(end 6.88213 -228.384354)
		(width 0.127)
		(layer "In5.Cu")
		(net "T1_BLAD1_EN")
	)
	(segment
		(start 9.357106 -227.404168)
		(end 7.862316 -227.404168)
		(width 0.127)
		(layer "In5.Cu")
		(net "T1_BLAD1_EN")
	)
	(segment
		(start 79.02194 -67.979036)
		(end 77.04328 -67.979036)
		(width 0.127)
		(layer "In5.Cu")
		(net "T1_BLAD1_EN")
	)
	(segment
		(start 15.113762 -220.69933)
		(end 15.113762 -221.647512)
		(width 0.127)
		(layer "In5.Cu")
		(net "T1_BLAD1_EN")
	)
	(segment
		(start 23.076154 -212.736938)
		(end 15.113762 -220.69933)
		(width 0.127)
		(layer "In5.Cu")
		(net "T1_BLAD1_EN")
	)
	(segment
		(start 100.698046 -52.022502)
		(end 95.39732 -57.323228)
		(width 0.127)
		(layer "In5.Cu")
		(net "T1_BLAD1_EN")
	)
	(segment
		(start 100.698046 -20.414234)
		(end 100.698046 -52.022502)
		(width 0.127)
		(layer "In5.Cu")
		(net "T1_BLAD1_EN")
	)
	(segment
		(start 15.113762 -221.647512)
		(end 9.357106 -227.404168)
		(width 0.127)
		(layer "In5.Cu")
		(net "T1_BLAD1_EN")
	)
	(segment
		(start 5.678424 -229.034594)
		(end 5.678424 -230.0732)
		(width 0.127)
		(layer "In5.Cu")
		(net "T1_BLAD1_EN")
	)
	(segment
		(start 95.39732 -57.323228)
		(end 89.677748 -57.323228)
		(width 0.127)
		(layer "In5.Cu")
		(net "T1_BLAD1_EN")
	)
	(segment
		(start 54.670706 -90.35161)
		(end 26.783792 -90.35161)
		(width 0.127)
		(layer "In5.Cu")
		(net "T1_BLAD1_EN")
	)
	(segment
		(start 89.098882 -8.81507)
		(end 88.17991 -8.81507)
		(width 0.127)
		(layer "In5.Cu")
		(net "T1_BLAD1_EN")
	)
	(segment
		(start 6.275832 -230.670608)
		(end 8.448802 -230.670608)
		(width 0.127)
		(layer "In5.Cu")
		(net "T1_BLAD1_EN")
	)
	(segment
		(start 22.53234 -108.60278)
		(end 27.854402 -113.924842)
		(width 0.127)
		(layer "In5.Cu")
		(net "T1_BLAD1_EN")
	)
	(segment
		(start 6.88213 -228.384354)
		(end 6.328664 -228.384354)
		(width 0.127)
		(layer "In5.Cu")
		(net "T1_BLAD1_EN")
	)
	(segment
		(start 89.677748 -57.323228)
		(end 79.02194 -67.979036)
		(width 0.127)
		(layer "In5.Cu")
		(net "T1_BLAD1_EN")
	)
	(segment
		(start 18.857214 -173.463458)
		(end 18.857214 -198.301102)
		(width 0.127)
		(layer "In5.Cu")
		(net "T1_BLAD1_EN")
	)
	(segment
		(start 22.53234 -94.603062)
		(end 22.53234 -108.60278)
		(width 0.127)
		(layer "In5.Cu")
		(net "T1_BLAD1_EN")
	)
	(segment
		(start 27.854402 -113.924842)
		(end 27.854402 -164.46627)
		(width 0.127)
		(layer "In5.Cu")
		(net "T1_BLAD1_EN")
	)
	(segment
		(start 23.076154 -202.520042)
		(end 23.076154 -212.736938)
		(width 0.127)
		(layer "In5.Cu")
		(net "T1_BLAD1_EN")
	)
	(segment
		(start 94.539816 -14.256004)
		(end 89.098882 -8.81507)
		(width 0.127)
		(layer "In5.Cu")
		(net "T1_BLAD1_EN")
	)
	(segment
		(start 26.783792 -90.35161)
		(end 22.53234 -94.603062)
		(width 0.127)
		(layer "In5.Cu")
		(net "T1_BLAD1_EN")
	)
	(segment
		(start 94.539816 -14.256004)
		(end 100.698046 -20.414234)
		(width 0.127)
		(layer "In5.Cu")
		(net "T1_BLAD1_EN")
	)
	(segment
		(start 77.04328 -67.979036)
		(end 54.670706 -90.35161)
		(width 0.127)
		(layer "In5.Cu")
		(net "T1_BLAD1_EN")
	)
	(segment
		(start 27.854402 -164.46627)
		(end 18.857214 -173.463458)
		(width 0.127)
		(layer "In5.Cu")
		(net "T1_BLAD1_EN")
	)
	(segment
		(start 18.857214 -198.301102)
		(end 23.076154 -202.520042)
		(width 0.127)
		(layer "In5.Cu")
		(net "T1_BLAD1_EN")
	)
	(segment
		(start 5.678424 -230.0732)
		(end 6.275832 -230.670608)
		(width 0.127)
		(layer "In5.Cu")
		(net "T1_BLAD1_EN")
	)
	(via
		(at 93.428566 -397.791432)
		(size 0.508)
		(drill 0.254)
		(layers "F.Cu" "B.Cu")
		(net "T10_BLAD4_RXD")
	)
	(segment
		(start 100.973636 -357.801164)
		(end 100.973636 -390.246362)
		(width 0.127)
		(layer "In5.Cu")
		(net "T10_BLAD4_RXD")
	)
	(segment
		(start 23.358094 -287.311338)
		(end 27.253184 -291.206428)
		(width 0.127)
		(layer "In5.Cu")
		(net "T10_BLAD4_RXD")
	)
	(segment
		(start 91.98991 -405.05507)
		(end 91.98991 -399.230088)
		(width 0.127)
		(layer "In5.Cu")
		(net "T10_BLAD4_RXD")
	)
	(segment
		(start 95.6564 -352.483928)
		(end 100.973636 -357.801164)
		(width 0.127)
		(layer "In5.Cu")
		(net "T10_BLAD4_RXD")
	)
	(segment
		(start 12.268962 -287.311338)
		(end 23.358094 -287.311338)
		(width 0.127)
		(layer "In5.Cu")
		(net "T10_BLAD4_RXD")
	)
	(segment
		(start 7.983982 -290.41852)
		(end 9.16178 -290.41852)
		(width 0.127)
		(layer "In5.Cu")
		(net "T10_BLAD4_RXD")
	)
	(segment
		(start 6.946138 -291.456364)
		(end 7.983982 -290.41852)
		(width 0.127)
		(layer "In5.Cu")
		(net "T10_BLAD4_RXD")
	)
	(segment
		(start 91.98991 -399.230088)
		(end 93.428566 -397.791432)
		(width 0.127)
		(layer "In5.Cu")
		(net "T10_BLAD4_RXD")
	)
	(segment
		(start 27.253184 -291.206428)
		(end 27.253184 -349.930974)
		(width 0.127)
		(layer "In5.Cu")
		(net "T10_BLAD4_RXD")
	)
	(segment
		(start 1.949958 -293.66972)
		(end 4.163314 -291.456364)
		(width 0.127)
		(layer "In5.Cu")
		(net "T10_BLAD4_RXD")
	)
	(segment
		(start 29.806138 -352.483928)
		(end 95.6564 -352.483928)
		(width 0.127)
		(layer "In5.Cu")
		(net "T10_BLAD4_RXD")
	)
	(segment
		(start 27.253184 -349.930974)
		(end 29.806138 -352.483928)
		(width 0.127)
		(layer "In5.Cu")
		(net "T10_BLAD4_RXD")
	)
	(segment
		(start 9.16178 -290.41852)
		(end 12.268962 -287.311338)
		(width 0.127)
		(layer "In5.Cu")
		(net "T10_BLAD4_RXD")
	)
	(segment
		(start 100.973636 -390.246362)
		(end 93.428566 -397.791432)
		(width 0.127)
		(layer "In5.Cu")
		(net "T10_BLAD4_RXD")
	)
	(segment
		(start 4.163314 -291.456364)
		(end 6.946138 -291.456364)
		(width 0.127)
		(layer "In5.Cu")
		(net "T10_BLAD4_RXD")
	)
	(via
		(at 85.334602 -399.744438)
		(size 0.508)
		(drill 0.254)
		(layers "F.Cu" "B.Cu")
		(net "T10_BLAD1_RXD")
	)
	(segment
		(start 22.407626 -350.272858)
		(end 22.407626 -310.091074)
		(width 0.127)
		(layer "In2.Cu")
		(net "T10_BLAD1_RXD")
	)
	(segment
		(start 4.855464 -299.76445)
		(end 3.949954 -300.66996)
		(width 0.127)
		(layer "In2.Cu")
		(net "T10_BLAD1_RXD")
	)
	(segment
		(start 82.430112 -358.776524)
		(end 42.360088 -358.776524)
		(width 0.127)
		(layer "In2.Cu")
		(net "T10_BLAD1_RXD")
	)
	(segment
		(start 90.29827 -404.708106)
		(end 90.29827 -405.562562)
		(width 0.127)
		(layer "In2.Cu")
		(net "T10_BLAD1_RXD")
	)
	(segment
		(start 90.29827 -405.562562)
		(end 89.8906 -405.970232)
		(width 0.127)
		(layer "In2.Cu")
		(net "T10_BLAD1_RXD")
	)
	(segment
		(start 85.334602 -399.744438)
		(end 90.29827 -404.708106)
		(width 0.127)
		(layer "In2.Cu")
		(net "T10_BLAD1_RXD")
	)
	(segment
		(start 7.75589 -298.923964)
		(end 6.915404 -299.76445)
		(width 0.127)
		(layer "In2.Cu")
		(net "T10_BLAD1_RXD")
	)
	(segment
		(start 89.8906 -406.736804)
		(end 90.46337 -407.309574)
		(width 0.127)
		(layer "In2.Cu")
		(net "T10_BLAD1_RXD")
	)
	(segment
		(start 90.46337 -407.891742)
		(end 89.929716 -408.425396)
		(width 0.127)
		(layer "In2.Cu")
		(net "T10_BLAD1_RXD")
	)
	(segment
		(start 85.334602 -399.744438)
		(end 83.825334 -398.23517)
		(width 0.127)
		(layer "In2.Cu")
		(net "T10_BLAD1_RXD")
	)
	(segment
		(start 88.735662 -408.056588)
		(end 87.371428 -408.056588)
		(width 0.127)
		(layer "In2.Cu")
		(net "T10_BLAD1_RXD")
	)
	(segment
		(start 89.929716 -408.425396)
		(end 89.10447 -408.425396)
		(width 0.127)
		(layer "In2.Cu")
		(net "T10_BLAD1_RXD")
	)
	(segment
		(start 42.360088 -358.776524)
		(end 38.852094 -355.26853)
		(width 0.127)
		(layer "In2.Cu")
		(net "T10_BLAD1_RXD")
	)
	(segment
		(start 22.407626 -310.091074)
		(end 11.240516 -298.923964)
		(width 0.127)
		(layer "In2.Cu")
		(net "T10_BLAD1_RXD")
	)
	(segment
		(start 27.403298 -355.26853)
		(end 22.407626 -350.272858)
		(width 0.127)
		(layer "In2.Cu")
		(net "T10_BLAD1_RXD")
	)
	(segment
		(start 89.8906 -405.970232)
		(end 89.8906 -406.736804)
		(width 0.127)
		(layer "In2.Cu")
		(net "T10_BLAD1_RXD")
	)
	(segment
		(start 83.825334 -360.171746)
		(end 82.430112 -358.776524)
		(width 0.127)
		(layer "In2.Cu")
		(net "T10_BLAD1_RXD")
	)
	(segment
		(start 38.852094 -355.26853)
		(end 27.403298 -355.26853)
		(width 0.127)
		(layer "In2.Cu")
		(net "T10_BLAD1_RXD")
	)
	(segment
		(start 83.825334 -398.23517)
		(end 83.825334 -360.171746)
		(width 0.127)
		(layer "In2.Cu")
		(net "T10_BLAD1_RXD")
	)
	(segment
		(start 89.10447 -408.425396)
		(end 88.735662 -408.056588)
		(width 0.127)
		(layer "In2.Cu")
		(net "T10_BLAD1_RXD")
	)
	(segment
		(start 87.371428 -408.056588)
		(end 86.90991 -407.59507)
		(width 0.127)
		(layer "In2.Cu")
		(net "T10_BLAD1_RXD")
	)
	(segment
		(start 6.915404 -299.76445)
		(end 4.855464 -299.76445)
		(width 0.127)
		(layer "In2.Cu")
		(net "T10_BLAD1_RXD")
	)
	(segment
		(start 90.46337 -407.309574)
		(end 90.46337 -407.891742)
		(width 0.127)
		(layer "In2.Cu")
		(net "T10_BLAD1_RXD")
	)
	(segment
		(start 11.240516 -298.923964)
		(end 7.75589 -298.923964)
		(width 0.127)
		(layer "In2.Cu")
		(net "T10_BLAD1_RXD")
	)
	(via
		(at 84.702396 -397.938244)
		(size 0.508)
		(drill 0.254)
		(layers "F.Cu" "B.Cu")
		(net "T10_BLAD1_TXD")
	)
	(segment
		(start 38.981888 -354.931218)
		(end 27.671268 -354.931218)
		(width 0.127)
		(layer "In2.Cu")
		(net "T10_BLAD1_TXD")
	)
	(segment
		(start 91.511628 -405.76627)
		(end 91.511628 -406.814274)
		(width 0.127)
		(layer "In2.Cu")
		(net "T10_BLAD1_TXD")
	)
	(segment
		(start 91.511628 -406.814274)
		(end 91.016836 -407.309066)
		(width 0.127)
		(layer "In2.Cu")
		(net "T10_BLAD1_TXD")
	)
	(segment
		(start 84.702396 -397.938244)
		(end 84.155534 -397.391382)
		(width 0.127)
		(layer "In2.Cu")
		(net "T10_BLAD1_TXD")
	)
	(segment
		(start 22.737826 -309.782718)
		(end 11.52017 -298.565062)
		(width 0.127)
		(layer "In2.Cu")
		(net "T10_BLAD1_TXD")
	)
	(segment
		(start 84.155534 -397.391382)
		(end 84.155534 -360.03484)
		(width 0.127)
		(layer "In2.Cu")
		(net "T10_BLAD1_TXD")
	)
	(segment
		(start 91.110054 -409.777946)
		(end 86.552786 -409.777946)
		(width 0.127)
		(layer "In2.Cu")
		(net "T10_BLAD1_TXD")
	)
	(segment
		(start 84.155534 -360.03484)
		(end 82.567018 -358.446324)
		(width 0.127)
		(layer "In2.Cu")
		(net "T10_BLAD1_TXD")
	)
	(segment
		(start 91.016836 -407.901394)
		(end 91.496896 -408.381454)
		(width 0.127)
		(layer "In2.Cu")
		(net "T10_BLAD1_TXD")
	)
	(segment
		(start 6.749796 -299.433742)
		(end 3.74269 -299.433742)
		(width 0.127)
		(layer "In2.Cu")
		(net "T10_BLAD1_TXD")
	)
	(segment
		(start 42.496994 -358.446324)
		(end 38.981888 -354.931218)
		(width 0.127)
		(layer "In2.Cu")
		(net "T10_BLAD1_TXD")
	)
	(segment
		(start 91.496896 -409.391104)
		(end 91.110054 -409.777946)
		(width 0.127)
		(layer "In2.Cu")
		(net "T10_BLAD1_TXD")
	)
	(segment
		(start 91.094306 -405.348948)
		(end 91.511628 -405.76627)
		(width 0.127)
		(layer "In2.Cu")
		(net "T10_BLAD1_TXD")
	)
	(segment
		(start 86.552786 -409.777946)
		(end 85.63991 -408.86507)
		(width 0.127)
		(layer "In2.Cu")
		(net "T10_BLAD1_TXD")
	)
	(segment
		(start 82.567018 -358.446324)
		(end 42.496994 -358.446324)
		(width 0.127)
		(layer "In2.Cu")
		(net "T10_BLAD1_TXD")
	)
	(segment
		(start 7.618476 -298.565062)
		(end 6.749796 -299.433742)
		(width 0.127)
		(layer "In2.Cu")
		(net "T10_BLAD1_TXD")
	)
	(segment
		(start 3.74269 -299.433742)
		(end 3.50647 -299.669962)
		(width 0.127)
		(layer "In2.Cu")
		(net "T10_BLAD1_TXD")
	)
	(segment
		(start 91.496896 -408.381454)
		(end 91.496896 -409.391104)
		(width 0.127)
		(layer "In2.Cu")
		(net "T10_BLAD1_TXD")
	)
	(segment
		(start 22.737826 -349.997776)
		(end 22.737826 -309.782718)
		(width 0.127)
		(layer "In2.Cu")
		(net "T10_BLAD1_TXD")
	)
	(segment
		(start 84.702396 -397.938244)
		(end 91.094306 -404.330154)
		(width 0.127)
		(layer "In2.Cu")
		(net "T10_BLAD1_TXD")
	)
	(segment
		(start 3.50647 -299.669962)
		(end 1.949958 -299.669962)
		(width 0.127)
		(layer "In2.Cu")
		(net "T10_BLAD1_TXD")
	)
	(segment
		(start 91.094306 -404.330154)
		(end 91.094306 -405.348948)
		(width 0.127)
		(layer "In2.Cu")
		(net "T10_BLAD1_TXD")
	)
	(segment
		(start 11.52017 -298.565062)
		(end 7.618476 -298.565062)
		(width 0.127)
		(layer "In2.Cu")
		(net "T10_BLAD1_TXD")
	)
	(segment
		(start 27.671268 -354.931218)
		(end 22.737826 -349.997776)
		(width 0.127)
		(layer "In2.Cu")
		(net "T10_BLAD1_TXD")
	)
	(segment
		(start 91.016836 -407.309066)
		(end 91.016836 -407.901394)
		(width 0.127)
		(layer "In2.Cu")
		(net "T10_BLAD1_TXD")
	)
	(via
		(at 90.262456 -399.03146)
		(size 0.508)
		(drill 0.254)
		(layers "F.Cu" "B.Cu")
		(net "T10_BLAD3_RXD")
	)
	(segment
		(start 86.90991 -405.05507)
		(end 86.90991 -402.384006)
		(width 0.127)
		(layer "In5.Cu")
		(net "T10_BLAD3_RXD")
	)
	(segment
		(start 29.564838 -353.25812)
		(end 95.335344 -353.25812)
		(width 0.127)
		(layer "In5.Cu")
		(net "T10_BLAD3_RXD")
	)
	(segment
		(start 26.478992 -350.172274)
		(end 29.564838 -353.25812)
		(width 0.127)
		(layer "In5.Cu")
		(net "T10_BLAD3_RXD")
	)
	(segment
		(start 26.478992 -292.84295)
		(end 26.478992 -350.172274)
		(width 0.127)
		(layer "In5.Cu")
		(net "T10_BLAD3_RXD")
	)
	(segment
		(start 8.821166 -292.598348)
		(end 12.614656 -288.804858)
		(width 0.127)
		(layer "In5.Cu")
		(net "T10_BLAD3_RXD")
	)
	(segment
		(start 1.949958 -295.66997)
		(end 4.25069 -293.369238)
		(width 0.127)
		(layer "In5.Cu")
		(net "T10_BLAD3_RXD")
	)
	(segment
		(start 4.25069 -293.369238)
		(end 7.202424 -293.369238)
		(width 0.127)
		(layer "In5.Cu")
		(net "T10_BLAD3_RXD")
	)
	(segment
		(start 12.614656 -288.804858)
		(end 22.4409 -288.804858)
		(width 0.127)
		(layer "In5.Cu")
		(net "T10_BLAD3_RXD")
	)
	(segment
		(start 100.199444 -389.094472)
		(end 90.262456 -399.03146)
		(width 0.127)
		(layer "In5.Cu")
		(net "T10_BLAD3_RXD")
	)
	(segment
		(start 22.4409 -288.804858)
		(end 26.478992 -292.84295)
		(width 0.127)
		(layer "In5.Cu")
		(net "T10_BLAD3_RXD")
	)
	(segment
		(start 7.973314 -292.598348)
		(end 8.821166 -292.598348)
		(width 0.127)
		(layer "In5.Cu")
		(net "T10_BLAD3_RXD")
	)
	(segment
		(start 100.199444 -358.12222)
		(end 100.199444 -389.094472)
		(width 0.127)
		(layer "In5.Cu")
		(net "T10_BLAD3_RXD")
	)
	(segment
		(start 86.90991 -402.384006)
		(end 90.262456 -399.03146)
		(width 0.127)
		(layer "In5.Cu")
		(net "T10_BLAD3_RXD")
	)
	(segment
		(start 7.202424 -293.369238)
		(end 7.973314 -292.598348)
		(width 0.127)
		(layer "In5.Cu")
		(net "T10_BLAD3_RXD")
	)
	(segment
		(start 95.335344 -353.25812)
		(end 100.199444 -358.12222)
		(width 0.127)
		(layer "In5.Cu")
		(net "T10_BLAD3_RXD")
	)
	(via
		(at 79.267558 -400.271234)
		(size 0.508)
		(drill 0.254)
		(layers "F.Cu" "B.Cu")
		(net "T10_BLAD1_EN")
	)
	(segment
		(start 20.980654 -310.801258)
		(end 13.001244 -302.821848)
		(width 0.127)
		(layer "In2.Cu")
		(net "T10_BLAD1_EN")
	)
	(segment
		(start 7.987538 -302.821848)
		(end 6.974586 -303.8348)
		(width 0.127)
		(layer "In2.Cu")
		(net "T10_BLAD1_EN")
	)
	(segment
		(start 4.373626 -305.66995)
		(end 1.949958 -305.66995)
		(width 0.127)
		(layer "In2.Cu")
		(net "T10_BLAD1_EN")
	)
	(segment
		(start 88.17991 -408.86507)
		(end 86.83244 -408.86507)
		(width 0.127)
		(layer "In2.Cu")
		(net "T10_BLAD1_EN")
	)
	(segment
		(start 82.1563 -359.436924)
		(end 42.086276 -359.436924)
		(width 0.127)
		(layer "In2.Cu")
		(net "T10_BLAD1_EN")
	)
	(segment
		(start 24.699722 -356.296976)
		(end 20.980654 -352.577908)
		(width 0.127)
		(layer "In2.Cu")
		(net "T10_BLAD1_EN")
	)
	(segment
		(start 83.164934 -360.445558)
		(end 82.1563 -359.436924)
		(width 0.127)
		(layer "In2.Cu")
		(net "T10_BLAD1_EN")
	)
	(segment
		(start 79.267558 -400.271234)
		(end 83.164934 -396.373858)
		(width 0.127)
		(layer "In2.Cu")
		(net "T10_BLAD1_EN")
	)
	(segment
		(start 42.086276 -359.436924)
		(end 38.946328 -356.296976)
		(width 0.127)
		(layer "In2.Cu")
		(net "T10_BLAD1_EN")
	)
	(segment
		(start 38.946328 -356.296976)
		(end 24.699722 -356.296976)
		(width 0.127)
		(layer "In2.Cu")
		(net "T10_BLAD1_EN")
	)
	(segment
		(start 6.974586 -303.8348)
		(end 6.208776 -303.8348)
		(width 0.127)
		(layer "In2.Cu")
		(net "T10_BLAD1_EN")
	)
	(segment
		(start 6.208776 -303.8348)
		(end 4.373626 -305.66995)
		(width 0.127)
		(layer "In2.Cu")
		(net "T10_BLAD1_EN")
	)
	(segment
		(start 20.980654 -352.577908)
		(end 20.980654 -310.801258)
		(width 0.127)
		(layer "In2.Cu")
		(net "T10_BLAD1_EN")
	)
	(segment
		(start 86.83244 -408.86507)
		(end 84.174076 -406.206706)
		(width 0.127)
		(layer "In2.Cu")
		(net "T10_BLAD1_EN")
	)
	(segment
		(start 83.164934 -396.373858)
		(end 83.164934 -360.445558)
		(width 0.127)
		(layer "In2.Cu")
		(net "T10_BLAD1_EN")
	)
	(segment
		(start 13.001244 -302.821848)
		(end 7.987538 -302.821848)
		(width 0.127)
		(layer "In2.Cu")
		(net "T10_BLAD1_EN")
	)
	(segment
		(start 84.174076 -406.206706)
		(end 84.174076 -405.177752)
		(width 0.127)
		(layer "In2.Cu")
		(net "T10_BLAD1_EN")
	)
	(segment
		(start 84.174076 -405.177752)
		(end 79.267558 -400.271234)
		(width 0.127)
		(layer "In2.Cu")
		(net "T10_BLAD1_EN")
	)
	(via
		(at 88.45423 -400.111214)
		(size 0.508)
		(drill 0.254)
		(layers "F.Cu" "B.Cu")
		(net "T10_BLAD3_TXD")
	)
	(segment
		(start 22.297644 -289.150298)
		(end 12.817094 -289.150298)
		(width 0.127)
		(layer "In5.Cu")
		(net "T10_BLAD3_TXD")
	)
	(segment
		(start 99.854004 -388.71144)
		(end 99.854004 -358.265476)
		(width 0.127)
		(layer "In5.Cu")
		(net "T10_BLAD3_TXD")
	)
	(segment
		(start 26.133552 -292.986206)
		(end 22.297644 -289.150298)
		(width 0.127)
		(layer "In5.Cu")
		(net "T10_BLAD3_TXD")
	)
	(segment
		(start 9.03732 -292.930072)
		(end 8.11784 -292.930072)
		(width 0.127)
		(layer "In5.Cu")
		(net "T10_BLAD3_TXD")
	)
	(segment
		(start 95.192088 -353.60356)
		(end 29.442664 -353.60356)
		(width 0.127)
		(layer "In5.Cu")
		(net "T10_BLAD3_TXD")
	)
	(segment
		(start 26.133552 -350.294448)
		(end 26.133552 -292.986206)
		(width 0.127)
		(layer "In5.Cu")
		(net "T10_BLAD3_TXD")
	)
	(segment
		(start 4.858258 -293.761668)
		(end 3.949954 -294.669972)
		(width 0.127)
		(layer "In5.Cu")
		(net "T10_BLAD3_TXD")
	)
	(segment
		(start 29.442664 -353.60356)
		(end 26.133552 -350.294448)
		(width 0.127)
		(layer "In5.Cu")
		(net "T10_BLAD3_TXD")
	)
	(segment
		(start 12.817094 -289.150298)
		(end 9.03732 -292.930072)
		(width 0.127)
		(layer "In5.Cu")
		(net "T10_BLAD3_TXD")
	)
	(segment
		(start 99.854004 -358.265476)
		(end 95.192088 -353.60356)
		(width 0.127)
		(layer "In5.Cu")
		(net "T10_BLAD3_TXD")
	)
	(segment
		(start 88.45423 -400.111214)
		(end 85.63991 -402.925534)
		(width 0.127)
		(layer "In5.Cu")
		(net "T10_BLAD3_TXD")
	)
	(segment
		(start 88.45423 -400.111214)
		(end 99.854004 -388.71144)
		(width 0.127)
		(layer "In5.Cu")
		(net "T10_BLAD3_TXD")
	)
	(segment
		(start 7.286244 -293.761668)
		(end 4.858258 -293.761668)
		(width 0.127)
		(layer "In5.Cu")
		(net "T10_BLAD3_TXD")
	)
	(segment
		(start 85.63991 -402.925534)
		(end 85.63991 -406.32507)
		(width 0.127)
		(layer "In5.Cu")
		(net "T10_BLAD3_TXD")
	)
	(segment
		(start 8.11784 -292.930072)
		(end 7.286244 -293.761668)
		(width 0.127)
		(layer "In5.Cu")
		(net "T10_BLAD3_TXD")
	)
	(via
		(at 87.224108 -399.30832)
		(size 0.508)
		(drill 0.254)
		(layers "F.Cu" "B.Cu")
		(net "T10_BLAD2_RXD")
	)
	(segment
		(start 28.979114 -354.378006)
		(end 94.871032 -354.378006)
		(width 0.127)
		(layer "In5.Cu")
		(net "T10_BLAD2_RXD")
	)
	(segment
		(start 7.037324 -295.790112)
		(end 7.920482 -294.906954)
		(width 0.127)
		(layer "In5.Cu")
		(net "T10_BLAD2_RXD")
	)
	(segment
		(start 6.280404 -295.790112)
		(end 7.037324 -295.790112)
		(width 0.127)
		(layer "In5.Cu")
		(net "T10_BLAD2_RXD")
	)
	(segment
		(start 83.902296 -409.405836)
		(end 83.902296 -402.630132)
		(width 0.127)
		(layer "In5.Cu")
		(net "T10_BLAD2_RXD")
	)
	(segment
		(start 85.047328 -410.550868)
		(end 83.902296 -409.405836)
		(width 0.127)
		(layer "In5.Cu")
		(net "T10_BLAD2_RXD")
	)
	(segment
		(start 3.949954 -298.120562)
		(end 6.280404 -295.790112)
		(width 0.127)
		(layer "In5.Cu")
		(net "T10_BLAD2_RXD")
	)
	(segment
		(start 99.079558 -387.45287)
		(end 87.224108 -399.30832)
		(width 0.127)
		(layer "In5.Cu")
		(net "T10_BLAD2_RXD")
	)
	(segment
		(start 91.98991 -407.59507)
		(end 91.98991 -408.800808)
		(width 0.127)
		(layer "In5.Cu")
		(net "T10_BLAD2_RXD")
	)
	(segment
		(start 7.920482 -294.906954)
		(end 9.141206 -294.906954)
		(width 0.127)
		(layer "In5.Cu")
		(net "T10_BLAD2_RXD")
	)
	(segment
		(start 83.902296 -402.630132)
		(end 87.224108 -399.30832)
		(width 0.127)
		(layer "In5.Cu")
		(net "T10_BLAD2_RXD")
	)
	(segment
		(start 21.47443 -290.519866)
		(end 23.978362 -293.023798)
		(width 0.127)
		(layer "In5.Cu")
		(net "T10_BLAD2_RXD")
	)
	(segment
		(start 90.23985 -410.550868)
		(end 85.047328 -410.550868)
		(width 0.127)
		(layer "In5.Cu")
		(net "T10_BLAD2_RXD")
	)
	(segment
		(start 94.871032 -354.378006)
		(end 99.079558 -358.586532)
		(width 0.127)
		(layer "In5.Cu")
		(net "T10_BLAD2_RXD")
	)
	(segment
		(start 3.949954 -298.669964)
		(end 3.949954 -298.120562)
		(width 0.127)
		(layer "In5.Cu")
		(net "T10_BLAD2_RXD")
	)
	(segment
		(start 99.079558 -358.586532)
		(end 99.079558 -387.45287)
		(width 0.127)
		(layer "In5.Cu")
		(net "T10_BLAD2_RXD")
	)
	(segment
		(start 91.98991 -408.800808)
		(end 90.23985 -410.550868)
		(width 0.127)
		(layer "In5.Cu")
		(net "T10_BLAD2_RXD")
	)
	(segment
		(start 13.528294 -290.519866)
		(end 21.47443 -290.519866)
		(width 0.127)
		(layer "In5.Cu")
		(net "T10_BLAD2_RXD")
	)
	(segment
		(start 23.978362 -349.377254)
		(end 28.979114 -354.378006)
		(width 0.127)
		(layer "In5.Cu")
		(net "T10_BLAD2_RXD")
	)
	(segment
		(start 9.141206 -294.906954)
		(end 13.528294 -290.519866)
		(width 0.127)
		(layer "In5.Cu")
		(net "T10_BLAD2_RXD")
	)
	(segment
		(start 23.978362 -293.023798)
		(end 23.978362 -349.377254)
		(width 0.127)
		(layer "In5.Cu")
		(net "T10_BLAD2_RXD")
	)
	(via
		(at 91.696794 -398.49806)
		(size 0.508)
		(drill 0.254)
		(layers "F.Cu" "B.Cu")
		(net "T10_BLAD4_TXD")
	)
	(segment
		(start 26.89987 -291.352986)
		(end 26.89987 -350.09074)
		(width 0.127)
		(layer "In5.Cu")
		(net "T10_BLAD4_TXD")
	)
	(segment
		(start 9.372092 -290.771834)
		(end 12.442444 -287.701482)
		(width 0.127)
		(layer "In5.Cu")
		(net "T10_BLAD4_TXD")
	)
	(segment
		(start 23.248366 -287.701482)
		(end 26.89987 -291.352986)
		(width 0.127)
		(layer "In5.Cu")
		(net "T10_BLAD4_TXD")
	)
	(segment
		(start 90.71991 -406.32507)
		(end 90.71991 -399.474944)
		(width 0.127)
		(layer "In5.Cu")
		(net "T10_BLAD4_TXD")
	)
	(segment
		(start 95.509842 -352.837242)
		(end 100.620322 -357.947722)
		(width 0.127)
		(layer "In5.Cu")
		(net "T10_BLAD4_TXD")
	)
	(segment
		(start 26.89987 -350.09074)
		(end 29.646372 -352.837242)
		(width 0.127)
		(layer "In5.Cu")
		(net "T10_BLAD4_TXD")
	)
	(segment
		(start 4.81584 -291.80409)
		(end 7.098284 -291.80409)
		(width 0.127)
		(layer "In5.Cu")
		(net "T10_BLAD4_TXD")
	)
	(segment
		(start 29.646372 -352.837242)
		(end 95.509842 -352.837242)
		(width 0.127)
		(layer "In5.Cu")
		(net "T10_BLAD4_TXD")
	)
	(segment
		(start 7.098284 -291.80409)
		(end 8.13054 -290.771834)
		(width 0.127)
		(layer "In5.Cu")
		(net "T10_BLAD4_TXD")
	)
	(segment
		(start 3.949954 -292.669976)
		(end 4.81584 -291.80409)
		(width 0.127)
		(layer "In5.Cu")
		(net "T10_BLAD4_TXD")
	)
	(segment
		(start 100.620322 -389.574532)
		(end 91.696794 -398.49806)
		(width 0.127)
		(layer "In5.Cu")
		(net "T10_BLAD4_TXD")
	)
	(segment
		(start 8.13054 -290.771834)
		(end 9.372092 -290.771834)
		(width 0.127)
		(layer "In5.Cu")
		(net "T10_BLAD4_TXD")
	)
	(segment
		(start 12.442444 -287.701482)
		(end 23.248366 -287.701482)
		(width 0.127)
		(layer "In5.Cu")
		(net "T10_BLAD4_TXD")
	)
	(segment
		(start 100.620322 -357.947722)
		(end 100.620322 -389.574532)
		(width 0.127)
		(layer "In5.Cu")
		(net "T10_BLAD4_TXD")
	)
	(segment
		(start 90.71991 -399.474944)
		(end 91.696794 -398.49806)
		(width 0.127)
		(layer "In5.Cu")
		(net "T10_BLAD4_TXD")
	)
	(via
		(at 82.22488 -399.014696)
		(size 0.508)
		(drill 0.254)
		(layers "F.Cu" "B.Cu")
		(net "T10_BLAD3_EN")
	)
	(segment
		(start 21.641054 -352.185986)
		(end 21.641054 -310.409082)
		(width 0.127)
		(layer "In2.Cu")
		(net "T10_BLAD3_EN")
	)
	(segment
		(start 88.17991 -404.969726)
		(end 88.17991 -406.32507)
		(width 0.127)
		(layer "In2.Cu")
		(net "T10_BLAD3_EN")
	)
	(segment
		(start 82.22488 -399.014696)
		(end 88.17991 -404.969726)
		(width 0.127)
		(layer "In2.Cu")
		(net "T10_BLAD3_EN")
	)
	(segment
		(start 42.223182 -359.106724)
		(end 39.083234 -355.966776)
		(width 0.127)
		(layer "In2.Cu")
		(net "T10_BLAD3_EN")
	)
	(segment
		(start 39.083234 -355.966776)
		(end 25.421844 -355.966776)
		(width 0.127)
		(layer "In2.Cu")
		(net "T10_BLAD3_EN")
	)
	(segment
		(start 4.952238 -303.035716)
		(end 4.318 -303.669954)
		(width 0.127)
		(layer "In2.Cu")
		(net "T10_BLAD3_EN")
	)
	(segment
		(start 25.421844 -355.966776)
		(end 21.641054 -352.185986)
		(width 0.127)
		(layer "In2.Cu")
		(net "T10_BLAD3_EN")
	)
	(segment
		(start 4.952238 -302.683926)
		(end 4.952238 -303.035716)
		(width 0.127)
		(layer "In2.Cu")
		(net "T10_BLAD3_EN")
	)
	(segment
		(start 5.812536 -301.823628)
		(end 4.952238 -302.683926)
		(width 0.127)
		(layer "In2.Cu")
		(net "T10_BLAD3_EN")
	)
	(segment
		(start 83.495134 -360.308652)
		(end 82.293206 -359.106724)
		(width 0.127)
		(layer "In2.Cu")
		(net "T10_BLAD3_EN")
	)
	(segment
		(start 4.318 -303.669954)
		(end 1.949958 -303.669954)
		(width 0.127)
		(layer "In2.Cu")
		(net "T10_BLAD3_EN")
	)
	(segment
		(start 82.293206 -359.106724)
		(end 42.223182 -359.106724)
		(width 0.127)
		(layer "In2.Cu")
		(net "T10_BLAD3_EN")
	)
	(segment
		(start 8.03783 -300.894242)
		(end 7.108444 -301.823628)
		(width 0.127)
		(layer "In2.Cu")
		(net "T10_BLAD3_EN")
	)
	(segment
		(start 83.495134 -397.744442)
		(end 83.495134 -360.308652)
		(width 0.127)
		(layer "In2.Cu")
		(net "T10_BLAD3_EN")
	)
	(segment
		(start 21.641054 -310.409082)
		(end 12.126214 -300.894242)
		(width 0.127)
		(layer "In2.Cu")
		(net "T10_BLAD3_EN")
	)
	(segment
		(start 12.126214 -300.894242)
		(end 8.03783 -300.894242)
		(width 0.127)
		(layer "In2.Cu")
		(net "T10_BLAD3_EN")
	)
	(segment
		(start 7.108444 -301.823628)
		(end 5.812536 -301.823628)
		(width 0.127)
		(layer "In2.Cu")
		(net "T10_BLAD3_EN")
	)
	(segment
		(start 82.22488 -399.014696)
		(end 83.495134 -397.744442)
		(width 0.127)
		(layer "In2.Cu")
		(net "T10_BLAD3_EN")
	)
	(via
		(at 88.57234 -398.827498)
		(size 0.508)
		(drill 0.254)
		(layers "F.Cu" "B.Cu")
		(net "T10_BLAD2_TXD")
	)
	(segment
		(start 7.629144 -294.47998)
		(end 6.65988 -295.449244)
		(width 0.127)
		(layer "In5.Cu")
		(net "T10_BLAD2_TXD")
	)
	(segment
		(start 84.505038 -402.8948)
		(end 84.505038 -409.156154)
		(width 0.127)
		(layer "In5.Cu")
		(net "T10_BLAD2_TXD")
	)
	(segment
		(start 95.000572 -353.98329)
		(end 29.078682 -353.98329)
		(width 0.127)
		(layer "In5.Cu")
		(net "T10_BLAD2_TXD")
	)
	(segment
		(start 89.636854 -409.948126)
		(end 90.71991 -408.86507)
		(width 0.127)
		(layer "In5.Cu")
		(net "T10_BLAD2_TXD")
	)
	(segment
		(start 99.450144 -358.432862)
		(end 95.000572 -353.98329)
		(width 0.127)
		(layer "In5.Cu")
		(net "T10_BLAD2_TXD")
	)
	(segment
		(start 2.69748 -296.922444)
		(end 1.949958 -297.669966)
		(width 0.127)
		(layer "In5.Cu")
		(net "T10_BLAD2_TXD")
	)
	(segment
		(start 24.976582 -349.88119)
		(end 24.976582 -293.465504)
		(width 0.127)
		(layer "In5.Cu")
		(net "T10_BLAD2_TXD")
	)
	(segment
		(start 29.078682 -353.98329)
		(end 24.976582 -349.88119)
		(width 0.127)
		(layer "In5.Cu")
		(net "T10_BLAD2_TXD")
	)
	(segment
		(start 21.489924 -289.978846)
		(end 13.525754 -289.978846)
		(width 0.127)
		(layer "In5.Cu")
		(net "T10_BLAD2_TXD")
	)
	(segment
		(start 9.02462 -294.47998)
		(end 7.629144 -294.47998)
		(width 0.127)
		(layer "In5.Cu")
		(net "T10_BLAD2_TXD")
	)
	(segment
		(start 2.999994 -296.612564)
		(end 2.69748 -296.915078)
		(width 0.127)
		(layer "In5.Cu")
		(net "T10_BLAD2_TXD")
	)
	(segment
		(start 3.93319 -295.449244)
		(end 2.999994 -296.38244)
		(width 0.127)
		(layer "In5.Cu")
		(net "T10_BLAD2_TXD")
	)
	(segment
		(start 2.999994 -296.38244)
		(end 2.999994 -296.612564)
		(width 0.127)
		(layer "In5.Cu")
		(net "T10_BLAD2_TXD")
	)
	(segment
		(start 88.57234 -398.827498)
		(end 84.505038 -402.8948)
		(width 0.127)
		(layer "In5.Cu")
		(net "T10_BLAD2_TXD")
	)
	(segment
		(start 88.57234 -398.827498)
		(end 99.450144 -387.949694)
		(width 0.127)
		(layer "In5.Cu")
		(net "T10_BLAD2_TXD")
	)
	(segment
		(start 13.525754 -289.978846)
		(end 9.02462 -294.47998)
		(width 0.127)
		(layer "In5.Cu")
		(net "T10_BLAD2_TXD")
	)
	(segment
		(start 6.65988 -295.449244)
		(end 3.93319 -295.449244)
		(width 0.127)
		(layer "In5.Cu")
		(net "T10_BLAD2_TXD")
	)
	(segment
		(start 24.976582 -293.465504)
		(end 21.489924 -289.978846)
		(width 0.127)
		(layer "In5.Cu")
		(net "T10_BLAD2_TXD")
	)
	(segment
		(start 85.29701 -409.948126)
		(end 89.636854 -409.948126)
		(width 0.127)
		(layer "In5.Cu")
		(net "T10_BLAD2_TXD")
	)
	(segment
		(start 2.69748 -296.915078)
		(end 2.69748 -296.922444)
		(width 0.127)
		(layer "In5.Cu")
		(net "T10_BLAD2_TXD")
	)
	(segment
		(start 99.450144 -387.949694)
		(end 99.450144 -358.432862)
		(width 0.127)
		(layer "In5.Cu")
		(net "T10_BLAD2_TXD")
	)
	(segment
		(start 84.505038 -409.156154)
		(end 85.29701 -409.948126)
		(width 0.127)
		(layer "In5.Cu")
		(net "T10_BLAD2_TXD")
	)
	(via
		(at 24.51354 -354.427028)
		(size 0.508)
		(drill 0.254)
		(layers "F.Cu" "B.Cu")
		(net "T9_BLAD1_EN")
	)
	(segment
		(start 44.217844 -358.75468)
		(end 39.654988 -358.75468)
		(width 0.127)
		(layer "In5.Cu")
		(net "T9_BLAD1_EN")
	)
	(segment
		(start 8.449818 -301.669958)
		(end 9.978136 -303.198276)
		(width 0.127)
		(layer "In5.Cu")
		(net "T9_BLAD1_EN")
	)
	(segment
		(start 80.44053 -357.232712)
		(end 45.739812 -357.232712)
		(width 0.127)
		(layer "In5.Cu")
		(net "T9_BLAD1_EN")
	)
	(segment
		(start 22.284182 -350.574356)
		(end 22.284182 -352.19767)
		(width 0.127)
		(layer "In5.Cu")
		(net "T9_BLAD1_EN")
	)
	(segment
		(start 84.524088 -361.31627)
		(end 80.44053 -357.232712)
		(width 0.127)
		(layer "In5.Cu")
		(net "T9_BLAD1_EN")
	)
	(segment
		(start 22.284182 -352.19767)
		(end 24.51354 -354.427028)
		(width 0.127)
		(layer "In5.Cu")
		(net "T9_BLAD1_EN")
	)
	(segment
		(start 9.978136 -303.329848)
		(end 21.888196 -315.239908)
		(width 0.127)
		(layer "In5.Cu")
		(net "T9_BLAD1_EN")
	)
	(segment
		(start 88.17991 -364.41507)
		(end 86.846664 -364.41507)
		(width 0.127)
		(layer "In5.Cu")
		(net "T9_BLAD1_EN")
	)
	(segment
		(start 21.888196 -350.17837)
		(end 22.284182 -350.574356)
		(width 0.127)
		(layer "In5.Cu")
		(net "T9_BLAD1_EN")
	)
	(segment
		(start 45.739812 -357.232712)
		(end 44.217844 -358.75468)
		(width 0.127)
		(layer "In5.Cu")
		(net "T9_BLAD1_EN")
	)
	(segment
		(start 27.228546 -357.142034)
		(end 24.51354 -354.427028)
		(width 0.127)
		(layer "In5.Cu")
		(net "T9_BLAD1_EN")
	)
	(segment
		(start 84.524088 -362.092494)
		(end 84.524088 -361.31627)
		(width 0.127)
		(layer "In5.Cu")
		(net "T9_BLAD1_EN")
	)
	(segment
		(start 39.654988 -358.75468)
		(end 38.042342 -357.142034)
		(width 0.127)
		(layer "In5.Cu")
		(net "T9_BLAD1_EN")
	)
	(segment
		(start 21.888196 -315.239908)
		(end 21.888196 -350.17837)
		(width 0.127)
		(layer "In5.Cu")
		(net "T9_BLAD1_EN")
	)
	(segment
		(start 9.978136 -303.198276)
		(end 9.978136 -303.329848)
		(width 0.127)
		(layer "In5.Cu")
		(net "T9_BLAD1_EN")
	)
	(segment
		(start 86.846664 -364.41507)
		(end 84.524088 -362.092494)
		(width 0.127)
		(layer "In5.Cu")
		(net "T9_BLAD1_EN")
	)
	(segment
		(start 38.042342 -357.142034)
		(end 27.228546 -357.142034)
		(width 0.127)
		(layer "In5.Cu")
		(net "T9_BLAD1_EN")
	)
	(via
		(at 89.07526 -356.423722)
		(size 0.508)
		(drill 0.254)
		(layers "F.Cu" "B.Cu")
		(net "T9_BLAD1_TXD")
	)
	(segment
		(start 87.41537 -354.754688)
		(end 89.07526 -356.414578)
		(width 0.127)
		(layer "In5.Cu")
		(net "T9_BLAD1_TXD")
	)
	(segment
		(start 90.949018 -365.567214)
		(end 86.792054 -365.567214)
		(width 0.127)
		(layer "In5.Cu")
		(net "T9_BLAD1_TXD")
	)
	(segment
		(start 23.573994 -313.327034)
		(end 23.573994 -349.46717)
		(width 0.127)
		(layer "In5.Cu")
		(net "T9_BLAD1_TXD")
	)
	(segment
		(start 89.07526 -356.414578)
		(end 92.89034 -360.229658)
		(width 0.127)
		(layer "In5.Cu")
		(net "T9_BLAD1_TXD")
	)
	(segment
		(start 92.89034 -363.625892)
		(end 90.949018 -365.567214)
		(width 0.127)
		(layer "In5.Cu")
		(net "T9_BLAD1_TXD")
	)
	(segment
		(start 86.792054 -365.567214)
		(end 85.63991 -364.41507)
		(width 0.127)
		(layer "In5.Cu")
		(net "T9_BLAD1_TXD")
	)
	(segment
		(start 92.89034 -360.229658)
		(end 92.89034 -363.625892)
		(width 0.127)
		(layer "In5.Cu")
		(net "T9_BLAD1_TXD")
	)
	(segment
		(start 10.577068 -297.79722)
		(end 10.577068 -298.72432)
		(width 0.127)
		(layer "In5.Cu")
		(net "T9_BLAD1_TXD")
	)
	(segment
		(start 13.433298 -301.58055)
		(end 13.433298 -303.186338)
		(width 0.127)
		(layer "In5.Cu")
		(net "T9_BLAD1_TXD")
	)
	(segment
		(start 29.424122 -355.317298)
		(end 39.350696 -355.317298)
		(width 0.127)
		(layer "In5.Cu")
		(net "T9_BLAD1_TXD")
	)
	(segment
		(start 43.236896 -354.754688)
		(end 87.41537 -354.754688)
		(width 0.127)
		(layer "In5.Cu")
		(net "T9_BLAD1_TXD")
	)
	(segment
		(start 13.433298 -303.186338)
		(end 23.573994 -313.327034)
		(width 0.127)
		(layer "In5.Cu")
		(net "T9_BLAD1_TXD")
	)
	(segment
		(start 89.07526 -356.423722)
		(end 89.07526 -356.414578)
		(width 0.127)
		(layer "In5.Cu")
		(net "T9_BLAD1_TXD")
	)
	(segment
		(start 23.573994 -349.46717)
		(end 29.424122 -355.317298)
		(width 0.127)
		(layer "In5.Cu")
		(net "T9_BLAD1_TXD")
	)
	(segment
		(start 8.449818 -295.66997)
		(end 10.577068 -297.79722)
		(width 0.127)
		(layer "In5.Cu")
		(net "T9_BLAD1_TXD")
	)
	(segment
		(start 10.577068 -298.72432)
		(end 13.433298 -301.58055)
		(width 0.127)
		(layer "In5.Cu")
		(net "T9_BLAD1_TXD")
	)
	(segment
		(start 39.350696 -355.317298)
		(end 40.275002 -356.241604)
		(width 0.127)
		(layer "In5.Cu")
		(net "T9_BLAD1_TXD")
	)
	(segment
		(start 41.74998 -356.241604)
		(end 43.236896 -354.754688)
		(width 0.127)
		(layer "In5.Cu")
		(net "T9_BLAD1_TXD")
	)
	(segment
		(start 40.275002 -356.241604)
		(end 41.74998 -356.241604)
		(width 0.127)
		(layer "In5.Cu")
		(net "T9_BLAD1_TXD")
	)
	(via
		(at 87.40902 -356.02418)
		(size 0.508)
		(drill 0.254)
		(layers "F.Cu" "B.Cu")
		(net "T9_BLAD4_RXD")
	)
	(segment
		(start 21.196808 -288.411412)
		(end 24.730964 -291.945568)
		(width 0.127)
		(layer "In2.Cu")
		(net "T9_BLAD4_RXD")
	)
	(segment
		(start 83.9089 -355.178106)
		(end 86.562946 -355.178106)
		(width 0.127)
		(layer "In2.Cu")
		(net "T9_BLAD4_RXD")
	)
	(segment
		(start 82.20837 -355.836728)
		(end 83.250278 -355.836728)
		(width 0.127)
		(layer "In2.Cu")
		(net "T9_BLAD4_RXD")
	)
	(segment
		(start 24.730964 -348.557342)
		(end 29.036772 -352.86315)
		(width 0.127)
		(layer "In2.Cu")
		(net "T9_BLAD4_RXD")
	)
	(segment
		(start 81.549748 -355.178106)
		(end 82.20837 -355.836728)
		(width 0.127)
		(layer "In2.Cu")
		(net "T9_BLAD4_RXD")
	)
	(segment
		(start 45.899832 -355.178106)
		(end 81.549748 -355.178106)
		(width 0.127)
		(layer "In2.Cu")
		(net "T9_BLAD4_RXD")
	)
	(segment
		(start 24.730964 -291.945568)
		(end 24.730964 -348.557342)
		(width 0.127)
		(layer "In2.Cu")
		(net "T9_BLAD4_RXD")
	)
	(segment
		(start 8.449818 -289.669728)
		(end 9.727438 -289.669728)
		(width 0.127)
		(layer "In2.Cu")
		(net "T9_BLAD4_RXD")
	)
	(segment
		(start 29.036772 -352.86315)
		(end 43.584876 -352.86315)
		(width 0.127)
		(layer "In2.Cu")
		(net "T9_BLAD4_RXD")
	)
	(segment
		(start 87.40902 -356.02418)
		(end 91.98991 -360.60507)
		(width 0.127)
		(layer "In2.Cu")
		(net "T9_BLAD4_RXD")
	)
	(segment
		(start 86.562946 -355.178106)
		(end 87.40902 -356.02418)
		(width 0.127)
		(layer "In2.Cu")
		(net "T9_BLAD4_RXD")
	)
	(segment
		(start 83.250278 -355.836728)
		(end 83.9089 -355.178106)
		(width 0.127)
		(layer "In2.Cu")
		(net "T9_BLAD4_RXD")
	)
	(segment
		(start 43.584876 -352.86315)
		(end 45.899832 -355.178106)
		(width 0.127)
		(layer "In2.Cu")
		(net "T9_BLAD4_RXD")
	)
	(segment
		(start 10.985754 -288.411412)
		(end 21.196808 -288.411412)
		(width 0.127)
		(layer "In2.Cu")
		(net "T9_BLAD4_RXD")
	)
	(segment
		(start 9.727438 -289.669728)
		(end 10.985754 -288.411412)
		(width 0.127)
		(layer "In2.Cu")
		(net "T9_BLAD4_RXD")
	)
	(via
		(at 43.269154 -355.936296)
		(size 0.508)
		(drill 0.254)
		(layers "F.Cu" "B.Cu")
		(net "T9_BLAD3_TXD")
	)
	(segment
		(start 23.740364 -349.228918)
		(end 28.431998 -353.920552)
		(width 0.127)
		(layer "In2.Cu")
		(net "T9_BLAD3_TXD")
	)
	(segment
		(start 41.24833 -353.920552)
		(end 43.269154 -355.941376)
		(width 0.127)
		(layer "In2.Cu")
		(net "T9_BLAD3_TXD")
	)
	(segment
		(start 44.703746 -357.375968)
		(end 43.269154 -355.941376)
		(width 0.127)
		(layer "In2.Cu")
		(net "T9_BLAD3_TXD")
	)
	(segment
		(start 20.74291 -289.625278)
		(end 23.740364 -292.622732)
		(width 0.127)
		(layer "In2.Cu")
		(net "T9_BLAD3_TXD")
	)
	(segment
		(start 6.449822 -290.66998)
		(end 8.358632 -292.57879)
		(width 0.127)
		(layer "In2.Cu")
		(net "T9_BLAD3_TXD")
	)
	(segment
		(start 85.63991 -361.87507)
		(end 85.63991 -359.906824)
		(width 0.127)
		(layer "In2.Cu")
		(net "T9_BLAD3_TXD")
	)
	(segment
		(start 28.431998 -353.920552)
		(end 41.24833 -353.920552)
		(width 0.127)
		(layer "In2.Cu")
		(net "T9_BLAD3_TXD")
	)
	(segment
		(start 12.288774 -289.625278)
		(end 20.74291 -289.625278)
		(width 0.127)
		(layer "In2.Cu")
		(net "T9_BLAD3_TXD")
	)
	(segment
		(start 23.740364 -292.622732)
		(end 23.740364 -349.228918)
		(width 0.127)
		(layer "In2.Cu")
		(net "T9_BLAD3_TXD")
	)
	(segment
		(start 8.358632 -292.57879)
		(end 9.335262 -292.57879)
		(width 0.127)
		(layer "In2.Cu")
		(net "T9_BLAD3_TXD")
	)
	(segment
		(start 9.335262 -292.57879)
		(end 12.288774 -289.625278)
		(width 0.127)
		(layer "In2.Cu")
		(net "T9_BLAD3_TXD")
	)
	(segment
		(start 83.109054 -357.375968)
		(end 44.703746 -357.375968)
		(width 0.127)
		(layer "In2.Cu")
		(net "T9_BLAD3_TXD")
	)
	(segment
		(start 85.63991 -359.906824)
		(end 83.109054 -357.375968)
		(width 0.127)
		(layer "In2.Cu")
		(net "T9_BLAD3_TXD")
	)
	(segment
		(start 43.269154 -355.941376)
		(end 43.269154 -355.936296)
		(width 0.127)
		(layer "In2.Cu")
		(net "T9_BLAD3_TXD")
	)
	(via
		(at 41.665398 -355.657404)
		(size 0.508)
		(drill 0.254)
		(layers "F.Cu" "B.Cu")
		(net "T9_BLAD2_TXD")
	)
	(segment
		(start 84.86521 -359.59923)
		(end 84.86521 -364.979458)
		(width 0.127)
		(layer "In2.Cu")
		(net "T9_BLAD2_TXD")
	)
	(segment
		(start 41.665398 -355.657404)
		(end 43.74134 -357.733346)
		(width 0.127)
		(layer "In2.Cu")
		(net "T9_BLAD2_TXD")
	)
	(segment
		(start 10.069068 -293.66972)
		(end 13.749274 -289.989514)
		(width 0.127)
		(layer "In2.Cu")
		(net "T9_BLAD2_TXD")
	)
	(segment
		(start 23.410164 -292.807644)
		(end 23.410164 -349.436436)
		(width 0.127)
		(layer "In2.Cu")
		(net "T9_BLAD2_TXD")
	)
	(segment
		(start 28.23337 -354.259642)
		(end 40.267636 -354.259642)
		(width 0.127)
		(layer "In2.Cu")
		(net "T9_BLAD2_TXD")
	)
	(segment
		(start 89.701116 -365.433864)
		(end 90.71991 -364.41507)
		(width 0.127)
		(layer "In2.Cu")
		(net "T9_BLAD2_TXD")
	)
	(segment
		(start 84.86521 -364.979458)
		(end 85.319616 -365.433864)
		(width 0.127)
		(layer "In2.Cu")
		(net "T9_BLAD2_TXD")
	)
	(segment
		(start 82.999326 -357.733346)
		(end 84.86521 -359.59923)
		(width 0.127)
		(layer "In2.Cu")
		(net "T9_BLAD2_TXD")
	)
	(segment
		(start 8.449818 -293.66972)
		(end 10.069068 -293.66972)
		(width 0.127)
		(layer "In2.Cu")
		(net "T9_BLAD2_TXD")
	)
	(segment
		(start 13.749274 -289.989514)
		(end 20.592034 -289.989514)
		(width 0.127)
		(layer "In2.Cu")
		(net "T9_BLAD2_TXD")
	)
	(segment
		(start 23.410164 -349.436436)
		(end 28.23337 -354.259642)
		(width 0.127)
		(layer "In2.Cu")
		(net "T9_BLAD2_TXD")
	)
	(segment
		(start 40.267636 -354.259642)
		(end 41.665398 -355.657404)
		(width 0.127)
		(layer "In2.Cu")
		(net "T9_BLAD2_TXD")
	)
	(segment
		(start 20.592034 -289.989514)
		(end 23.410164 -292.807644)
		(width 0.127)
		(layer "In2.Cu")
		(net "T9_BLAD2_TXD")
	)
	(segment
		(start 43.74134 -357.733346)
		(end 82.999326 -357.733346)
		(width 0.127)
		(layer "In2.Cu")
		(net "T9_BLAD2_TXD")
	)
	(segment
		(start 85.319616 -365.433864)
		(end 89.701116 -365.433864)
		(width 0.127)
		(layer "In2.Cu")
		(net "T9_BLAD2_TXD")
	)
	(via
		(at 85.000084 -355.804216)
		(size 0.508)
		(drill 0.254)
		(layers "F.Cu" "B.Cu")
		(net "T9_BLAD4_TXD")
	)
	(segment
		(start 24.400764 -348.80677)
		(end 28.792932 -353.198938)
		(width 0.127)
		(layer "In2.Cu")
		(net "T9_BLAD4_TXD")
	)
	(segment
		(start 90.71991 -360.563922)
		(end 90.71991 -361.87507)
		(width 0.127)
		(layer "In2.Cu")
		(net "T9_BLAD4_TXD")
	)
	(segment
		(start 81.412842 -355.508306)
		(end 82.071464 -356.166928)
		(width 0.127)
		(layer "In2.Cu")
		(net "T9_BLAD4_TXD")
	)
	(segment
		(start 85.000084 -355.804216)
		(end 85.960204 -355.804216)
		(width 0.127)
		(layer "In2.Cu")
		(net "T9_BLAD4_TXD")
	)
	(segment
		(start 45.541184 -355.508306)
		(end 81.412842 -355.508306)
		(width 0.127)
		(layer "In2.Cu")
		(net "T9_BLAD4_TXD")
	)
	(segment
		(start 28.792932 -353.198938)
		(end 43.231816 -353.198938)
		(width 0.127)
		(layer "In2.Cu")
		(net "T9_BLAD4_TXD")
	)
	(segment
		(start 84.637372 -356.166928)
		(end 85.000084 -355.804216)
		(width 0.127)
		(layer "In2.Cu")
		(net "T9_BLAD4_TXD")
	)
	(segment
		(start 8.24103 -290.461192)
		(end 9.657588 -290.461192)
		(width 0.127)
		(layer "In2.Cu")
		(net "T9_BLAD4_TXD")
	)
	(segment
		(start 11.36142 -288.75736)
		(end 21.045932 -288.75736)
		(width 0.127)
		(layer "In2.Cu")
		(net "T9_BLAD4_TXD")
	)
	(segment
		(start 6.449822 -288.669984)
		(end 8.24103 -290.461192)
		(width 0.127)
		(layer "In2.Cu")
		(net "T9_BLAD4_TXD")
	)
	(segment
		(start 9.657588 -290.461192)
		(end 11.36142 -288.75736)
		(width 0.127)
		(layer "In2.Cu")
		(net "T9_BLAD4_TXD")
	)
	(segment
		(start 43.231816 -353.198938)
		(end 45.541184 -355.508306)
		(width 0.127)
		(layer "In2.Cu")
		(net "T9_BLAD4_TXD")
	)
	(segment
		(start 21.045932 -288.75736)
		(end 24.400764 -292.112192)
		(width 0.127)
		(layer "In2.Cu")
		(net "T9_BLAD4_TXD")
	)
	(segment
		(start 82.071464 -356.166928)
		(end 84.637372 -356.166928)
		(width 0.127)
		(layer "In2.Cu")
		(net "T9_BLAD4_TXD")
	)
	(segment
		(start 85.960204 -355.804216)
		(end 90.71991 -360.563922)
		(width 0.127)
		(layer "In2.Cu")
		(net "T9_BLAD4_TXD")
	)
	(segment
		(start 24.400764 -292.112192)
		(end 24.400764 -348.80677)
		(width 0.127)
		(layer "In2.Cu")
		(net "T9_BLAD4_TXD")
	)
	(via
		(at 40.288972 -355.459792)
		(size 0.508)
		(drill 0.254)
		(layers "F.Cu" "B.Cu")
		(net "T9_BLAD2_RXD")
	)
	(segment
		(start 20.441158 -290.353496)
		(end 23.068026 -292.980364)
		(width 0.127)
		(layer "In2.Cu")
		(net "T9_BLAD2_RXD")
	)
	(segment
		(start 84.53501 -359.73639)
		(end 84.53501 -365.116618)
		(width 0.127)
		(layer "In2.Cu")
		(net "T9_BLAD2_RXD")
	)
	(segment
		(start 13.90015 -290.353496)
		(end 20.441158 -290.353496)
		(width 0.127)
		(layer "In2.Cu")
		(net "T9_BLAD2_RXD")
	)
	(segment
		(start 6.449822 -294.669972)
		(end 9.583674 -294.669972)
		(width 0.127)
		(layer "In2.Cu")
		(net "T9_BLAD2_RXD")
	)
	(segment
		(start 42.945304 -358.116124)
		(end 82.914744 -358.116124)
		(width 0.127)
		(layer "In2.Cu")
		(net "T9_BLAD2_RXD")
	)
	(segment
		(start 39.402766 -354.59543)
		(end 39.716456 -354.90912)
		(width 0.127)
		(layer "In2.Cu")
		(net "T9_BLAD2_RXD")
	)
	(segment
		(start 85.279484 -365.861092)
		(end 90.710004 -365.861092)
		(width 0.127)
		(layer "In2.Cu")
		(net "T9_BLAD2_RXD")
	)
	(segment
		(start 84.53501 -365.116618)
		(end 85.279484 -365.861092)
		(width 0.127)
		(layer "In2.Cu")
		(net "T9_BLAD2_RXD")
	)
	(segment
		(start 91.98991 -364.581186)
		(end 91.98991 -363.14507)
		(width 0.127)
		(layer "In2.Cu")
		(net "T9_BLAD2_RXD")
	)
	(segment
		(start 23.068026 -292.980364)
		(end 23.068026 -349.621856)
		(width 0.127)
		(layer "In2.Cu")
		(net "T9_BLAD2_RXD")
	)
	(segment
		(start 23.068026 -349.621856)
		(end 28.0416 -354.59543)
		(width 0.127)
		(layer "In2.Cu")
		(net "T9_BLAD2_RXD")
	)
	(segment
		(start 40.288972 -355.459792)
		(end 42.945304 -358.116124)
		(width 0.127)
		(layer "In2.Cu")
		(net "T9_BLAD2_RXD")
	)
	(segment
		(start 82.914744 -358.116124)
		(end 84.53501 -359.73639)
		(width 0.127)
		(layer "In2.Cu")
		(net "T9_BLAD2_RXD")
	)
	(segment
		(start 39.7383 -354.90912)
		(end 40.288972 -355.459792)
		(width 0.127)
		(layer "In2.Cu")
		(net "T9_BLAD2_RXD")
	)
	(segment
		(start 39.716456 -354.90912)
		(end 39.7383 -354.90912)
		(width 0.127)
		(layer "In2.Cu")
		(net "T9_BLAD2_RXD")
	)
	(segment
		(start 28.0416 -354.59543)
		(end 39.402766 -354.59543)
		(width 0.127)
		(layer "In2.Cu")
		(net "T9_BLAD2_RXD")
	)
	(segment
		(start 9.583674 -294.669972)
		(end 13.90015 -290.353496)
		(width 0.127)
		(layer "In2.Cu")
		(net "T9_BLAD2_RXD")
	)
	(segment
		(start 90.710004 -365.861092)
		(end 91.98991 -364.581186)
		(width 0.127)
		(layer "In2.Cu")
		(net "T9_BLAD2_RXD")
	)
	(via
		(at 82.711544 -355.374956)
		(size 0.508)
		(drill 0.254)
		(layers "F.Cu" "B.Cu")
		(net "T9_BLAD1_RXD")
	)
	(segment
		(start 85.166962 -357.089456)
		(end 87.275416 -357.089456)
		(width 0.127)
		(layer "In5.Cu")
		(net "T9_BLAD1_RXD")
	)
	(segment
		(start 91.618816 -362.383832)
		(end 90.06586 -363.936788)
		(width 0.127)
		(layer "In5.Cu")
		(net "T9_BLAD1_RXD")
	)
	(segment
		(start 87.765636 -363.43209)
		(end 87.478616 -363.14507)
		(width 0.127)
		(layer "In5.Cu")
		(net "T9_BLAD1_RXD")
	)
	(segment
		(start 23.208996 -313.563762)
		(end 13.007848 -303.362614)
		(width 0.127)
		(layer "In5.Cu")
		(net "T9_BLAD1_RXD")
	)
	(segment
		(start 39.063422 -355.682296)
		(end 29.260546 -355.682296)
		(width 0.127)
		(layer "In5.Cu")
		(net "T9_BLAD1_RXD")
	)
	(segment
		(start 13.007848 -302.039782)
		(end 9.900412 -298.932346)
		(width 0.127)
		(layer "In5.Cu")
		(net "T9_BLAD1_RXD")
	)
	(segment
		(start 82.711544 -355.374956)
		(end 83.452462 -355.374956)
		(width 0.127)
		(layer "In5.Cu")
		(net "T9_BLAD1_RXD")
	)
	(segment
		(start 82.711544 -355.374956)
		(end 44.854876 -355.374956)
		(width 0.127)
		(layer "In5.Cu")
		(net "T9_BLAD1_RXD")
	)
	(segment
		(start 29.260546 -355.682296)
		(end 23.208996 -349.630746)
		(width 0.127)
		(layer "In5.Cu")
		(net "T9_BLAD1_RXD")
	)
	(segment
		(start 43.421554 -356.808278)
		(end 40.189404 -356.808278)
		(width 0.127)
		(layer "In5.Cu")
		(net "T9_BLAD1_RXD")
	)
	(segment
		(start 87.275416 -357.089456)
		(end 91.618816 -361.432856)
		(width 0.127)
		(layer "In5.Cu")
		(net "T9_BLAD1_RXD")
	)
	(segment
		(start 83.452462 -355.374956)
		(end 85.166962 -357.089456)
		(width 0.127)
		(layer "In5.Cu")
		(net "T9_BLAD1_RXD")
	)
	(segment
		(start 90.06586 -363.936788)
		(end 88.978994 -363.936788)
		(width 0.127)
		(layer "In5.Cu")
		(net "T9_BLAD1_RXD")
	)
	(segment
		(start 8.69315 -296.669968)
		(end 6.449822 -296.669968)
		(width 0.127)
		(layer "In5.Cu")
		(net "T9_BLAD1_RXD")
	)
	(segment
		(start 40.189404 -356.808278)
		(end 39.063422 -355.682296)
		(width 0.127)
		(layer "In5.Cu")
		(net "T9_BLAD1_RXD")
	)
	(segment
		(start 23.208996 -349.630746)
		(end 23.208996 -313.563762)
		(width 0.127)
		(layer "In5.Cu")
		(net "T9_BLAD1_RXD")
	)
	(segment
		(start 44.854876 -355.374956)
		(end 43.421554 -356.808278)
		(width 0.127)
		(layer "In5.Cu")
		(net "T9_BLAD1_RXD")
	)
	(segment
		(start 88.474296 -363.43209)
		(end 87.765636 -363.43209)
		(width 0.127)
		(layer "In5.Cu")
		(net "T9_BLAD1_RXD")
	)
	(segment
		(start 13.007848 -303.362614)
		(end 13.007848 -302.039782)
		(width 0.127)
		(layer "In5.Cu")
		(net "T9_BLAD1_RXD")
	)
	(segment
		(start 88.978994 -363.936788)
		(end 88.474296 -363.43209)
		(width 0.127)
		(layer "In5.Cu")
		(net "T9_BLAD1_RXD")
	)
	(segment
		(start 87.478616 -363.14507)
		(end 86.90991 -363.14507)
		(width 0.127)
		(layer "In5.Cu")
		(net "T9_BLAD1_RXD")
	)
	(segment
		(start 9.900412 -298.932346)
		(end 9.900412 -297.87723)
		(width 0.127)
		(layer "In5.Cu")
		(net "T9_BLAD1_RXD")
	)
	(segment
		(start 9.900412 -297.87723)
		(end 8.69315 -296.669968)
		(width 0.127)
		(layer "In5.Cu")
		(net "T9_BLAD1_RXD")
	)
	(segment
		(start 91.618816 -361.432856)
		(end 91.618816 -362.383832)
		(width 0.127)
		(layer "In5.Cu")
		(net "T9_BLAD1_RXD")
	)
	(via
		(at 44.725082 -356.189534)
		(size 0.508)
		(drill 0.254)
		(layers "F.Cu" "B.Cu")
		(net "T9_BLAD3_RXD")
	)
	(segment
		(start 9.705848 -291.669724)
		(end 12.13104 -289.244532)
		(width 0.127)
		(layer "In2.Cu")
		(net "T9_BLAD3_RXD")
	)
	(segment
		(start 24.070564 -349.05823)
		(end 28.562046 -353.549712)
		(width 0.127)
		(layer "In2.Cu")
		(net "T9_BLAD3_RXD")
	)
	(segment
		(start 45.44949 -356.913942)
		(end 44.725082 -356.189534)
		(width 0.127)
		(layer "In2.Cu")
		(net "T9_BLAD3_RXD")
	)
	(segment
		(start 42.77995 -354.244402)
		(end 44.725082 -356.189534)
		(width 0.127)
		(layer "In2.Cu")
		(net "T9_BLAD3_RXD")
	)
	(segment
		(start 42.77995 -354.243894)
		(end 42.77995 -354.244402)
		(width 0.127)
		(layer "In2.Cu")
		(net "T9_BLAD3_RXD")
	)
	(segment
		(start 28.562046 -353.549712)
		(end 42.085768 -353.549712)
		(width 0.127)
		(layer "In2.Cu")
		(net "T9_BLAD3_RXD")
	)
	(segment
		(start 24.070564 -292.414452)
		(end 24.070564 -349.05823)
		(width 0.127)
		(layer "In2.Cu")
		(net "T9_BLAD3_RXD")
	)
	(segment
		(start 12.13104 -289.244532)
		(end 20.900644 -289.244532)
		(width 0.127)
		(layer "In2.Cu")
		(net "T9_BLAD3_RXD")
	)
	(segment
		(start 20.900644 -289.244532)
		(end 24.070564 -292.414452)
		(width 0.127)
		(layer "In2.Cu")
		(net "T9_BLAD3_RXD")
	)
	(segment
		(start 86.90991 -360.60507)
		(end 83.218782 -356.913942)
		(width 0.127)
		(layer "In2.Cu")
		(net "T9_BLAD3_RXD")
	)
	(segment
		(start 42.085768 -353.549712)
		(end 42.77995 -354.243894)
		(width 0.127)
		(layer "In2.Cu")
		(net "T9_BLAD3_RXD")
	)
	(segment
		(start 8.449818 -291.669724)
		(end 9.705848 -291.669724)
		(width 0.127)
		(layer "In2.Cu")
		(net "T9_BLAD3_RXD")
	)
	(segment
		(start 83.218782 -356.913942)
		(end 45.44949 -356.913942)
		(width 0.127)
		(layer "In2.Cu")
		(net "T9_BLAD3_RXD")
	)
	(via
		(at 79.802482 -356.469442)
		(size 0.508)
		(drill 0.254)
		(layers "F.Cu" "B.Cu")
		(net "T9_BLAD3_EN")
	)
	(segment
		(start 40.071802 -357.81361)
		(end 38.727634 -356.469442)
		(width 0.127)
		(layer "In5.Cu")
		(net "T9_BLAD3_EN")
	)
	(segment
		(start 45.668184 -356.469442)
		(end 44.324016 -357.81361)
		(width 0.127)
		(layer "In5.Cu")
		(net "T9_BLAD3_EN")
	)
	(segment
		(start 28.239974 -356.469442)
		(end 22.957282 -351.18675)
		(width 0.127)
		(layer "In5.Cu")
		(net "T9_BLAD3_EN")
	)
	(segment
		(start 83.053682 -356.469442)
		(end 79.802482 -356.469442)
		(width 0.127)
		(layer "In5.Cu")
		(net "T9_BLAD3_EN")
	)
	(segment
		(start 12.853924 -305.07559)
		(end 11.4935 -303.715166)
		(width 0.127)
		(layer "In5.Cu")
		(net "T9_BLAD3_EN")
	)
	(segment
		(start 22.957282 -351.18675)
		(end 22.957282 -350.313244)
		(width 0.127)
		(layer "In5.Cu")
		(net "T9_BLAD3_EN")
	)
	(segment
		(start 12.854178 -305.07559)
		(end 12.853924 -305.07559)
		(width 0.127)
		(layer "In5.Cu")
		(net "T9_BLAD3_EN")
	)
	(segment
		(start 86.215982 -358.287574)
		(end 84.871814 -358.287574)
		(width 0.127)
		(layer "In5.Cu")
		(net "T9_BLAD3_EN")
	)
	(segment
		(start 87.895684 -361.590844)
		(end 87.895684 -359.967276)
		(width 0.127)
		(layer "In5.Cu")
		(net "T9_BLAD3_EN")
	)
	(segment
		(start 38.727634 -356.469442)
		(end 28.239974 -356.469442)
		(width 0.127)
		(layer "In5.Cu")
		(net "T9_BLAD3_EN")
	)
	(segment
		(start 87.895684 -359.967276)
		(end 86.215982 -358.287574)
		(width 0.127)
		(layer "In5.Cu")
		(net "T9_BLAD3_EN")
	)
	(segment
		(start 22.957282 -350.313244)
		(end 22.548596 -349.904558)
		(width 0.127)
		(layer "In5.Cu")
		(net "T9_BLAD3_EN")
	)
	(segment
		(start 11.4935 -302.713644)
		(end 8.449818 -299.669962)
		(width 0.127)
		(layer "In5.Cu")
		(net "T9_BLAD3_EN")
	)
	(segment
		(start 22.548596 -314.770008)
		(end 12.854178 -305.07559)
		(width 0.127)
		(layer "In5.Cu")
		(net "T9_BLAD3_EN")
	)
	(segment
		(start 79.802482 -356.469442)
		(end 45.668184 -356.469442)
		(width 0.127)
		(layer "In5.Cu")
		(net "T9_BLAD3_EN")
	)
	(segment
		(start 44.324016 -357.81361)
		(end 40.071802 -357.81361)
		(width 0.127)
		(layer "In5.Cu")
		(net "T9_BLAD3_EN")
	)
	(segment
		(start 84.871814 -358.287574)
		(end 83.053682 -356.469442)
		(width 0.127)
		(layer "In5.Cu")
		(net "T9_BLAD3_EN")
	)
	(segment
		(start 22.548596 -349.904558)
		(end 22.548596 -314.770008)
		(width 0.127)
		(layer "In5.Cu")
		(net "T9_BLAD3_EN")
	)
	(segment
		(start 88.17991 -361.87507)
		(end 87.895684 -361.590844)
		(width 0.127)
		(layer "In5.Cu")
		(net "T9_BLAD3_EN")
	)
	(segment
		(start 11.4935 -303.715166)
		(end 11.4935 -302.713644)
		(width 0.127)
		(layer "In5.Cu")
		(net "T9_BLAD3_EN")
	)
	(segment
		(start 9.862566 -223.252538)
		(end 9.862566 -222.494094)
		(width 0.1524)
		(layer "F.Cu")
		(net "I2C_PSU1_SDA")
	)
	(segment
		(start 6.880352 -220.82887)
		(end 6.269482 -220.82887)
		(width 0.1524)
		(layer "F.Cu")
		(net "I2C_PSU1_SDA")
	)
	(segment
		(start 6.269482 -220.82887)
		(end 5.047996 -219.607384)
		(width 0.1524)
		(layer "F.Cu")
		(net "I2C_PSU1_SDA")
	)
	(segment
		(start 5.047996 -218.769692)
		(end 3.948938 -217.670634)
		(width 0.1524)
		(layer "F.Cu")
		(net "I2C_PSU1_SDA")
	)
	(segment
		(start 9.862566 -222.494094)
		(end 9.03732 -221.668848)
		(width 0.1524)
		(layer "F.Cu")
		(net "I2C_PSU1_SDA")
	)
	(segment
		(start 23.528782 -230.480616)
		(end 17.090644 -230.480616)
		(width 0.1524)
		(layer "F.Cu")
		(net "I2C_PSU1_SDA")
	)
	(segment
		(start 17.090644 -230.480616)
		(end 9.862566 -223.252538)
		(width 0.1524)
		(layer "F.Cu")
		(net "I2C_PSU1_SDA")
	)
	(segment
		(start 5.047996 -219.607384)
		(end 5.047996 -218.769692)
		(width 0.1524)
		(layer "F.Cu")
		(net "I2C_PSU1_SDA")
	)
	(segment
		(start 9.03732 -221.668848)
		(end 7.72033 -221.668848)
		(width 0.1524)
		(layer "F.Cu")
		(net "I2C_PSU1_SDA")
	)
	(segment
		(start 7.72033 -221.668848)
		(end 6.880352 -220.82887)
		(width 0.1524)
		(layer "F.Cu")
		(net "I2C_PSU1_SDA")
	)
	(via
		(at 23.528782 -230.480616)
		(size 0.508)
		(drill 0.254)
		(layers "F.Cu" "B.Cu")
		(net "I2C_PSU1_SDA")
	)
	(segment
		(start 37.081206 -6.13156)
		(end 37.081206 -17.185386)
		(width 0.1524)
		(layer "B.Cu")
		(net "I2C_PSU1_SDA")
	)
	(segment
		(start 25.418034 -20.823428)
		(end 25.418034 -84.846668)
		(width 0.1524)
		(layer "B.Cu")
		(net "I2C_PSU1_SDA")
	)
	(segment
		(start 35.665918 -18.600674)
		(end 27.640788 -18.600674)
		(width 0.1524)
		(layer "B.Cu")
		(net "I2C_PSU1_SDA")
	)
	(segment
		(start 36.787836 -94.238064)
		(end 35.53968 -92.989908)
		(width 0.1524)
		(layer "B.Cu")
		(net "I2C_PSU1_SDA")
	)
	(segment
		(start 33.085786 -181.073806)
		(end 24.93264 -172.92066)
		(width 0.1524)
		(layer "B.Cu")
		(net "I2C_PSU1_SDA")
	)
	(segment
		(start 33.561274 -92.989908)
		(end 35.53968 -92.989908)
		(width 0.1524)
		(layer "B.Cu")
		(net "I2C_PSU1_SDA")
	)
	(segment
		(start 37.081206 -17.185386)
		(end 35.665918 -18.600674)
		(width 0.1524)
		(layer "B.Cu")
		(net "I2C_PSU1_SDA")
	)
	(segment
		(start 23.833582 -204.161898)
		(end 30.04439 -197.95109)
		(width 0.1524)
		(layer "B.Cu")
		(net "I2C_PSU1_SDA")
	)
	(segment
		(start 36.12642 -107.000802)
		(end 36.787836 -106.339386)
		(width 0.1524)
		(layer "B.Cu")
		(net "I2C_PSU1_SDA")
	)
	(segment
		(start 23.833582 -230.175816)
		(end 23.833582 -204.161898)
		(width 0.1524)
		(layer "B.Cu")
		(net "I2C_PSU1_SDA")
	)
	(segment
		(start 31.098744 -197.95109)
		(end 33.085786 -195.964048)
		(width 0.1524)
		(layer "B.Cu")
		(net "I2C_PSU1_SDA")
	)
	(segment
		(start 25.418034 -84.846668)
		(end 33.561274 -92.989908)
		(width 0.1524)
		(layer "B.Cu")
		(net "I2C_PSU1_SDA")
	)
	(segment
		(start 30.04439 -197.95109)
		(end 31.098744 -197.95109)
		(width 0.1524)
		(layer "B.Cu")
		(net "I2C_PSU1_SDA")
	)
	(segment
		(start 30.063186 -107.000802)
		(end 36.12642 -107.000802)
		(width 0.1524)
		(layer "B.Cu")
		(net "I2C_PSU1_SDA")
	)
	(segment
		(start 35.53968 -4.590034)
		(end 37.081206 -6.13156)
		(width 0.1524)
		(layer "B.Cu")
		(net "I2C_PSU1_SDA")
	)
	(segment
		(start 27.640788 -18.600674)
		(end 25.418034 -20.823428)
		(width 0.1524)
		(layer "B.Cu")
		(net "I2C_PSU1_SDA")
	)
	(segment
		(start 33.085786 -195.964048)
		(end 33.085786 -181.073806)
		(width 0.1524)
		(layer "B.Cu")
		(net "I2C_PSU1_SDA")
	)
	(segment
		(start 24.93264 -172.92066)
		(end 24.93264 -112.131348)
		(width 0.1524)
		(layer "B.Cu")
		(net "I2C_PSU1_SDA")
	)
	(segment
		(start 24.93264 -112.131348)
		(end 30.063186 -107.000802)
		(width 0.1524)
		(layer "B.Cu")
		(net "I2C_PSU1_SDA")
	)
	(segment
		(start 23.528782 -230.480616)
		(end 23.833582 -230.175816)
		(width 0.1524)
		(layer "B.Cu")
		(net "I2C_PSU1_SDA")
	)
	(segment
		(start 36.787836 -106.339386)
		(end 36.787836 -94.238064)
		(width 0.1524)
		(layer "B.Cu")
		(net "I2C_PSU1_SDA")
	)
	(segment
		(start 2.70002 -219.42171)
		(end 1.948942 -218.670632)
		(width 0.1524)
		(layer "F.Cu")
		(net "I2C_PSU1_SCL")
	)
	(segment
		(start 24.252428 -229.395274)
		(end 24.252428 -230.5939)
		(width 0.1524)
		(layer "F.Cu")
		(net "I2C_PSU1_SCL")
	)
	(segment
		(start 24.252428 -230.5939)
		(end 23.628604 -231.217724)
		(width 0.1524)
		(layer "F.Cu")
		(net "I2C_PSU1_SCL")
	)
	(segment
		(start 6.51764 -224.952052)
		(end 5.066792 -223.501204)
		(width 0.1524)
		(layer "F.Cu")
		(net "I2C_PSU1_SCL")
	)
	(segment
		(start 23.300182 -228.443028)
		(end 24.252428 -229.395274)
		(width 0.1524)
		(layer "F.Cu")
		(net "I2C_PSU1_SCL")
	)
	(segment
		(start 7.26186 -224.952052)
		(end 6.51764 -224.952052)
		(width 0.1524)
		(layer "F.Cu")
		(net "I2C_PSU1_SCL")
	)
	(segment
		(start 5.066792 -223.501204)
		(end 5.066792 -221.61119)
		(width 0.1524)
		(layer "F.Cu")
		(net "I2C_PSU1_SCL")
	)
	(segment
		(start 23.628604 -231.217724)
		(end 16.639032 -231.217724)
		(width 0.1524)
		(layer "F.Cu")
		(net "I2C_PSU1_SCL")
	)
	(segment
		(start 4.093464 -220.637862)
		(end 3.578098 -220.637862)
		(width 0.1524)
		(layer "F.Cu")
		(net "I2C_PSU1_SCL")
	)
	(segment
		(start 11.162792 -225.741484)
		(end 8.051292 -225.741484)
		(width 0.1524)
		(layer "F.Cu")
		(net "I2C_PSU1_SCL")
	)
	(segment
		(start 2.70002 -219.759784)
		(end 2.70002 -219.42171)
		(width 0.1524)
		(layer "F.Cu")
		(net "I2C_PSU1_SCL")
	)
	(segment
		(start 3.578098 -220.637862)
		(end 2.70002 -219.759784)
		(width 0.1524)
		(layer "F.Cu")
		(net "I2C_PSU1_SCL")
	)
	(segment
		(start 16.639032 -231.217724)
		(end 11.162792 -225.741484)
		(width 0.1524)
		(layer "F.Cu")
		(net "I2C_PSU1_SCL")
	)
	(segment
		(start 5.066792 -221.61119)
		(end 4.093464 -220.637862)
		(width 0.1524)
		(layer "F.Cu")
		(net "I2C_PSU1_SCL")
	)
	(segment
		(start 8.051292 -225.741484)
		(end 7.26186 -224.952052)
		(width 0.1524)
		(layer "F.Cu")
		(net "I2C_PSU1_SCL")
	)
	(via
		(at 23.300182 -228.443028)
		(size 0.508)
		(drill 0.254)
		(layers "F.Cu" "B.Cu")
		(net "I2C_PSU1_SCL")
	)
	(segment
		(start 24.916638 -18.225262)
		(end 24.916638 -84.920328)
		(width 0.1524)
		(layer "B.Cu")
		(net "I2C_PSU1_SCL")
	)
	(segment
		(start 24.52624 -173.156626)
		(end 32.467804 -181.09819)
		(width 0.1524)
		(layer "B.Cu")
		(net "I2C_PSU1_SCL")
	)
	(segment
		(start 29.34335 -106.858054)
		(end 24.52624 -111.675164)
		(width 0.1524)
		(layer "B.Cu")
		(net "I2C_PSU1_SCL")
	)
	(segment
		(start 23.300182 -202.171046)
		(end 23.300182 -228.443028)
		(width 0.1524)
		(layer "B.Cu")
		(net "I2C_PSU1_SCL")
	)
	(segment
		(start 34.409888 -96.940116)
		(end 35.53968 -98.069908)
		(width 0.1524)
		(layer "B.Cu")
		(net "I2C_PSU1_SCL")
	)
	(segment
		(start 32.467804 -181.09819)
		(end 32.467804 -194.063874)
		(width 0.1524)
		(layer "B.Cu")
		(net "I2C_PSU1_SCL")
	)
	(segment
		(start 24.916638 -84.920328)
		(end 34.409888 -94.413578)
		(width 0.1524)
		(layer "B.Cu")
		(net "I2C_PSU1_SCL")
	)
	(segment
		(start 28.343352 -14.798548)
		(end 24.916638 -18.225262)
		(width 0.1524)
		(layer "B.Cu")
		(net "I2C_PSU1_SCL")
	)
	(segment
		(start 30.32506 -195.146168)
		(end 23.300182 -202.171046)
		(width 0.1524)
		(layer "B.Cu")
		(net "I2C_PSU1_SCL")
	)
	(segment
		(start 35.53968 -9.670034)
		(end 34.229548 -10.980166)
		(width 0.1524)
		(layer "B.Cu")
		(net "I2C_PSU1_SCL")
	)
	(segment
		(start 30.292802 -104.262682)
		(end 29.34335 -105.212134)
		(width 0.1524)
		(layer "B.Cu")
		(net "I2C_PSU1_SCL")
	)
	(segment
		(start 29.330396 -10.980166)
		(end 28.343352 -11.96721)
		(width 0.1524)
		(layer "B.Cu")
		(net "I2C_PSU1_SCL")
	)
	(segment
		(start 31.14167 -104.262682)
		(end 30.292802 -104.262682)
		(width 0.1524)
		(layer "B.Cu")
		(net "I2C_PSU1_SCL")
	)
	(segment
		(start 34.229548 -10.980166)
		(end 29.330396 -10.980166)
		(width 0.1524)
		(layer "B.Cu")
		(net "I2C_PSU1_SCL")
	)
	(segment
		(start 31.38551 -195.146168)
		(end 30.32506 -195.146168)
		(width 0.1524)
		(layer "B.Cu")
		(net "I2C_PSU1_SCL")
	)
	(segment
		(start 28.343352 -11.96721)
		(end 28.343352 -14.798548)
		(width 0.1524)
		(layer "B.Cu")
		(net "I2C_PSU1_SCL")
	)
	(segment
		(start 34.409888 -94.413578)
		(end 34.409888 -96.940116)
		(width 0.1524)
		(layer "B.Cu")
		(net "I2C_PSU1_SCL")
	)
	(segment
		(start 24.52624 -111.675164)
		(end 24.52624 -173.156626)
		(width 0.1524)
		(layer "B.Cu")
		(net "I2C_PSU1_SCL")
	)
	(segment
		(start 32.467804 -194.063874)
		(end 31.38551 -195.146168)
		(width 0.1524)
		(layer "B.Cu")
		(net "I2C_PSU1_SCL")
	)
	(segment
		(start 34.409888 -100.994464)
		(end 31.14167 -104.262682)
		(width 0.1524)
		(layer "B.Cu")
		(net "I2C_PSU1_SCL")
	)
	(segment
		(start 29.34335 -105.212134)
		(end 29.34335 -106.858054)
		(width 0.1524)
		(layer "B.Cu")
		(net "I2C_PSU1_SCL")
	)
	(segment
		(start 35.53968 -98.069908)
		(end 34.409888 -99.1997)
		(width 0.1524)
		(layer "B.Cu")
		(net "I2C_PSU1_SCL")
	)
	(segment
		(start 34.409888 -99.1997)
		(end 34.409888 -100.994464)
		(width 0.1524)
		(layer "B.Cu")
		(net "I2C_PSU1_SCL")
	)
	(zone
		(layer "F.Cu")
		(hatch none 0.5)
		(connect_pads
			(clearance 0)
		)
		(min_thickness 0.25)
		(keepout
			(tracks not_allowed)
			(vias allowed)
			(pads allowed)
			(copperpour not_allowed)
			(footprints allowed)
		)
		(placement
			(enabled no)
			(sheetname "")
		)
		(fill
			(thermal_gap 0.5)
			(thermal_bridge_width 0.5)
			(island_removal_mode 0)
		)
		(polygon
			(pts
				(arc
					(start 18.599912 -473.700094)
					(mid 16.599916 -475.70009)
					(end 14.59992 -473.700094)
				)
				(arc
					(start 14.59992 -473.700094)
					(mid 16.599916 -471.700098)
					(end 18.599912 -473.700094)
				)
			)
		)
	)
	(zone
		(layer "F.Cu")
		(hatch none 0.5)
		(connect_pads
			(clearance 0)
		)
		(min_thickness 0.25)
		(keepout
			(tracks not_allowed)
			(vias allowed)
			(pads allowed)
			(copperpour not_allowed)
			(footprints allowed)
		)
		(placement
			(enabled no)
			(sheetname "")
		)
		(fill
			(thermal_gap 0.5)
			(thermal_bridge_width 0.5)
			(island_removal_mode 0)
		)
		(polygon
			(pts
				(arc
					(start 95.400114 -153.36012)
					(mid 91.400122 -157.360112)
					(end 87.399876 -153.36012)
				)
				(arc
					(start 87.399876 -153.36012)
					(mid 91.400122 -149.359874)
					(end 95.400114 -153.36012)
				)
			)
		)
	)
	(zone
		(layer "F.Cu")
		(hatch none 0.5)
		(connect_pads
			(clearance 0)
		)
		(min_thickness 0.25)
		(keepout
			(tracks allowed)
			(vias allowed)
			(pads allowed)
			(copperpour allowed)
			(footprints not_allowed)
		)
		(placement
			(enabled no)
			(sheetname "")
		)
		(fill
			(thermal_gap 0.5)
			(thermal_bridge_width 0.5)
			(island_removal_mode 0)
		)
		(polygon
			(pts
				(xy 55.999888 -257.549904) (xy 55.999888 -232.549954) (xy 44.99991 -232.549954) (xy 44.99991 -257.549904)
			)
		)
	)
	(zone
		(layer "F.Cu")
		(hatch none 0.5)
		(connect_pads
			(clearance 0)
		)
		(min_thickness 0.25)
		(keepout
			(tracks allowed)
			(vias allowed)
			(pads allowed)
			(copperpour allowed)
			(footprints not_allowed)
		)
		(placement
			(enabled no)
			(sheetname "")
		)
		(fill
			(thermal_gap 0.5)
			(thermal_bridge_width 0.5)
			(island_removal_mode 0)
		)
		(polygon
			(pts
				(xy 55.999888 -365.899954) (xy 44.99991 -365.899954) (xy 44.99991 -390.899904) (xy 55.999888 -390.899904)
			)
		)
	)
	(zone
		(layer "F.Cu")
		(hatch none 0.5)
		(connect_pads
			(clearance 0)
		)
		(min_thickness 0.25)
		(keepout
			(tracks not_allowed)
			(vias allowed)
			(pads allowed)
			(copperpour not_allowed)
			(footprints allowed)
		)
		(placement
			(enabled no)
			(sheetname "")
		)
		(fill
			(thermal_gap 0.5)
			(thermal_bridge_width 0.5)
			(island_removal_mode 0)
		)
		(polygon
			(pts
				(arc
					(start 11.599926 -473.700094)
					(mid 16.599916 -468.700104)
					(end 21.599906 -473.700094)
				)
				(arc
					(start 21.599906 -473.700094)
					(mid 16.599916 -478.700084)
					(end 11.599926 -473.700094)
				)
			)
		)
	)
	(zone
		(layer "F.Cu")
		(hatch none 0.5)
		(connect_pads
			(clearance 0)
		)
		(min_thickness 0.25)
		(keepout
			(tracks allowed)
			(vias allowed)
			(pads allowed)
			(copperpour allowed)
			(footprints not_allowed)
		)
		(placement
			(enabled no)
			(sheetname "")
		)
		(fill
			(thermal_gap 0.5)
			(thermal_bridge_width 0.5)
			(island_removal_mode 0)
		)
		(polygon
			(pts
				(arc
					(start 83.000088 -519.050016)
					(mid 78.000098 -524.050006)
					(end 73.000108 -519.050016)
				)
				(arc
					(start 73.000108 -519.050016)
					(mid 78.000098 -514.050026)
					(end 83.000088 -519.050016)
				)
			)
		)
	)
	(zone
		(layer "F.Cu")
		(hatch none 0.5)
		(connect_pads
			(clearance 0)
		)
		(min_thickness 0.25)
		(keepout
			(tracks not_allowed)
			(vias allowed)
			(pads allowed)
			(copperpour not_allowed)
			(footprints allowed)
		)
		(placement
			(enabled no)
			(sheetname "")
		)
		(fill
			(thermal_gap 0.5)
			(thermal_bridge_width 0.5)
			(island_removal_mode 0)
		)
		(polygon
			(pts
				(arc
					(start 77.999844 -346.380816)
					(mid 79.434944 -347.815916)
					(end 77.999844 -349.251016)
				)
				(arc
					(start 77.999844 -349.251016)
					(mid 69.998844 -341.250016)
					(end 77.999844 -333.249016)
				)
				(arc
					(start 77.999844 -333.249016)
					(mid 79.434944 -334.684116)
					(end 77.999844 -336.119216)
				)
				(arc
					(start 77.999844 -336.119216)
					(mid 72.869044 -341.250016)
					(end 77.999844 -346.380816)
				)
			)
		)
	)
	(zone
		(layer "F.Cu")
		(hatch none 0.5)
		(connect_pads
			(clearance 0)
		)
		(min_thickness 0.25)
		(keepout
			(tracks not_allowed)
			(vias allowed)
			(pads allowed)
			(copperpour not_allowed)
			(footprints allowed)
		)
		(placement
			(enabled no)
			(sheetname "")
		)
		(fill
			(thermal_gap 0.5)
			(thermal_bridge_width 0.5)
			(island_removal_mode 0)
		)
		(polygon
			(pts
				(arc
					(start 73.000108 -519.050016)
					(mid 78.000098 -514.050026)
					(end 83.000088 -519.050016)
				)
				(arc
					(start 83.000088 -519.050016)
					(mid 78.000098 -524.050006)
					(end 73.000108 -519.050016)
				)
			)
		)
	)
	(zone
		(layer "F.Cu")
		(hatch none 0.5)
		(connect_pads
			(clearance 0)
		)
		(min_thickness 0.25)
		(keepout
			(tracks not_allowed)
			(vias allowed)
			(pads allowed)
			(copperpour not_allowed)
			(footprints allowed)
		)
		(placement
			(enabled no)
			(sheetname "")
		)
		(fill
			(thermal_gap 0.5)
			(thermal_bridge_width 0.5)
			(island_removal_mode 0)
		)
		(polygon
			(pts
				(arc
					(start 16.599916 -301.03064)
					(mid 18.035016 -302.46574)
					(end 16.599916 -303.90084)
				)
				(arc
					(start 16.599916 -303.90084)
					(mid 8.598916 -295.89984)
					(end 16.599916 -287.89884)
				)
				(arc
					(start 16.599916 -287.89884)
					(mid 18.035016 -289.33394)
					(end 16.599916 -290.76904)
				)
				(arc
					(start 16.599916 -290.76904)
					(mid 11.469116 -295.89984)
					(end 16.599916 -301.03064)
				)
			)
		)
	)
	(zone
		(layer "F.Cu")
		(hatch none 0.5)
		(connect_pads
			(clearance 0)
		)
		(min_thickness 0.25)
		(keepout
			(tracks not_allowed)
			(vias allowed)
			(pads allowed)
			(copperpour not_allowed)
			(footprints allowed)
		)
		(placement
			(enabled no)
			(sheetname "")
		)
		(fill
			(thermal_gap 0.5)
			(thermal_bridge_width 0.5)
			(island_removal_mode 0)
		)
		(polygon
			(pts
				(arc
					(start 80.000094 -519.050016)
					(mid 78.000098 -521.050012)
					(end 76.000102 -519.050016)
				)
				(arc
					(start 76.000102 -519.050016)
					(mid 78.000098 -517.05002)
					(end 80.000094 -519.050016)
				)
			)
		)
	)
	(zone
		(layer "F.Cu")
		(hatch none 0.5)
		(connect_pads
			(clearance 0)
		)
		(min_thickness 0.25)
		(keepout
			(tracks allowed)
			(vias allowed)
			(pads allowed)
			(copperpour allowed)
			(footprints not_allowed)
		)
		(placement
			(enabled no)
			(sheetname "")
		)
		(fill
			(thermal_gap 0.5)
			(thermal_bridge_width 0.5)
			(island_removal_mode 0)
		)
		(polygon
			(pts
				(arc
					(start 86.399878 -108.91012)
					(mid 91.400122 -103.909876)
					(end 96.400112 -108.91012)
				)
				(arc
					(start 96.400112 -108.91012)
					(mid 91.400122 -113.91011)
					(end 86.399878 -108.91012)
				)
			)
		)
	)
	(zone
		(layer "F.Cu")
		(hatch none 0.5)
		(connect_pads
			(clearance 0)
		)
		(min_thickness 0.25)
		(keepout
			(tracks not_allowed)
			(vias allowed)
			(pads allowed)
			(copperpour not_allowed)
			(footprints allowed)
		)
		(placement
			(enabled no)
			(sheetname "")
		)
		(fill
			(thermal_gap 0.5)
			(thermal_bridge_width 0.5)
			(island_removal_mode 0)
		)
		(polygon
			(pts
				(arc
					(start 86.399878 -508.96012)
					(mid 91.400122 -503.959876)
					(end 96.400112 -508.96012)
				)
				(arc
					(start 96.400112 -508.96012)
					(mid 91.400122 -513.96011)
					(end 86.399878 -508.96012)
				)
			)
		)
	)
	(zone
		(layer "F.Cu")
		(hatch none 0.5)
		(connect_pads
			(clearance 0)
		)
		(min_thickness 0.25)
		(keepout
			(tracks allowed)
			(vias allowed)
			(pads allowed)
			(copperpour allowed)
			(footprints not_allowed)
		)
		(placement
			(enabled no)
			(sheetname "")
		)
		(fill
			(thermal_gap 0.5)
			(thermal_bridge_width 0.5)
			(island_removal_mode 0)
		)
		(polygon
			(pts
				(arc
					(start 83.000088 -430.150016)
					(mid 78.000098 -435.150006)
					(end 73.000108 -430.150016)
				)
				(arc
					(start 73.000108 -430.150016)
					(mid 78.000098 -425.150026)
					(end 83.000088 -430.150016)
				)
			)
		)
	)
	(zone
		(layer "F.Cu")
		(hatch none 0.5)
		(connect_pads
			(clearance 0)
		)
		(min_thickness 0.25)
		(keepout
			(tracks allowed)
			(vias allowed)
			(pads allowed)
			(copperpour allowed)
			(footprints not_allowed)
		)
		(placement
			(enabled no)
			(sheetname "")
		)
		(fill
			(thermal_gap 0.5)
			(thermal_bridge_width 0.5)
			(island_removal_mode 0)
		)
		(polygon
			(pts
				(arc
					(start 96.400112 -375.61012)
					(mid 91.400122 -380.61011)
					(end 86.399878 -375.61012)
				)
				(arc
					(start 86.399878 -375.61012)
					(mid 91.400122 -370.609876)
					(end 96.400112 -375.61012)
				)
			)
		)
	)
	(zone
		(layer "F.Cu")
		(hatch none 0.5)
		(connect_pads
			(clearance 0)
		)
		(min_thickness 0.25)
		(keepout
			(tracks not_allowed)
			(vias allowed)
			(pads allowed)
			(copperpour not_allowed)
			(footprints allowed)
		)
		(placement
			(enabled no)
			(sheetname "")
		)
		(fill
			(thermal_gap 0.5)
			(thermal_bridge_width 0.5)
			(island_removal_mode 0)
		)
		(polygon
			(pts
				(arc
					(start 80.000094 -341.250016)
					(mid 78.000098 -343.250012)
					(end 76.000102 -341.250016)
				)
				(arc
					(start 76.000102 -341.250016)
					(mid 78.000098 -339.25002)
					(end 80.000094 -341.250016)
				)
			)
		)
	)
	(zone
		(layer "F.Cu")
		(hatch none 0.5)
		(connect_pads
			(clearance 0)
		)
		(min_thickness 0.25)
		(keepout
			(tracks not_allowed)
			(vias allowed)
			(pads allowed)
			(copperpour not_allowed)
			(footprints allowed)
		)
		(placement
			(enabled no)
			(sheetname "")
		)
		(fill
			(thermal_gap 0.5)
			(thermal_bridge_width 0.5)
			(island_removal_mode 0)
		)
		(polygon
			(pts
				(arc
					(start 80.000094 -210.09991)
					(mid 78.000098 -212.099906)
					(end 76.000102 -210.09991)
				)
				(arc
					(start 76.000102 -210.09991)
					(mid 78.000098 -208.099914)
					(end 80.000094 -210.09991)
				)
			)
		)
	)
	(zone
		(layer "F.Cu")
		(hatch none 0.5)
		(connect_pads
			(clearance 0)
		)
		(min_thickness 0.25)
		(keepout
			(tracks not_allowed)
			(vias allowed)
			(pads allowed)
			(copperpour not_allowed)
			(footprints allowed)
		)
		(placement
			(enabled no)
			(sheetname "")
		)
		(fill
			(thermal_gap 0.5)
			(thermal_bridge_width 0.5)
			(island_removal_mode 0)
		)
		(polygon
			(pts
				(arc
					(start 16.599916 -392.80084)
					(mid 15.164816 -391.36574)
					(end 16.599916 -389.93064)
				)
				(arc
					(start 16.599916 -389.93064)
					(mid 21.730716 -384.79984)
					(end 16.599916 -379.66904)
				)
				(arc
					(start 16.599916 -379.66904)
					(mid 15.164816 -378.23394)
					(end 16.599916 -376.79884)
				)
				(arc
					(start 16.599916 -376.79884)
					(mid 24.600916 -384.79984)
					(end 16.599916 -392.80084)
				)
			)
		)
	)
	(zone
		(layer "F.Cu")
		(hatch none 0.5)
		(connect_pads
			(clearance 0)
		)
		(min_thickness 0.25)
		(keepout
			(tracks not_allowed)
			(vias allowed)
			(pads allowed)
			(copperpour not_allowed)
			(footprints allowed)
		)
		(placement
			(enabled no)
			(sheetname "")
		)
		(fill
			(thermal_gap 0.5)
			(thermal_bridge_width 0.5)
			(island_removal_mode 0)
		)
		(polygon
			(pts
				(arc
					(start 77.999844 -435.280816)
					(mid 79.434944 -436.715916)
					(end 77.999844 -438.151016)
				)
				(arc
					(start 77.999844 -438.151016)
					(mid 69.998844 -430.150016)
					(end 77.999844 -422.149016)
				)
				(arc
					(start 77.999844 -422.149016)
					(mid 79.434944 -423.584116)
					(end 77.999844 -425.019216)
				)
				(arc
					(start 77.999844 -425.019216)
					(mid 72.869044 -430.150016)
					(end 77.999844 -435.280816)
				)
			)
		)
	)
	(zone
		(layer "F.Cu")
		(hatch none 0.5)
		(connect_pads
			(clearance 0)
		)
		(min_thickness 0.25)
		(keepout
			(tracks not_allowed)
			(vias allowed)
			(pads allowed)
			(copperpour not_allowed)
			(footprints allowed)
		)
		(placement
			(enabled no)
			(sheetname "")
		)
		(fill
			(thermal_gap 0.5)
			(thermal_bridge_width 0.5)
			(island_removal_mode 0)
		)
		(polygon
			(pts
				(arc
					(start 86.399878 -331.16012)
					(mid 91.400122 -326.159876)
					(end 96.400112 -331.16012)
				)
				(arc
					(start 96.400112 -331.16012)
					(mid 91.400122 -336.16011)
					(end 86.399878 -331.16012)
				)
			)
		)
	)
	(zone
		(layer "F.Cu")
		(hatch none 0.5)
		(connect_pads
			(clearance 0)
		)
		(min_thickness 0.25)
		(keepout
			(tracks not_allowed)
			(vias allowed)
			(pads allowed)
			(copperpour not_allowed)
			(footprints allowed)
		)
		(placement
			(enabled no)
			(sheetname "")
		)
		(fill
			(thermal_gap 0.5)
			(thermal_bridge_width 0.5)
			(island_removal_mode 0)
		)
		(polygon
			(pts
				(arc
					(start 86.399878 -64.46012)
					(mid 91.400122 -59.459876)
					(end 96.400112 -64.46012)
				)
				(arc
					(start 96.400112 -64.46012)
					(mid 91.400122 -69.46011)
					(end 86.399878 -64.46012)
				)
			)
		)
	)
	(zone
		(layer "F.Cu")
		(hatch none 0.5)
		(connect_pads
			(clearance 0)
		)
		(min_thickness 0.25)
		(keepout
			(tracks allowed)
			(vias allowed)
			(pads allowed)
			(copperpour allowed)
			(footprints not_allowed)
		)
		(placement
			(enabled no)
			(sheetname "")
		)
		(fill
			(thermal_gap 0.5)
			(thermal_bridge_width 0.5)
			(island_removal_mode 0)
		)
		(polygon
			(pts
				(arc
					(start 21.599906 -295.900094)
					(mid 16.599916 -300.900084)
					(end 11.599926 -295.900094)
				)
				(arc
					(start 11.599926 -295.900094)
					(mid 16.599916 -290.900104)
					(end 21.599906 -295.900094)
				)
			)
		)
	)
	(zone
		(layer "F.Cu")
		(hatch none 0.5)
		(connect_pads
			(clearance 0)
		)
		(min_thickness 0.25)
		(keepout
			(tracks allowed)
			(vias allowed)
			(pads allowed)
			(copperpour allowed)
			(footprints not_allowed)
		)
		(placement
			(enabled no)
			(sheetname "")
		)
		(fill
			(thermal_gap 0.5)
			(thermal_bridge_width 0.5)
			(island_removal_mode 0)
		)
		(polygon
			(pts
				(arc
					(start 96.400112 -464.51012)
					(mid 91.400122 -469.51011)
					(end 86.399878 -464.51012)
				)
				(arc
					(start 86.399878 -464.51012)
					(mid 91.400122 -459.509876)
					(end 96.400112 -464.51012)
				)
			)
		)
	)
	(zone
		(layer "F.Cu")
		(hatch none 0.5)
		(connect_pads
			(clearance 0)
		)
		(min_thickness 0.25)
		(keepout
			(tracks allowed)
			(vias allowed)
			(pads allowed)
			(copperpour allowed)
			(footprints not_allowed)
		)
		(placement
			(enabled no)
			(sheetname "")
		)
		(fill
			(thermal_gap 0.5)
			(thermal_bridge_width 0.5)
			(island_removal_mode 0)
		)
		(polygon
			(pts
				(arc
					(start 96.400112 -242.26012)
					(mid 91.400122 -247.26011)
					(end 86.399878 -242.26012)
				)
				(arc
					(start 86.399878 -242.26012)
					(mid 91.400122 -237.259876)
					(end 96.400112 -242.26012)
				)
			)
		)
	)
	(zone
		(layer "F.Cu")
		(hatch none 0.5)
		(connect_pads
			(clearance 0)
		)
		(min_thickness 0.25)
		(keepout
			(tracks allowed)
			(vias allowed)
			(pads allowed)
			(copperpour allowed)
			(footprints not_allowed)
		)
		(placement
			(enabled no)
			(sheetname "")
		)
		(fill
			(thermal_gap 0.5)
			(thermal_bridge_width 0.5)
			(island_removal_mode 0)
		)
		(polygon
			(pts
				(arc
					(start 96.400112 -153.36012)
					(mid 91.400122 -158.36011)
					(end 86.399878 -153.36012)
				)
				(arc
					(start 86.399878 -153.36012)
					(mid 91.400122 -148.359876)
					(end 96.400112 -153.36012)
				)
			)
		)
	)
	(zone
		(layer "F.Cu")
		(hatch none 0.5)
		(connect_pads
			(clearance 0)
		)
		(min_thickness 0.25)
		(keepout
			(tracks not_allowed)
			(vias allowed)
			(pads allowed)
			(copperpour not_allowed)
			(footprints allowed)
		)
		(placement
			(enabled no)
			(sheetname "")
		)
		(fill
			(thermal_gap 0.5)
			(thermal_bridge_width 0.5)
			(island_removal_mode 0)
		)
		(polygon
			(pts
				(arc
					(start 86.399878 -197.81012)
					(mid 91.400122 -192.809876)
					(end 96.400112 -197.81012)
				)
				(arc
					(start 96.400112 -197.81012)
					(mid 91.400122 -202.81011)
					(end 86.399878 -197.81012)
				)
			)
		)
	)
	(zone
		(layer "F.Cu")
		(hatch none 0.5)
		(connect_pads
			(clearance 0)
		)
		(min_thickness 0.25)
		(keepout
			(tracks not_allowed)
			(vias allowed)
			(pads allowed)
			(copperpour not_allowed)
			(footprints allowed)
		)
		(placement
			(enabled no)
			(sheetname "")
		)
		(fill
			(thermal_gap 0.5)
			(thermal_bridge_width 0.5)
			(island_removal_mode 0)
		)
		(polygon
			(pts
				(arc
					(start 95.400114 -286.71012)
					(mid 91.400122 -290.710112)
					(end 87.399876 -286.71012)
				)
				(arc
					(start 87.399876 -286.71012)
					(mid 91.400122 -282.709874)
					(end 95.400114 -286.71012)
				)
			)
		)
	)
	(zone
		(layer "F.Cu")
		(hatch none 0.5)
		(connect_pads
			(clearance 0)
		)
		(min_thickness 0.25)
		(keepout
			(tracks allowed)
			(vias allowed)
			(pads allowed)
			(copperpour allowed)
			(footprints not_allowed)
		)
		(placement
			(enabled no)
			(sheetname "")
		)
		(fill
			(thermal_gap 0.5)
			(thermal_bridge_width 0.5)
			(island_removal_mode 0)
		)
		(polygon
			(pts
				(arc
					(start 96.400112 -508.96012)
					(mid 91.400122 -513.96011)
					(end 86.399878 -508.96012)
				)
				(arc
					(start 86.399878 -508.96012)
					(mid 91.400122 -503.959876)
					(end 96.400112 -508.96012)
				)
			)
		)
	)
	(zone
		(layer "F.Cu")
		(hatch none 0.5)
		(connect_pads
			(clearance 0)
		)
		(min_thickness 0.25)
		(keepout
			(tracks not_allowed)
			(vias allowed)
			(pads allowed)
			(copperpour not_allowed)
			(footprints allowed)
		)
		(placement
			(enabled no)
			(sheetname "")
		)
		(fill
			(thermal_gap 0.5)
			(thermal_bridge_width 0.5)
			(island_removal_mode 0)
		)
		(polygon
			(pts
				(arc
					(start 18.599912 -118.100094)
					(mid 16.599916 -120.10009)
					(end 14.59992 -118.100094)
				)
				(arc
					(start 14.59992 -118.100094)
					(mid 16.599916 -116.100098)
					(end 18.599912 -118.100094)
				)
			)
		)
	)
	(zone
		(layer "F.Cu")
		(hatch none 0.5)
		(connect_pads
			(clearance 0)
		)
		(min_thickness 0.25)
		(keepout
			(tracks allowed)
			(vias allowed)
			(pads allowed)
			(copperpour allowed)
			(footprints not_allowed)
		)
		(placement
			(enabled no)
			(sheetname "")
		)
		(fill
			(thermal_gap 0.5)
			(thermal_bridge_width 0.5)
			(island_removal_mode 0)
		)
		(polygon
			(pts
				(xy 37.975032 -264.839958) (xy 37.975032 -176.729898) (xy 28.02509 -176.729898) (xy 28.02509 -264.839958)
			)
		)
	)
	(zone
		(layer "F.Cu")
		(hatch none 0.5)
		(connect_pads
			(clearance 0)
		)
		(min_thickness 0.25)
		(keepout
			(tracks allowed)
			(vias allowed)
			(pads allowed)
			(copperpour allowed)
			(footprints not_allowed)
		)
		(placement
			(enabled no)
			(sheetname "")
		)
		(fill
			(thermal_gap 0.5)
			(thermal_bridge_width 0.5)
			(island_removal_mode 0)
		)
		(polygon
			(pts
				(xy 55.999888 -143.649954) (xy 44.99991 -143.649954) (xy 44.99991 -168.649904) (xy 55.999888 -168.649904)
			)
		)
	)
	(zone
		(layer "F.Cu")
		(hatch none 0.5)
		(connect_pads
			(clearance 0)
		)
		(min_thickness 0.25)
		(keepout
			(tracks not_allowed)
			(vias allowed)
			(pads allowed)
			(copperpour not_allowed)
			(footprints allowed)
		)
		(placement
			(enabled no)
			(sheetname "")
		)
		(fill
			(thermal_gap 0.5)
			(thermal_bridge_width 0.5)
			(island_removal_mode 0)
		)
		(polygon
			(pts
				(arc
					(start 95.400114 -20.01012)
					(mid 91.400122 -24.010112)
					(end 87.399876 -20.01012)
				)
				(arc
					(start 87.399876 -20.01012)
					(mid 91.400122 -16.009874)
					(end 95.400114 -20.01012)
				)
			)
		)
	)
	(zone
		(layer "F.Cu")
		(hatch none 0.5)
		(connect_pads
			(clearance 0)
		)
		(min_thickness 0.25)
		(keepout
			(tracks not_allowed)
			(vias allowed)
			(pads allowed)
			(copperpour not_allowed)
			(footprints allowed)
		)
		(placement
			(enabled no)
			(sheetname "")
		)
		(fill
			(thermal_gap 0.5)
			(thermal_bridge_width 0.5)
			(island_removal_mode 0)
		)
		(polygon
			(pts
				(arc
					(start 80.600042 -78.300072)
					(mid 78.000098 -80.900016)
					(end 75.3999 -78.300072)
				)
				(arc
					(start 75.3999 -78.300072)
					(mid 78.000098 -75.699874)
					(end 80.600042 -78.300072)
				)
			)
		)
	)
	(zone
		(layer "F.Cu")
		(hatch none 0.5)
		(connect_pads
			(clearance 0)
		)
		(min_thickness 0.25)
		(keepout
			(tracks not_allowed)
			(vias allowed)
			(pads allowed)
			(copperpour not_allowed)
			(footprints allowed)
		)
		(placement
			(enabled no)
			(sheetname "")
		)
		(fill
			(thermal_gap 0.5)
			(thermal_bridge_width 0.5)
			(island_removal_mode 0)
		)
		(polygon
			(pts
				(arc
					(start 95.400114 -108.91012)
					(mid 91.400122 -112.910112)
					(end 87.399876 -108.91012)
				)
				(arc
					(start 87.399876 -108.91012)
					(mid 91.400122 -104.909874)
					(end 95.400114 -108.91012)
				)
			)
		)
	)
	(zone
		(layer "F.Cu")
		(hatch none 0.5)
		(connect_pads
			(clearance 0)
		)
		(min_thickness 0.25)
		(keepout
			(tracks allowed)
			(vias allowed)
			(pads allowed)
			(copperpour allowed)
			(footprints not_allowed)
		)
		(placement
			(enabled no)
			(sheetname "")
		)
		(fill
			(thermal_gap 0.5)
			(thermal_bridge_width 0.5)
			(island_removal_mode 0)
		)
		(polygon
			(pts
				(xy 55.999888 -54.749954) (xy 44.99991 -54.749954) (xy 44.99991 -79.749904) (xy 55.999888 -79.749904)
			)
		)
	)
	(zone
		(layer "F.Cu")
		(hatch none 0.5)
		(connect_pads
			(clearance 0)
		)
		(min_thickness 0.25)
		(keepout
			(tracks allowed)
			(vias allowed)
			(pads allowed)
			(copperpour allowed)
			(footprints not_allowed)
		)
		(placement
			(enabled no)
			(sheetname "")
		)
		(fill
			(thermal_gap 0.5)
			(thermal_bridge_width 0.5)
			(island_removal_mode 0)
		)
		(polygon
			(pts
				(arc
					(start 83.000088 -121.19991)
					(mid 78.000098 -126.1999)
					(end 73.000108 -121.19991)
				)
				(arc
					(start 73.000108 -121.19991)
					(mid 78.000098 -116.19992)
					(end 83.000088 -121.19991)
				)
			)
		)
	)
	(zone
		(layer "F.Cu")
		(hatch none 0.5)
		(connect_pads
			(clearance 0)
		)
		(min_thickness 0.25)
		(keepout
			(tracks not_allowed)
			(vias allowed)
			(pads allowed)
			(copperpour not_allowed)
			(footprints allowed)
		)
		(placement
			(enabled no)
			(sheetname "")
		)
		(fill
			(thermal_gap 0.5)
			(thermal_bridge_width 0.5)
			(island_removal_mode 0)
		)
		(polygon
			(pts
				(arc
					(start 97.076514 -15.774924)
					(mid 98.702114 -14.149324)
					(end 100.327714 -15.774924)
				)
				(arc
					(start 100.327714 -15.774924)
					(mid 98.702114 -17.400524)
					(end 97.076514 -15.774924)
				)
			)
		)
	)
	(zone
		(layer "F.Cu")
		(hatch none 0.5)
		(connect_pads
			(clearance 0)
		)
		(min_thickness 0.25)
		(keepout
			(tracks allowed)
			(vias allowed)
			(pads allowed)
			(copperpour allowed)
			(footprints not_allowed)
		)
		(placement
			(enabled no)
			(sheetname "")
		)
		(fill
			(thermal_gap 0.5)
			(thermal_bridge_width 0.5)
			(island_removal_mode 0)
		)
		(polygon
			(pts
				(xy 55.999888 -524.249904) (xy 55.999888 -499.249954) (xy 44.99991 -499.249954) (xy 44.99991 -524.249904)
			)
		)
	)
	(zone
		(layer "F.Cu")
		(hatch none 0.5)
		(connect_pads
			(clearance 0)
		)
		(min_thickness 0.25)
		(keepout
			(tracks not_allowed)
			(vias allowed)
			(pads allowed)
			(copperpour not_allowed)
			(footprints allowed)
		)
		(placement
			(enabled no)
			(sheetname "")
		)
		(fill
			(thermal_gap 0.5)
			(thermal_bridge_width 0.5)
			(island_removal_mode 0)
		)
		(polygon
			(pts
				(arc
					(start 77.999844 -126.33071)
					(mid 79.434944 -127.76581)
					(end 77.999844 -129.20091)
				)
				(arc
					(start 77.999844 -129.20091)
					(mid 69.998844 -121.19991)
					(end 77.999844 -113.19891)
				)
				(arc
					(start 77.999844 -113.19891)
					(mid 79.434944 -114.63401)
					(end 77.999844 -116.06911)
				)
				(arc
					(start 77.999844 -116.06911)
					(mid 72.869044 -121.19991)
					(end 77.999844 -126.33071)
				)
			)
		)
	)
	(zone
		(layer "F.Cu")
		(hatch none 0.5)
		(connect_pads
			(clearance 0)
		)
		(min_thickness 0.25)
		(keepout
			(tracks not_allowed)
			(vias allowed)
			(pads allowed)
			(copperpour not_allowed)
			(footprints allowed)
		)
		(placement
			(enabled no)
			(sheetname "")
		)
		(fill
			(thermal_gap 0.5)
			(thermal_bridge_width 0.5)
			(island_removal_mode 0)
		)
		(polygon
			(pts
				(arc
					(start 16.599916 -478.83064)
					(mid 18.035016 -480.26574)
					(end 16.599916 -481.70084)
				)
				(arc
					(start 16.599916 -481.70084)
					(mid 8.598916 -473.69984)
					(end 16.599916 -465.69884)
				)
				(arc
					(start 16.599916 -465.69884)
					(mid 18.035016 -467.13394)
					(end 16.599916 -468.56904)
				)
				(arc
					(start 16.599916 -468.56904)
					(mid 11.469116 -473.69984)
					(end 16.599916 -478.83064)
				)
			)
		)
	)
	(zone
		(layer "F.Cu")
		(hatch none 0.5)
		(connect_pads
			(clearance 0)
		)
		(min_thickness 0.25)
		(keepout
			(tracks not_allowed)
			(vias allowed)
			(pads allowed)
			(copperpour not_allowed)
			(footprints allowed)
		)
		(placement
			(enabled no)
			(sheetname "")
		)
		(fill
			(thermal_gap 0.5)
			(thermal_bridge_width 0.5)
			(island_removal_mode 0)
		)
		(polygon
			(pts
				(arc
					(start 86.399878 -420.06012)
					(mid 91.400122 -415.059876)
					(end 96.400112 -420.06012)
				)
				(arc
					(start 96.400112 -420.06012)
					(mid 91.400122 -425.06011)
					(end 86.399878 -420.06012)
				)
			)
		)
	)
	(zone
		(layer "F.Cu")
		(hatch none 0.5)
		(connect_pads
			(clearance 0)
		)
		(min_thickness 0.25)
		(keepout
			(tracks allowed)
			(vias allowed)
			(pads allowed)
			(copperpour allowed)
			(footprints not_allowed)
		)
		(placement
			(enabled no)
			(sheetname "")
		)
		(fill
			(thermal_gap 0.5)
			(thermal_bridge_width 0.5)
			(island_removal_mode 0)
		)
		(polygon
			(pts
				(arc
					(start 26.293064 -528.999958)
					(mid 26.136273 -528.974662)
					(end 25.995376 -528.901406)
				)
				(arc
					(start 25.995376 -527.85391)
					(mid 25.261404 -526.089428)
					(end 23.495508 -525.358868)
				)
				(xy 0.995426 -525.358868) (xy 0.995426 -414.158938) (xy 17.836896 -414.158938) (xy 17.836896 -396.141194)
				(xy 0.995426 -396.141194) (xy 0.995426 -382.41605) (xy 0.995426 -370.51615) (xy 0.995426 -355.970078)
				(xy 9.39546 -355.970078) (xy 9.39546 -175.369982) (xy 0.995426 -175.369982) (xy 0.995426 -161.633916)
				(xy 0.995426 -149.734016) (xy 0.995426 -145.308828) (xy 17.836896 -145.308828) (xy 17.836896 -127.291084)
				(xy 0.995426 -127.291084) (xy 0.995426 -109.599984) (xy 17.770094 -109.599984) (xy 17.770094 -92.490036)
				(xy 0.995426 -92.490036) (xy 0.995426 -75.049888) (xy 17.770094 -75.049888) (xy 17.770094 -39.45001)
				(xy 0.995426 -39.45001) (xy 0.995426 -22.010116) (xy 17.770094 -22.010116) (xy 17.770094 -4.99999)
				(arc
					(start 23.495508 -4.99999)
					(mid 25.2614 -4.269427)
					(end 25.995376 -2.504948)
				)
				(arc
					(start 25.995376 -1.457452)
					(mid 26.076293 -1.184528)
					(end 26.293064 -0.999998)
				)
				(xy 28.02001 -0.999998) (xy 28.02001 -528.999958)
			)
		)
	)
	(zone
		(layer "F.Cu")
		(hatch none 0.5)
		(connect_pads
			(clearance 0)
		)
		(min_thickness 0.25)
		(keepout
			(tracks not_allowed)
			(vias allowed)
			(pads allowed)
			(copperpour not_allowed)
			(footprints allowed)
		)
		(placement
			(enabled no)
			(sheetname "")
		)
		(fill
			(thermal_gap 0.5)
			(thermal_bridge_width 0.5)
			(island_removal_mode 0)
		)
		(polygon
			(pts
				(arc
					(start 86.399878 -286.71012)
					(mid 91.400122 -281.709876)
					(end 96.400112 -286.71012)
				)
				(arc
					(start 96.400112 -286.71012)
					(mid 91.400122 -291.71011)
					(end 86.399878 -286.71012)
				)
			)
		)
	)
	(zone
		(layer "F.Cu")
		(hatch none 0.5)
		(connect_pads
			(clearance 0)
		)
		(min_thickness 0.25)
		(keepout
			(tracks allowed)
			(vias allowed)
			(pads allowed)
			(copperpour allowed)
			(footprints not_allowed)
		)
		(placement
			(enabled no)
			(sheetname "")
		)
		(fill
			(thermal_gap 0.5)
			(thermal_bridge_width 0.5)
			(island_removal_mode 0)
		)
		(polygon
			(pts
				(xy 55.999888 -499.249954) (xy 44.99991 -499.249954) (xy 44.99991 -524.249904) (xy 55.999888 -524.249904)
			)
		)
	)
	(zone
		(layer "F.Cu")
		(hatch none 0.5)
		(connect_pads
			(clearance 0)
		)
		(min_thickness 0.25)
		(keepout
			(tracks not_allowed)
			(vias allowed)
			(pads allowed)
			(copperpour not_allowed)
			(footprints allowed)
		)
		(placement
			(enabled no)
			(sheetname "")
		)
		(fill
			(thermal_gap 0.5)
			(thermal_bridge_width 0.5)
			(island_removal_mode 0)
		)
		(polygon
			(pts
				(arc
					(start 95.400114 -464.51012)
					(mid 91.400122 -468.510112)
					(end 87.399876 -464.51012)
				)
				(arc
					(start 87.399876 -464.51012)
					(mid 91.400122 -460.509874)
					(end 95.400114 -464.51012)
				)
			)
		)
	)
	(zone
		(layer "F.Cu")
		(hatch none 0.5)
		(connect_pads
			(clearance 0)
		)
		(min_thickness 0.25)
		(keepout
			(tracks not_allowed)
			(vias allowed)
			(pads allowed)
			(copperpour not_allowed)
			(footprints allowed)
		)
		(placement
			(enabled no)
			(sheetname "")
		)
		(fill
			(thermal_gap 0.5)
			(thermal_bridge_width 0.5)
			(island_removal_mode 0)
		)
		(polygon
			(pts
				(arc
					(start 86.399878 -242.26012)
					(mid 91.400122 -237.259876)
					(end 96.400112 -242.26012)
				)
				(arc
					(start 96.400112 -242.26012)
					(mid 91.400122 -247.26011)
					(end 86.399878 -242.26012)
				)
			)
		)
	)
	(zone
		(layer "F.Cu")
		(hatch none 0.5)
		(connect_pads
			(clearance 0)
		)
		(min_thickness 0.25)
		(keepout
			(tracks not_allowed)
			(vias allowed)
			(pads allowed)
			(copperpour not_allowed)
			(footprints allowed)
		)
		(placement
			(enabled no)
			(sheetname "")
		)
		(fill
			(thermal_gap 0.5)
			(thermal_bridge_width 0.5)
			(island_removal_mode 0)
		)
		(polygon
			(pts
				(arc
					(start 95.400114 -197.81012)
					(mid 91.400122 -201.810112)
					(end 87.399876 -197.81012)
				)
				(arc
					(start 87.399876 -197.81012)
					(mid 91.400122 -193.809874)
					(end 95.400114 -197.81012)
				)
			)
		)
	)
	(zone
		(layer "F.Cu")
		(hatch none 0.5)
		(connect_pads
			(clearance 0)
		)
		(min_thickness 0.25)
		(keepout
			(tracks not_allowed)
			(vias allowed)
			(pads allowed)
			(copperpour not_allowed)
			(footprints allowed)
		)
		(placement
			(enabled no)
			(sheetname "")
		)
		(fill
			(thermal_gap 0.5)
			(thermal_bridge_width 0.5)
			(island_removal_mode 0)
		)
		(polygon
			(pts
				(arc
					(start 77.999844 -215.23071)
					(mid 79.434944 -216.66581)
					(end 77.999844 -218.10091)
				)
				(arc
					(start 77.999844 -218.10091)
					(mid 69.998844 -210.09991)
					(end 77.999844 -202.09891)
				)
				(arc
					(start 77.999844 -202.09891)
					(mid 79.434944 -203.53401)
					(end 77.999844 -204.96911)
				)
				(arc
					(start 77.999844 -204.96911)
					(mid 72.869044 -210.09991)
					(end 77.999844 -215.23071)
				)
			)
		)
	)
	(zone
		(layer "F.Cu")
		(hatch none 0.5)
		(connect_pads
			(clearance 0)
		)
		(min_thickness 0.25)
		(keepout
			(tracks allowed)
			(vias allowed)
			(pads allowed)
			(copperpour allowed)
			(footprints not_allowed)
		)
		(placement
			(enabled no)
			(sheetname "")
		)
		(fill
			(thermal_gap 0.5)
			(thermal_bridge_width 0.5)
			(island_removal_mode 0)
		)
		(polygon
			(pts
				(xy 55.999888 -213.099904) (xy 55.999888 -188.099954) (xy 44.99991 -188.099954) (xy 44.99991 -213.099904)
			)
		)
	)
	(zone
		(layer "F.Cu")
		(hatch none 0.5)
		(connect_pads
			(clearance 0)
		)
		(min_thickness 0.25)
		(keepout
			(tracks allowed)
			(vias allowed)
			(pads allowed)
			(copperpour allowed)
			(footprints not_allowed)
		)
		(placement
			(enabled no)
			(sheetname "")
		)
		(fill
			(thermal_gap 0.5)
			(thermal_bridge_width 0.5)
			(island_removal_mode 0)
		)
		(polygon
			(pts
				(arc
					(start 11.599926 -118.100094)
					(mid 16.599916 -113.100104)
					(end 21.599906 -118.100094)
				)
				(arc
					(start 21.599906 -118.100094)
					(mid 16.599916 -123.100084)
					(end 11.599926 -118.100094)
				)
			)
		)
	)
	(zone
		(layer "F.Cu")
		(hatch none 0.5)
		(connect_pads
			(clearance 0)
		)
		(min_thickness 0.25)
		(keepout
			(tracks not_allowed)
			(vias allowed)
			(pads allowed)
			(copperpour not_allowed)
			(footprints allowed)
		)
		(placement
			(enabled no)
			(sheetname "")
		)
		(fill
			(thermal_gap 0.5)
			(thermal_bridge_width 0.5)
			(island_removal_mode 0)
		)
		(polygon
			(pts
				(arc
					(start 11.599926 -118.100094)
					(mid 16.599916 -113.100104)
					(end 21.599906 -118.100094)
				)
				(arc
					(start 21.599906 -118.100094)
					(mid 16.599916 -123.100084)
					(end 11.599926 -118.100094)
				)
			)
		)
	)
	(zone
		(layer "F.Cu")
		(hatch none 0.5)
		(connect_pads
			(clearance 0)
		)
		(min_thickness 0.25)
		(keepout
			(tracks allowed)
			(vias allowed)
			(pads allowed)
			(copperpour allowed)
			(footprints not_allowed)
		)
		(placement
			(enabled no)
			(sheetname "")
		)
		(fill
			(thermal_gap 0.5)
			(thermal_bridge_width 0.5)
			(island_removal_mode 0)
		)
		(polygon
			(pts
				(arc
					(start 21.599906 -207.000094)
					(mid 16.599916 -212.000084)
					(end 11.599926 -207.000094)
				)
				(arc
					(start 11.599926 -207.000094)
					(mid 16.599916 -202.000104)
					(end 21.599906 -207.000094)
				)
			)
		)
	)
	(zone
		(layer "F.Cu")
		(hatch none 0.5)
		(connect_pads
			(clearance 0)
		)
		(min_thickness 0.25)
		(keepout
			(tracks allowed)
			(vias allowed)
			(pads allowed)
			(copperpour allowed)
			(footprints not_allowed)
		)
		(placement
			(enabled no)
			(sheetname "")
		)
		(fill
			(thermal_gap 0.5)
			(thermal_bridge_width 0.5)
			(island_removal_mode 0)
		)
		(polygon
			(pts
				(xy 55.999888 -479.799904) (xy 55.999888 -454.799954) (xy 44.99991 -454.799954) (xy 44.99991 -479.799904)
			)
		)
	)
	(zone
		(layer "F.Cu")
		(hatch none 0.5)
		(connect_pads
			(clearance 0)
		)
		(min_thickness 0.25)
		(keepout
			(tracks not_allowed)
			(vias allowed)
			(pads allowed)
			(copperpour not_allowed)
			(footprints allowed)
		)
		(placement
			(enabled no)
			(sheetname "")
		)
		(fill
			(thermal_gap 0.5)
			(thermal_bridge_width 0.5)
			(island_removal_mode 0)
		)
		(polygon
			(pts
				(arc
					(start 16.599916 -215.00084)
					(mid 15.164816 -213.56574)
					(end 16.599916 -212.13064)
				)
				(arc
					(start 16.599916 -212.13064)
					(mid 21.730716 -206.99984)
					(end 16.599916 -201.86904)
				)
				(arc
					(start 16.599916 -201.86904)
					(mid 15.164816 -200.43394)
					(end 16.599916 -198.99884)
				)
				(arc
					(start 16.599916 -198.99884)
					(mid 24.600916 -206.99984)
					(end 16.599916 -215.00084)
				)
			)
		)
	)
	(zone
		(layer "F.Cu")
		(hatch none 0.5)
		(connect_pads
			(clearance 0)
		)
		(min_thickness 0.25)
		(keepout
			(tracks not_allowed)
			(vias allowed)
			(pads allowed)
			(copperpour not_allowed)
			(footprints allowed)
		)
		(placement
			(enabled no)
			(sheetname "")
		)
		(fill
			(thermal_gap 0.5)
			(thermal_bridge_width 0.5)
			(island_removal_mode 0)
		)
		(polygon
			(pts
				(arc
					(start 77.999844 -349.251016)
					(mid 76.564744 -347.815916)
					(end 77.999844 -346.380816)
				)
				(arc
					(start 77.999844 -346.380816)
					(mid 83.130644 -341.250016)
					(end 77.999844 -336.119216)
				)
				(arc
					(start 77.999844 -336.119216)
					(mid 76.564744 -334.684116)
					(end 77.999844 -333.249016)
				)
				(arc
					(start 77.999844 -333.249016)
					(mid 86.000844 -341.250016)
					(end 77.999844 -349.251016)
				)
			)
		)
	)
	(zone
		(layer "F.Cu")
		(hatch none 0.5)
		(connect_pads
			(clearance 0)
		)
		(min_thickness 0.25)
		(keepout
			(tracks not_allowed)
			(vias allowed)
			(pads allowed)
			(copperpour not_allowed)
			(footprints allowed)
		)
		(placement
			(enabled no)
			(sheetname "")
		)
		(fill
			(thermal_gap 0.5)
			(thermal_bridge_width 0.5)
			(island_removal_mode 0)
		)
		(polygon
			(pts
				(arc
					(start 11.599926 -384.800094)
					(mid 16.599916 -379.800104)
					(end 21.599906 -384.800094)
				)
				(arc
					(start 21.599906 -384.800094)
					(mid 16.599916 -389.800084)
					(end 11.599926 -384.800094)
				)
			)
		)
	)
	(zone
		(layer "F.Cu")
		(hatch none 0.5)
		(connect_pads
			(clearance 0)
		)
		(min_thickness 0.25)
		(keepout
			(tracks allowed)
			(vias allowed)
			(pads allowed)
			(copperpour allowed)
			(footprints not_allowed)
		)
		(placement
			(enabled no)
			(sheetname "")
		)
		(fill
			(thermal_gap 0.5)
			(thermal_bridge_width 0.5)
			(island_removal_mode 0)
		)
		(polygon
			(pts
				(xy 13.875004 -420.900098) (xy 2.325116 -420.900098) (xy 2.325116 -464.90001) (xy 13.875004 -464.90001)
			)
		)
	)
	(zone
		(layer "F.Cu")
		(hatch none 0.5)
		(connect_pads
			(clearance 0)
		)
		(min_thickness 0.25)
		(keepout
			(tracks not_allowed)
			(vias allowed)
			(pads allowed)
			(copperpour not_allowed)
			(footprints allowed)
		)
		(placement
			(enabled no)
			(sheetname "")
		)
		(fill
			(thermal_gap 0.5)
			(thermal_bridge_width 0.5)
			(island_removal_mode 0)
		)
		(polygon
			(pts
				(arc
					(start 96.320864 -505.85878)
					(mid 97.946464 -504.23318)
					(end 99.572064 -505.85878)
				)
				(arc
					(start 99.572064 -505.85878)
					(mid 97.946464 -507.48438)
					(end 96.320864 -505.85878)
				)
			)
		)
	)
	(zone
		(layer "F.Cu")
		(hatch none 0.5)
		(connect_pads
			(clearance 0)
		)
		(min_thickness 0.25)
		(keepout
			(tracks allowed)
			(vias allowed)
			(pads allowed)
			(copperpour allowed)
			(footprints not_allowed)
		)
		(placement
			(enabled no)
			(sheetname "")
		)
		(fill
			(thermal_gap 0.5)
			(thermal_bridge_width 0.5)
			(island_removal_mode 0)
		)
		(polygon
			(pts
				(xy 55.999888 -188.099954) (xy 44.99991 -188.099954) (xy 44.99991 -213.099904) (xy 55.999888 -213.099904)
			)
		)
	)
	(zone
		(layer "F.Cu")
		(hatch none 0.5)
		(connect_pads
			(clearance 0)
		)
		(min_thickness 0.25)
		(keepout
			(tracks allowed)
			(vias allowed)
			(pads allowed)
			(copperpour allowed)
			(footprints not_allowed)
		)
		(placement
			(enabled no)
			(sheetname "")
		)
		(fill
			(thermal_gap 0.5)
			(thermal_bridge_width 0.5)
			(island_removal_mode 0)
		)
		(polygon
			(pts
				(arc
					(start 74.399902 -477.799908)
					(mid 78.000098 -474.199712)
					(end 81.60004 -477.799908)
				)
				(arc
					(start 81.60004 -478.799906)
					(mid 78.000098 -482.399848)
					(end 74.399902 -478.799906)
				)
			)
		)
	)
	(zone
		(layer "F.Cu")
		(hatch none 0.5)
		(connect_pads
			(clearance 0)
		)
		(min_thickness 0.25)
		(keepout
			(tracks not_allowed)
			(vias allowed)
			(pads allowed)
			(copperpour not_allowed)
			(footprints allowed)
		)
		(placement
			(enabled no)
			(sheetname "")
		)
		(fill
			(thermal_gap 0.5)
			(thermal_bridge_width 0.5)
			(island_removal_mode 0)
		)
		(polygon
			(pts
				(arc
					(start 86.399878 -108.91012)
					(mid 91.400122 -103.909876)
					(end 96.400112 -108.91012)
				)
				(arc
					(start 96.400112 -108.91012)
					(mid 91.400122 -113.91011)
					(end 86.399878 -108.91012)
				)
			)
		)
	)
	(zone
		(layer "F.Cu")
		(hatch none 0.5)
		(connect_pads
			(clearance 0)
		)
		(min_thickness 0.25)
		(keepout
			(tracks not_allowed)
			(vias allowed)
			(pads allowed)
			(copperpour not_allowed)
			(footprints allowed)
		)
		(placement
			(enabled no)
			(sheetname "")
		)
		(fill
			(thermal_gap 0.5)
			(thermal_bridge_width 0.5)
			(island_removal_mode 0)
		)
		(polygon
			(pts
				(arc
					(start 18.599912 -29.200094)
					(mid 16.599916 -31.20009)
					(end 14.59992 -29.200094)
				)
				(arc
					(start 14.59992 -29.200094)
					(mid 16.599916 -27.200098)
					(end 18.599912 -29.200094)
				)
			)
		)
	)
	(zone
		(layer "F.Cu")
		(hatch none 0.5)
		(connect_pads
			(clearance 0)
		)
		(min_thickness 0.25)
		(keepout
			(tracks allowed)
			(vias allowed)
			(pads allowed)
			(copperpour allowed)
			(footprints not_allowed)
		)
		(placement
			(enabled no)
			(sheetname "")
		)
		(fill
			(thermal_gap 0.5)
			(thermal_bridge_width 0.5)
			(island_removal_mode 0)
		)
		(polygon
			(pts
				(xy 55.999888 -79.749904) (xy 55.999888 -54.749954) (xy 44.99991 -54.749954) (xy 44.99991 -79.749904)
			)
		)
	)
	(zone
		(layer "F.Cu")
		(hatch none 0.5)
		(connect_pads
			(clearance 0)
		)
		(min_thickness 0.25)
		(keepout
			(tracks not_allowed)
			(vias allowed)
			(pads allowed)
			(copperpour not_allowed)
			(footprints allowed)
		)
		(placement
			(enabled no)
			(sheetname "")
		)
		(fill
			(thermal_gap 0.5)
			(thermal_bridge_width 0.5)
			(island_removal_mode 0)
		)
		(polygon
			(pts
				(arc
					(start 16.599916 -34.33064)
					(mid 18.035016 -35.76574)
					(end 16.599916 -37.20084)
				)
				(arc
					(start 16.599916 -37.20084)
					(mid 8.598916 -29.19984)
					(end 16.599916 -21.19884)
				)
				(arc
					(start 16.599916 -21.19884)
					(mid 18.035016 -22.63394)
					(end 16.599916 -24.06904)
				)
				(arc
					(start 16.599916 -24.06904)
					(mid 11.469116 -29.19984)
					(end 16.599916 -34.33064)
				)
			)
		)
	)
	(zone
		(layer "F.Cu")
		(hatch none 0.5)
		(connect_pads
			(clearance 0)
		)
		(min_thickness 0.25)
		(keepout
			(tracks not_allowed)
			(vias allowed)
			(pads allowed)
			(copperpour not_allowed)
			(footprints allowed)
		)
		(placement
			(enabled no)
			(sheetname "")
		)
		(fill
			(thermal_gap 0.5)
			(thermal_bridge_width 0.5)
			(island_removal_mode 0)
		)
		(polygon
			(pts
				(arc
					(start 73.000108 -121.19991)
					(mid 78.000098 -116.19992)
					(end 83.000088 -121.19991)
				)
				(arc
					(start 83.000088 -121.19991)
					(mid 78.000098 -126.1999)
					(end 73.000108 -121.19991)
				)
			)
		)
	)
	(zone
		(layer "F.Cu")
		(hatch none 0.5)
		(connect_pads
			(clearance 0)
		)
		(min_thickness 0.25)
		(keepout
			(tracks not_allowed)
			(vias allowed)
			(pads allowed)
			(copperpour not_allowed)
			(footprints allowed)
		)
		(placement
			(enabled no)
			(sheetname "")
		)
		(fill
			(thermal_gap 0.5)
			(thermal_bridge_width 0.5)
			(island_removal_mode 0)
		)
		(polygon
			(pts
				(arc
					(start 80.000094 -121.19991)
					(mid 78.000098 -123.199906)
					(end 76.000102 -121.19991)
				)
				(arc
					(start 76.000102 -121.19991)
					(mid 78.000098 -119.199914)
					(end 80.000094 -121.19991)
				)
			)
		)
	)
	(zone
		(layer "F.Cu")
		(hatch none 0.5)
		(connect_pads
			(clearance 0)
		)
		(min_thickness 0.25)
		(keepout
			(tracks not_allowed)
			(vias allowed)
			(pads allowed)
			(copperpour not_allowed)
			(footprints allowed)
		)
		(placement
			(enabled no)
			(sheetname "")
		)
		(fill
			(thermal_gap 0.5)
			(thermal_bridge_width 0.5)
			(island_removal_mode 0)
		)
		(polygon
			(pts
				(arc
					(start 86.399878 -153.36012)
					(mid 91.400122 -148.359876)
					(end 96.400112 -153.36012)
				)
				(arc
					(start 96.400112 -153.36012)
					(mid 91.400122 -158.36011)
					(end 86.399878 -153.36012)
				)
			)
		)
	)
	(zone
		(layer "F.Cu")
		(hatch none 0.5)
		(connect_pads
			(clearance 0)
		)
		(min_thickness 0.25)
		(keepout
			(tracks allowed)
			(vias allowed)
			(pads allowed)
			(copperpour allowed)
			(footprints not_allowed)
		)
		(placement
			(enabled no)
			(sheetname "")
		)
		(fill
			(thermal_gap 0.5)
			(thermal_bridge_width 0.5)
			(island_removal_mode 0)
		)
		(polygon
			(pts
				(arc
					(start 96.400112 -331.16012)
					(mid 91.400122 -336.16011)
					(end 86.399878 -331.16012)
				)
				(arc
					(start 86.399878 -331.16012)
					(mid 91.400122 -326.159876)
					(end 96.400112 -331.16012)
				)
			)
		)
	)
	(zone
		(layer "F.Cu")
		(hatch none 0.5)
		(connect_pads
			(clearance 0)
		)
		(min_thickness 0.25)
		(keepout
			(tracks not_allowed)
			(vias allowed)
			(pads allowed)
			(copperpour not_allowed)
			(footprints allowed)
		)
		(placement
			(enabled no)
			(sheetname "")
		)
		(fill
			(thermal_gap 0.5)
			(thermal_bridge_width 0.5)
			(island_removal_mode 0)
		)
		(polygon
			(pts
				(arc
					(start 80.000094 -430.150016)
					(mid 78.000098 -432.150012)
					(end 76.000102 -430.150016)
				)
				(arc
					(start 76.000102 -430.150016)
					(mid 78.000098 -428.15002)
					(end 80.000094 -430.150016)
				)
			)
		)
	)
	(zone
		(layer "F.Cu")
		(hatch none 0.5)
		(connect_pads
			(clearance 0)
		)
		(min_thickness 0.25)
		(keepout
			(tracks allowed)
			(vias allowed)
			(pads allowed)
			(copperpour allowed)
			(footprints not_allowed)
		)
		(placement
			(enabled no)
			(sheetname "")
		)
		(fill
			(thermal_gap 0.5)
			(thermal_bridge_width 0.5)
			(island_removal_mode 0)
		)
		(polygon
			(pts
				(arc
					(start 11.599926 -29.200094)
					(mid 16.599916 -24.200104)
					(end 21.599906 -29.200094)
				)
				(arc
					(start 21.599906 -29.200094)
					(mid 16.599916 -34.200084)
					(end 11.599926 -29.200094)
				)
			)
		)
	)
	(zone
		(layer "F.Cu")
		(hatch none 0.5)
		(connect_pads
			(clearance 0)
		)
		(min_thickness 0.25)
		(keepout
			(tracks not_allowed)
			(vias allowed)
			(pads allowed)
			(copperpour not_allowed)
			(footprints allowed)
		)
		(placement
			(enabled no)
			(sheetname "")
		)
		(fill
			(thermal_gap 0.5)
			(thermal_bridge_width 0.5)
			(island_removal_mode 0)
		)
		(polygon
			(pts
				(arc
					(start 11.599926 -295.900094)
					(mid 16.599916 -290.900104)
					(end 21.599906 -295.900094)
				)
				(arc
					(start 21.599906 -295.900094)
					(mid 16.599916 -300.900084)
					(end 11.599926 -295.900094)
				)
			)
		)
	)
	(zone
		(layer "F.Cu")
		(hatch none 0.5)
		(connect_pads
			(clearance 0)
		)
		(min_thickness 0.25)
		(keepout
			(tracks not_allowed)
			(vias allowed)
			(pads allowed)
			(copperpour not_allowed)
			(footprints allowed)
		)
		(placement
			(enabled no)
			(sheetname "")
		)
		(fill
			(thermal_gap 0.5)
			(thermal_bridge_width 0.5)
			(island_removal_mode 0)
		)
		(polygon
			(pts
				(arc
					(start 16.599916 -303.90084)
					(mid 15.164816 -302.46574)
					(end 16.599916 -301.03064)
				)
				(arc
					(start 16.599916 -301.03064)
					(mid 21.730716 -295.89984)
					(end 16.599916 -290.76904)
				)
				(arc
					(start 16.599916 -290.76904)
					(mid 15.164816 -289.33394)
					(end 16.599916 -287.89884)
				)
				(arc
					(start 16.599916 -287.89884)
					(mid 24.600916 -295.89984)
					(end 16.599916 -303.90084)
				)
			)
		)
	)
	(zone
		(layer "F.Cu")
		(hatch none 0.5)
		(connect_pads
			(clearance 0)
		)
		(min_thickness 0.25)
		(keepout
			(tracks not_allowed)
			(vias allowed)
			(pads allowed)
			(copperpour not_allowed)
			(footprints allowed)
		)
		(placement
			(enabled no)
			(sheetname "")
		)
		(fill
			(thermal_gap 0.5)
			(thermal_bridge_width 0.5)
			(island_removal_mode 0)
		)
		(polygon
			(pts
				(arc
					(start 78.000098 -524.180562)
					(mid 79.435198 -525.615662)
					(end 78.000098 -527.050762)
				)
				(arc
					(start 78.000098 -527.050762)
					(mid 69.999098 -519.049762)
					(end 78.000098 -511.048762)
				)
				(arc
					(start 78.000098 -511.048762)
					(mid 79.435198 -512.483862)
					(end 78.000098 -513.918962)
				)
				(arc
					(start 78.000098 -513.918962)
					(mid 72.869298 -519.049762)
					(end 78.000098 -524.180562)
				)
			)
		)
	)
	(zone
		(layer "F.Cu")
		(hatch none 0.5)
		(connect_pads
			(clearance 0)
		)
		(min_thickness 0.25)
		(keepout
			(tracks not_allowed)
			(vias allowed)
			(pads allowed)
			(copperpour not_allowed)
			(footprints allowed)
		)
		(placement
			(enabled no)
			(sheetname "")
		)
		(fill
			(thermal_gap 0.5)
			(thermal_bridge_width 0.5)
			(island_removal_mode 0)
		)
		(polygon
			(pts
				(arc
					(start 73.000108 -210.09991)
					(mid 78.000098 -205.09992)
					(end 83.000088 -210.09991)
				)
				(arc
					(start 83.000088 -210.09991)
					(mid 78.000098 -215.0999)
					(end 73.000108 -210.09991)
				)
			)
		)
	)
	(zone
		(layer "F.Cu")
		(hatch none 0.5)
		(connect_pads
			(clearance 0)
		)
		(min_thickness 0.25)
		(keepout
			(tracks allowed)
			(vias allowed)
			(pads allowed)
			(copperpour allowed)
			(footprints not_allowed)
		)
		(placement
			(enabled no)
			(sheetname "")
		)
		(fill
			(thermal_gap 0.5)
			(thermal_bridge_width 0.5)
			(island_removal_mode 0)
		)
		(polygon
			(pts
				(arc
					(start 96.400112 -20.01012)
					(mid 91.400122 -25.01011)
					(end 86.399878 -20.01012)
				)
				(arc
					(start 86.399878 -20.01012)
					(mid 91.400122 -15.009876)
					(end 96.400112 -20.01012)
				)
			)
		)
	)
	(zone
		(layer "F.Cu")
		(hatch none 0.5)
		(connect_pads
			(clearance 0)
		)
		(min_thickness 0.25)
		(keepout
			(tracks allowed)
			(vias allowed)
			(pads allowed)
			(copperpour allowed)
			(footprints not_allowed)
		)
		(placement
			(enabled no)
			(sheetname "")
		)
		(fill
			(thermal_gap 0.5)
			(thermal_bridge_width 0.5)
			(island_removal_mode 0)
		)
		(polygon
			(pts
				(xy 37.975032 -176.440084) (xy 37.975032 -88.330024) (xy 28.02509 -88.330024) (xy 28.02509 -176.440084)
			)
		)
	)
	(zone
		(layer "F.Cu")
		(hatch none 0.5)
		(connect_pads
			(clearance 0)
		)
		(min_thickness 0.25)
		(keepout
			(tracks not_allowed)
			(vias allowed)
			(pads allowed)
			(copperpour not_allowed)
			(footprints allowed)
		)
		(placement
			(enabled no)
			(sheetname "")
		)
		(fill
			(thermal_gap 0.5)
			(thermal_bridge_width 0.5)
			(island_removal_mode 0)
		)
		(polygon
			(pts
				(arc
					(start 77.999844 -40.30091)
					(mid 76.564744 -38.86581)
					(end 77.999844 -37.43071)
				)
				(arc
					(start 77.999844 -37.43071)
					(mid 83.130644 -32.29991)
					(end 77.999844 -27.16911)
				)
				(arc
					(start 77.999844 -27.16911)
					(mid 76.564744 -25.73401)
					(end 77.999844 -24.29891)
				)
				(arc
					(start 77.999844 -24.29891)
					(mid 86.000844 -32.29991)
					(end 77.999844 -40.30091)
				)
			)
		)
	)
	(zone
		(layer "F.Cu")
		(hatch none 0.5)
		(connect_pads
			(clearance 0)
		)
		(min_thickness 0.25)
		(keepout
			(tracks not_allowed)
			(vias allowed)
			(pads allowed)
			(copperpour not_allowed)
			(footprints allowed)
		)
		(placement
			(enabled no)
			(sheetname "")
		)
		(fill
			(thermal_gap 0.5)
			(thermal_bridge_width 0.5)
			(island_removal_mode 0)
		)
		(polygon
			(pts
				(arc
					(start 77.999844 -37.43071)
					(mid 79.434944 -38.86581)
					(end 77.999844 -40.30091)
				)
				(arc
					(start 77.999844 -40.30091)
					(mid 69.998844 -32.29991)
					(end 77.999844 -24.29891)
				)
				(arc
					(start 77.999844 -24.29891)
					(mid 79.434944 -25.73401)
					(end 77.999844 -27.16911)
				)
				(arc
					(start 77.999844 -27.16911)
					(mid 72.869044 -32.29991)
					(end 77.999844 -37.43071)
				)
			)
		)
	)
	(zone
		(layer "F.Cu")
		(hatch none 0.5)
		(connect_pads
			(clearance 0)
		)
		(min_thickness 0.25)
		(keepout
			(tracks allowed)
			(vias allowed)
			(pads allowed)
			(copperpour allowed)
			(footprints not_allowed)
		)
		(placement
			(enabled no)
			(sheetname "")
		)
		(fill
			(thermal_gap 0.5)
			(thermal_bridge_width 0.5)
			(island_removal_mode 0)
		)
		(polygon
			(pts
				(arc
					(start 11.599926 -384.800094)
					(mid 16.599916 -379.800104)
					(end 21.599906 -384.800094)
				)
				(arc
					(start 21.599906 -384.800094)
					(mid 16.599916 -389.800084)
					(end 11.599926 -384.800094)
				)
			)
		)
	)
	(zone
		(layer "F.Cu")
		(hatch none 0.5)
		(connect_pads
			(clearance 0)
		)
		(min_thickness 0.25)
		(keepout
			(tracks not_allowed)
			(vias allowed)
			(pads allowed)
			(copperpour not_allowed)
			(footprints allowed)
		)
		(placement
			(enabled no)
			(sheetname "")
		)
		(fill
			(thermal_gap 0.5)
			(thermal_bridge_width 0.5)
			(island_removal_mode 0)
		)
		(polygon
			(pts
				(arc
					(start 16.599916 -126.10084)
					(mid 15.164816 -124.66574)
					(end 16.599916 -123.23064)
				)
				(arc
					(start 16.599916 -123.23064)
					(mid 21.730716 -118.09984)
					(end 16.599916 -112.96904)
				)
				(arc
					(start 16.599916 -112.96904)
					(mid 15.164816 -111.53394)
					(end 16.599916 -110.09884)
				)
				(arc
					(start 16.599916 -110.09884)
					(mid 24.600916 -118.09984)
					(end 16.599916 -126.10084)
				)
			)
		)
	)
	(zone
		(layer "F.Cu")
		(hatch none 0.5)
		(connect_pads
			(clearance 0)
		)
		(min_thickness 0.25)
		(keepout
			(tracks allowed)
			(vias allowed)
			(pads allowed)
			(copperpour allowed)
			(footprints not_allowed)
		)
		(placement
			(enabled no)
			(sheetname "")
		)
		(fill
			(thermal_gap 0.5)
			(thermal_bridge_width 0.5)
			(island_removal_mode 0)
		)
		(polygon
			(pts
				(xy 9.400032 -355.970078) (xy 9.400032 -175.369982) (xy 0.999998 -175.369982) (xy 0.999998 -355.970078)
			)
		)
	)
	(zone
		(layer "F.Cu")
		(hatch none 0.5)
		(connect_pads
			(clearance 0)
		)
		(min_thickness 0.25)
		(keepout
			(tracks not_allowed)
			(vias allowed)
			(pads allowed)
			(copperpour not_allowed)
			(footprints allowed)
		)
		(placement
			(enabled no)
			(sheetname "")
		)
		(fill
			(thermal_gap 0.5)
			(thermal_bridge_width 0.5)
			(island_removal_mode 0)
		)
		(polygon
			(pts
				(arc
					(start 73.000108 -32.29991)
					(mid 78.000098 -27.29992)
					(end 83.000088 -32.29991)
				)
				(arc
					(start 83.000088 -32.29991)
					(mid 78.000098 -37.2999)
					(end 73.000108 -32.29991)
				)
			)
		)
	)
	(zone
		(layer "F.Cu")
		(hatch none 0.5)
		(connect_pads
			(clearance 0)
		)
		(min_thickness 0.25)
		(keepout
			(tracks not_allowed)
			(vias allowed)
			(pads allowed)
			(copperpour not_allowed)
			(footprints allowed)
		)
		(placement
			(enabled no)
			(sheetname "")
		)
		(fill
			(thermal_gap 0.5)
			(thermal_bridge_width 0.5)
			(island_removal_mode 0)
		)
		(polygon
			(pts
				(arc
					(start 16.599916 -389.93064)
					(mid 18.035016 -391.36574)
					(end 16.599916 -392.80084)
				)
				(arc
					(start 16.599916 -392.80084)
					(mid 8.598916 -384.79984)
					(end 16.599916 -376.79884)
				)
				(arc
					(start 16.599916 -376.79884)
					(mid 18.035016 -378.23394)
					(end 16.599916 -379.66904)
				)
				(arc
					(start 16.599916 -379.66904)
					(mid 11.469116 -384.79984)
					(end 16.599916 -389.93064)
				)
			)
		)
	)
	(zone
		(layer "F.Cu")
		(hatch none 0.5)
		(connect_pads
			(clearance 0)
		)
		(min_thickness 0.25)
		(keepout
			(tracks not_allowed)
			(vias allowed)
			(pads allowed)
			(copperpour not_allowed)
			(footprints allowed)
		)
		(placement
			(enabled no)
			(sheetname "")
		)
		(fill
			(thermal_gap 0.5)
			(thermal_bridge_width 0.5)
			(island_removal_mode 0)
		)
		(polygon
			(pts
				(arc
					(start 73.000108 -341.250016)
					(mid 78.000098 -336.250026)
					(end 83.000088 -341.250016)
				)
				(arc
					(start 83.000088 -341.250016)
					(mid 78.000098 -346.250006)
					(end 73.000108 -341.250016)
				)
			)
		)
	)
	(zone
		(layer "F.Cu")
		(hatch none 0.5)
		(connect_pads
			(clearance 0)
		)
		(min_thickness 0.25)
		(keepout
			(tracks allowed)
			(vias allowed)
			(pads allowed)
			(copperpour allowed)
			(footprints not_allowed)
		)
		(placement
			(enabled no)
			(sheetname "")
		)
		(fill
			(thermal_gap 0.5)
			(thermal_bridge_width 0.5)
			(island_removal_mode 0)
		)
		(polygon
			(pts
				(arc
					(start 101.000052 -0.999998)
					(mid 101.707157 -1.292891)
					(end 102.00005 -1.999996)
				)
				(arc
					(start 102.00005 -527.99996)
					(mid 101.707157 -528.707065)
					(end 101.000052 -528.999958)
				)
				(xy 40.999918 -528.999958) (xy 40.999918 -0.999998)
			)
		)
	)
	(zone
		(layer "F.Cu")
		(hatch none 0.5)
		(connect_pads
			(clearance 0)
		)
		(min_thickness 0.25)
		(keepout
			(tracks not_allowed)
			(vias allowed)
			(pads allowed)
			(copperpour not_allowed)
			(footprints allowed)
		)
		(placement
			(enabled no)
			(sheetname "")
		)
		(fill
			(thermal_gap 0.5)
			(thermal_bridge_width 0.5)
			(island_removal_mode 0)
		)
		(polygon
			(pts
				(arc
					(start 11.599926 -207.000094)
					(mid 16.599916 -202.000104)
					(end 21.599906 -207.000094)
				)
				(arc
					(start 21.599906 -207.000094)
					(mid 16.599916 -212.000084)
					(end 11.599926 -207.000094)
				)
			)
		)
	)
	(zone
		(layer "F.Cu")
		(hatch none 0.5)
		(connect_pads
			(clearance 0)
		)
		(min_thickness 0.25)
		(keepout
			(tracks not_allowed)
			(vias allowed)
			(pads allowed)
			(copperpour not_allowed)
			(footprints allowed)
		)
		(placement
			(enabled no)
			(sheetname "")
		)
		(fill
			(thermal_gap 0.5)
			(thermal_bridge_width 0.5)
			(island_removal_mode 0)
		)
		(polygon
			(pts
				(arc
					(start 74.399902 -78.300072)
					(mid 78.000098 -74.699876)
					(end 81.60004 -78.300072)
				)
				(arc
					(start 81.60004 -78.300072)
					(mid 78.000098 -81.900014)
					(end 74.399902 -78.300072)
				)
			)
		)
	)
	(zone
		(layer "F.Cu")
		(hatch none 0.5)
		(connect_pads
			(clearance 0)
		)
		(min_thickness 0.25)
		(keepout
			(tracks not_allowed)
			(vias allowed)
			(pads allowed)
			(copperpour not_allowed)
			(footprints allowed)
		)
		(placement
			(enabled no)
			(sheetname "")
		)
		(fill
			(thermal_gap 0.5)
			(thermal_bridge_width 0.5)
			(island_removal_mode 0)
		)
		(polygon
			(pts
				(arc
					(start 95.400114 -420.06012)
					(mid 91.400122 -424.060112)
					(end 87.399876 -420.06012)
				)
				(arc
					(start 87.399876 -420.06012)
					(mid 91.400122 -416.059874)
					(end 95.400114 -420.06012)
				)
			)
		)
	)
	(zone
		(layer "F.Cu")
		(hatch none 0.5)
		(connect_pads
			(clearance 0)
		)
		(min_thickness 0.25)
		(keepout
			(tracks allowed)
			(vias allowed)
			(pads allowed)
			(copperpour allowed)
			(footprints not_allowed)
		)
		(placement
			(enabled no)
			(sheetname "")
		)
		(fill
			(thermal_gap 0.5)
			(thermal_bridge_width 0.5)
			(island_removal_mode 0)
		)
		(polygon
			(pts
				(xy 55.999888 -232.549954) (xy 44.99991 -232.549954) (xy 44.99991 -257.549904) (xy 55.999888 -257.549904)
			)
		)
	)
	(zone
		(layer "F.Cu")
		(hatch none 0.5)
		(connect_pads
			(clearance 0)
		)
		(min_thickness 0.25)
		(keepout
			(tracks allowed)
			(vias allowed)
			(pads allowed)
			(copperpour allowed)
			(footprints not_allowed)
		)
		(placement
			(enabled no)
			(sheetname "")
		)
		(fill
			(thermal_gap 0.5)
			(thermal_bridge_width 0.5)
			(island_removal_mode 0)
		)
		(polygon
			(pts
				(arc
					(start 96.400112 -420.06012)
					(mid 91.400122 -425.06011)
					(end 86.399878 -420.06012)
				)
				(arc
					(start 86.399878 -420.06012)
					(mid 91.400122 -415.059876)
					(end 96.400112 -420.06012)
				)
			)
		)
	)
	(zone
		(layer "F.Cu")
		(hatch none 0.5)
		(connect_pads
			(clearance 0)
		)
		(min_thickness 0.25)
		(keepout
			(tracks not_allowed)
			(vias allowed)
			(pads allowed)
			(copperpour not_allowed)
			(footprints allowed)
		)
		(placement
			(enabled no)
			(sheetname "")
		)
		(fill
			(thermal_gap 0.5)
			(thermal_bridge_width 0.5)
			(island_removal_mode 0)
		)
		(polygon
			(pts
				(arc
					(start 16.599916 -123.23064)
					(mid 18.035016 -124.66574)
					(end 16.599916 -126.10084)
				)
				(arc
					(start 16.599916 -126.10084)
					(mid 8.598916 -118.09984)
					(end 16.599916 -110.09884)
				)
				(arc
					(start 16.599916 -110.09884)
					(mid 18.035016 -111.53394)
					(end 16.599916 -112.96904)
				)
				(arc
					(start 16.599916 -112.96904)
					(mid 11.469116 -118.09984)
					(end 16.599916 -123.23064)
				)
			)
		)
	)
	(zone
		(layer "F.Cu")
		(hatch none 0.5)
		(connect_pads
			(clearance 0)
		)
		(min_thickness 0.25)
		(keepout
			(tracks not_allowed)
			(vias allowed)
			(pads allowed)
			(copperpour not_allowed)
			(footprints allowed)
		)
		(placement
			(enabled no)
			(sheetname "")
		)
		(fill
			(thermal_gap 0.5)
			(thermal_bridge_width 0.5)
			(island_removal_mode 0)
		)
		(polygon
			(pts
				(arc
					(start 86.399878 -20.01012)
					(mid 91.400122 -15.009876)
					(end 96.400112 -20.01012)
				)
				(arc
					(start 96.400112 -20.01012)
					(mid 91.400122 -25.01011)
					(end 86.399878 -20.01012)
				)
			)
		)
	)
	(zone
		(layer "F.Cu")
		(hatch none 0.5)
		(connect_pads
			(clearance 0)
		)
		(min_thickness 0.25)
		(keepout
			(tracks not_allowed)
			(vias allowed)
			(pads allowed)
			(copperpour not_allowed)
			(footprints allowed)
		)
		(placement
			(enabled no)
			(sheetname "")
		)
		(fill
			(thermal_gap 0.5)
			(thermal_bridge_width 0.5)
			(island_removal_mode 0)
		)
		(polygon
			(pts
				(arc
					(start 86.399878 -375.61012)
					(mid 91.400122 -370.609876)
					(end 96.400112 -375.61012)
				)
				(arc
					(start 96.400112 -375.61012)
					(mid 91.400122 -380.61011)
					(end 86.399878 -375.61012)
				)
			)
		)
	)
	(zone
		(layer "F.Cu")
		(hatch none 0.5)
		(connect_pads
			(clearance 0)
		)
		(min_thickness 0.25)
		(keepout
			(tracks not_allowed)
			(vias allowed)
			(pads allowed)
			(copperpour not_allowed)
			(footprints allowed)
		)
		(placement
			(enabled no)
			(sheetname "")
		)
		(fill
			(thermal_gap 0.5)
			(thermal_bridge_width 0.5)
			(island_removal_mode 0)
		)
		(polygon
			(pts
				(arc
					(start 18.599912 -207.000094)
					(mid 16.599916 -209.00009)
					(end 14.59992 -207.000094)
				)
				(arc
					(start 14.59992 -207.000094)
					(mid 16.599916 -205.000098)
					(end 18.599912 -207.000094)
				)
			)
		)
	)
	(zone
		(layer "F.Cu")
		(hatch none 0.5)
		(connect_pads
			(clearance 0)
		)
		(min_thickness 0.25)
		(keepout
			(tracks allowed)
			(vias allowed)
			(pads allowed)
			(copperpour allowed)
			(footprints not_allowed)
		)
		(placement
			(enabled no)
			(sheetname "")
		)
		(fill
			(thermal_gap 0.5)
			(thermal_bridge_width 0.5)
			(island_removal_mode 0)
		)
		(polygon
			(pts
				(arc
					(start 96.400112 -286.71012)
					(mid 91.400122 -291.71011)
					(end 86.399878 -286.71012)
				)
				(arc
					(start 86.399878 -286.71012)
					(mid 91.400122 -281.709876)
					(end 96.400112 -286.71012)
				)
			)
		)
	)
	(zone
		(layer "F.Cu")
		(hatch none 0.5)
		(connect_pads
			(clearance 0)
		)
		(min_thickness 0.25)
		(keepout
			(tracks allowed)
			(vias allowed)
			(pads allowed)
			(copperpour allowed)
			(footprints not_allowed)
		)
		(placement
			(enabled no)
			(sheetname "")
		)
		(fill
			(thermal_gap 0.5)
			(thermal_bridge_width 0.5)
			(island_removal_mode 0)
		)
		(polygon
			(pts
				(xy 55.999888 -435.349904) (xy 55.999888 -410.349954) (xy 44.99991 -410.349954) (xy 44.99991 -435.349904)
			)
		)
	)
	(zone
		(layer "F.Cu")
		(hatch none 0.5)
		(connect_pads
			(clearance 0)
		)
		(min_thickness 0.25)
		(keepout
			(tracks allowed)
			(vias allowed)
			(pads allowed)
			(copperpour allowed)
			(footprints not_allowed)
		)
		(placement
			(enabled no)
			(sheetname "")
		)
		(fill
			(thermal_gap 0.5)
			(thermal_bridge_width 0.5)
			(island_removal_mode 0)
		)
		(polygon
			(pts
				(xy 55.999888 -301.999904) (xy 55.999888 -276.999954) (xy 44.99991 -276.999954) (xy 44.99991 -301.999904)
			)
		)
	)
	(zone
		(layer "F.Cu")
		(hatch none 0.5)
		(connect_pads
			(clearance 0)
		)
		(min_thickness 0.25)
		(keepout
			(tracks allowed)
			(vias allowed)
			(pads allowed)
			(copperpour allowed)
			(footprints not_allowed)
		)
		(placement
			(enabled no)
			(sheetname "")
		)
		(fill
			(thermal_gap 0.5)
			(thermal_bridge_width 0.5)
			(island_removal_mode 0)
		)
		(polygon
			(pts
				(xy 55.999888 -454.799954) (xy 44.99991 -454.799954) (xy 44.99991 -479.799904) (xy 55.999888 -479.799904)
			)
		)
	)
	(zone
		(layer "F.Cu")
		(hatch none 0.5)
		(connect_pads
			(clearance 0)
		)
		(min_thickness 0.25)
		(keepout
			(tracks allowed)
			(vias allowed)
			(pads allowed)
			(copperpour allowed)
			(footprints not_allowed)
		)
		(placement
			(enabled no)
			(sheetname "")
		)
		(fill
			(thermal_gap 0.5)
			(thermal_bridge_width 0.5)
			(island_removal_mode 0)
		)
		(polygon
			(pts
				(xy 2.325116 -464.90001) (xy 13.875004 -464.90001) (xy 13.875004 -420.900098) (xy 2.325116 -420.900098)
			)
		)
	)
	(zone
		(layer "F.Cu")
		(hatch none 0.5)
		(connect_pads
			(clearance 0)
		)
		(min_thickness 0.25)
		(keepout
			(tracks allowed)
			(vias allowed)
			(pads allowed)
			(copperpour allowed)
			(footprints not_allowed)
		)
		(placement
			(enabled no)
			(sheetname "")
		)
		(fill
			(thermal_gap 0.5)
			(thermal_bridge_width 0.5)
			(island_removal_mode 0)
		)
		(polygon
			(pts
				(arc
					(start 21.599906 -473.700094)
					(mid 16.599916 -478.700084)
					(end 11.599926 -473.700094)
				)
				(arc
					(start 11.599926 -473.700094)
					(mid 16.599916 -468.700104)
					(end 21.599906 -473.700094)
				)
			)
		)
	)
	(zone
		(layer "F.Cu")
		(hatch none 0.5)
		(connect_pads
			(clearance 0)
		)
		(min_thickness 0.25)
		(keepout
			(tracks not_allowed)
			(vias allowed)
			(pads allowed)
			(copperpour not_allowed)
			(footprints allowed)
		)
		(placement
			(enabled no)
			(sheetname "")
		)
		(fill
			(thermal_gap 0.5)
			(thermal_bridge_width 0.5)
			(island_removal_mode 0)
		)
		(polygon
			(pts
				(arc
					(start 11.599926 -29.200094)
					(mid 16.599916 -24.200104)
					(end 21.599906 -29.200094)
				)
				(arc
					(start 21.599906 -29.200094)
					(mid 16.599916 -34.200084)
					(end 11.599926 -29.200094)
				)
			)
		)
	)
	(zone
		(layer "F.Cu")
		(hatch none 0.5)
		(connect_pads
			(clearance 0)
		)
		(min_thickness 0.25)
		(keepout
			(tracks not_allowed)
			(vias allowed)
			(pads allowed)
			(copperpour not_allowed)
			(footprints allowed)
		)
		(placement
			(enabled no)
			(sheetname "")
		)
		(fill
			(thermal_gap 0.5)
			(thermal_bridge_width 0.5)
			(island_removal_mode 0)
		)
		(polygon
			(pts
				(arc
					(start 77.999844 -438.151016)
					(mid 76.564744 -436.715916)
					(end 77.999844 -435.280816)
				)
				(arc
					(start 77.999844 -435.280816)
					(mid 83.130644 -430.150016)
					(end 77.999844 -425.019216)
				)
				(arc
					(start 77.999844 -425.019216)
					(mid 76.564744 -423.584116)
					(end 77.999844 -422.149016)
				)
				(arc
					(start 77.999844 -422.149016)
					(mid 86.000844 -430.150016)
					(end 77.999844 -438.151016)
				)
			)
		)
	)
	(zone
		(layer "F.Cu")
		(hatch none 0.5)
		(connect_pads
			(clearance 0)
		)
		(min_thickness 0.25)
		(keepout
			(tracks not_allowed)
			(vias allowed)
			(pads allowed)
			(copperpour not_allowed)
			(footprints allowed)
		)
		(placement
			(enabled no)
			(sheetname "")
		)
		(fill
			(thermal_gap 0.5)
			(thermal_bridge_width 0.5)
			(island_removal_mode 0)
		)
		(polygon
			(pts
				(arc
					(start 95.400114 -64.46012)
					(mid 91.400122 -68.460112)
					(end 87.399876 -64.46012)
				)
				(arc
					(start 87.399876 -64.46012)
					(mid 91.400122 -60.459874)
					(end 95.400114 -64.46012)
				)
			)
		)
	)
	(zone
		(layer "F.Cu")
		(hatch none 0.5)
		(connect_pads
			(clearance 0)
		)
		(min_thickness 0.25)
		(keepout
			(tracks allowed)
			(vias allowed)
			(pads allowed)
			(copperpour allowed)
			(footprints not_allowed)
		)
		(placement
			(enabled no)
			(sheetname "")
		)
		(fill
			(thermal_gap 0.5)
			(thermal_bridge_width 0.5)
			(island_removal_mode 0)
		)
		(polygon
			(pts
				(xy 55.999888 -346.449904) (xy 55.999888 -321.449954) (xy 44.99991 -321.449954) (xy 44.99991 -346.449904)
			)
		)
	)
	(zone
		(layer "F.Cu")
		(hatch none 0.5)
		(connect_pads
			(clearance 0)
		)
		(min_thickness 0.25)
		(keepout
			(tracks allowed)
			(vias allowed)
			(pads allowed)
			(copperpour allowed)
			(footprints not_allowed)
		)
		(placement
			(enabled no)
			(sheetname "")
		)
		(fill
			(thermal_gap 0.5)
			(thermal_bridge_width 0.5)
			(island_removal_mode 0)
		)
		(polygon
			(pts
				(xy 55.999888 -99.199954) (xy 44.99991 -99.199954) (xy 44.99991 -124.199904) (xy 55.999888 -124.199904)
			)
		)
	)
	(zone
		(layer "F.Cu")
		(hatch none 0.5)
		(connect_pads
			(clearance 0)
		)
		(min_thickness 0.25)
		(keepout
			(tracks not_allowed)
			(vias allowed)
			(pads allowed)
			(copperpour not_allowed)
			(footprints allowed)
		)
		(placement
			(enabled no)
			(sheetname "")
		)
		(fill
			(thermal_gap 0.5)
			(thermal_bridge_width 0.5)
			(island_removal_mode 0)
		)
		(polygon
			(pts
				(arc
					(start 80.000094 -32.29991)
					(mid 78.000098 -34.299906)
					(end 76.000102 -32.29991)
				)
				(arc
					(start 76.000102 -32.29991)
					(mid 78.000098 -30.299914)
					(end 80.000094 -32.29991)
				)
			)
		)
	)
	(zone
		(layer "F.Cu")
		(hatch none 0.5)
		(connect_pads
			(clearance 0)
		)
		(min_thickness 0.25)
		(keepout
			(tracks allowed)
			(vias allowed)
			(pads allowed)
			(copperpour allowed)
			(footprints not_allowed)
		)
		(placement
			(enabled no)
			(sheetname "")
		)
		(fill
			(thermal_gap 0.5)
			(thermal_bridge_width 0.5)
			(island_removal_mode 0)
		)
		(polygon
			(pts
				(xy 55.999888 -168.649904) (xy 55.999888 -143.649954) (xy 44.99991 -143.649954) (xy 44.99991 -168.649904)
			)
		)
	)
	(zone
		(layer "F.Cu")
		(hatch none 0.5)
		(connect_pads
			(clearance 0)
		)
		(min_thickness 0.25)
		(keepout
			(tracks allowed)
			(vias allowed)
			(pads allowed)
			(copperpour allowed)
			(footprints not_allowed)
		)
		(placement
			(enabled no)
			(sheetname "")
		)
		(fill
			(thermal_gap 0.5)
			(thermal_bridge_width 0.5)
			(island_removal_mode 0)
		)
		(polygon
			(pts
				(xy 37.975032 -441.63996) (xy 37.975032 -353.5299) (xy 28.02509 -353.5299) (xy 28.02509 -441.63996)
			)
		)
	)
	(zone
		(layer "F.Cu")
		(hatch none 0.5)
		(connect_pads
			(clearance 0)
		)
		(min_thickness 0.25)
		(keepout
			(tracks not_allowed)
			(vias allowed)
			(pads allowed)
			(copperpour not_allowed)
			(footprints allowed)
		)
		(placement
			(enabled no)
			(sheetname "")
		)
		(fill
			(thermal_gap 0.5)
			(thermal_bridge_width 0.5)
			(island_removal_mode 0)
		)
		(polygon
			(pts
				(arc
					(start 18.599912 -384.800094)
					(mid 16.599916 -386.80009)
					(end 14.59992 -384.800094)
				)
				(arc
					(start 14.59992 -384.800094)
					(mid 16.599916 -382.800098)
					(end 18.599912 -384.800094)
				)
			)
		)
	)
	(zone
		(layer "F.Cu")
		(hatch none 0.5)
		(connect_pads
			(clearance 0)
		)
		(min_thickness 0.25)
		(keepout
			(tracks not_allowed)
			(vias allowed)
			(pads allowed)
			(copperpour not_allowed)
			(footprints allowed)
		)
		(placement
			(enabled no)
			(sheetname "")
		)
		(fill
			(thermal_gap 0.5)
			(thermal_bridge_width 0.5)
			(island_removal_mode 0)
		)
		(polygon
			(pts
				(arc
					(start 78.000098 -527.050762)
					(mid 76.564998 -525.615662)
					(end 78.000098 -524.180562)
				)
				(arc
					(start 78.000098 -524.180562)
					(mid 83.130898 -519.049762)
					(end 78.000098 -513.918962)
				)
				(arc
					(start 78.000098 -513.918962)
					(mid 76.564998 -512.483862)
					(end 78.000098 -511.048762)
				)
				(arc
					(start 78.000098 -511.048762)
					(mid 86.001098 -519.049762)
					(end 78.000098 -527.050762)
				)
			)
		)
	)
	(zone
		(layer "F.Cu")
		(hatch none 0.5)
		(connect_pads
			(clearance 0)
		)
		(min_thickness 0.25)
		(keepout
			(tracks allowed)
			(vias allowed)
			(pads allowed)
			(copperpour allowed)
			(footprints not_allowed)
		)
		(placement
			(enabled no)
			(sheetname "")
		)
		(fill
			(thermal_gap 0.5)
			(thermal_bridge_width 0.5)
			(island_removal_mode 0)
		)
		(polygon
			(pts
				(arc
					(start 83.000088 -210.09991)
					(mid 78.000098 -215.0999)
					(end 73.000108 -210.09991)
				)
				(arc
					(start 73.000108 -210.09991)
					(mid 78.000098 -205.09992)
					(end 83.000088 -210.09991)
				)
			)
		)
	)
	(zone
		(layer "F.Cu")
		(hatch none 0.5)
		(connect_pads
			(clearance 0)
		)
		(min_thickness 0.25)
		(keepout
			(tracks allowed)
			(vias allowed)
			(pads allowed)
			(copperpour allowed)
			(footprints not_allowed)
		)
		(placement
			(enabled no)
			(sheetname "")
		)
		(fill
			(thermal_gap 0.5)
			(thermal_bridge_width 0.5)
			(island_removal_mode 0)
		)
		(polygon
			(pts
				(arc
					(start 96.400112 -197.81012)
					(mid 91.400122 -202.81011)
					(end 86.399878 -197.81012)
				)
				(arc
					(start 86.399878 -197.81012)
					(mid 91.400122 -192.809876)
					(end 96.400112 -197.81012)
				)
			)
		)
	)
	(zone
		(layer "F.Cu")
		(hatch none 0.5)
		(connect_pads
			(clearance 0)
		)
		(min_thickness 0.25)
		(keepout
			(tracks allowed)
			(vias allowed)
			(pads allowed)
			(copperpour allowed)
			(footprints not_allowed)
		)
		(placement
			(enabled no)
			(sheetname "")
		)
		(fill
			(thermal_gap 0.5)
			(thermal_bridge_width 0.5)
			(island_removal_mode 0)
		)
		(polygon
			(pts
				(xy 55.999888 -410.349954) (xy 44.99991 -410.349954) (xy 44.99991 -435.349904) (xy 55.999888 -435.349904)
			)
		)
	)
	(zone
		(layer "F.Cu")
		(hatch none 0.5)
		(connect_pads
			(clearance 0)
		)
		(min_thickness 0.25)
		(keepout
			(tracks allowed)
			(vias allowed)
			(pads allowed)
			(copperpour allowed)
			(footprints not_allowed)
		)
		(placement
			(enabled no)
			(sheetname "")
		)
		(fill
			(thermal_gap 0.5)
			(thermal_bridge_width 0.5)
			(island_removal_mode 0)
		)
		(polygon
			(pts
				(xy 37.975032 -353.240086) (xy 37.975032 -265.130026) (xy 28.02509 -265.130026) (xy 28.02509 -353.240086)
			)
		)
	)
	(zone
		(layer "F.Cu")
		(hatch none 0.5)
		(connect_pads
			(clearance 0)
		)
		(min_thickness 0.25)
		(keepout
			(tracks allowed)
			(vias allowed)
			(pads allowed)
			(copperpour allowed)
			(footprints not_allowed)
		)
		(placement
			(enabled no)
			(sheetname "")
		)
		(fill
			(thermal_gap 0.5)
			(thermal_bridge_width 0.5)
			(island_removal_mode 0)
		)
		(polygon
			(pts
				(xy 55.999888 -124.199904) (xy 55.999888 -99.199954) (xy 44.99991 -99.199954) (xy 44.99991 -124.199904)
			)
		)
	)
	(zone
		(layer "F.Cu")
		(hatch none 0.5)
		(connect_pads
			(clearance 0)
		)
		(min_thickness 0.25)
		(keepout
			(tracks allowed)
			(vias allowed)
			(pads allowed)
			(copperpour allowed)
			(footprints not_allowed)
		)
		(placement
			(enabled no)
			(sheetname "")
		)
		(fill
			(thermal_gap 0.5)
			(thermal_bridge_width 0.5)
			(island_removal_mode 0)
		)
		(polygon
			(pts
				(xy 55.999888 -390.899904) (xy 55.999888 -365.899954) (xy 44.99991 -365.899954) (xy 44.99991 -390.899904)
			)
		)
	)
	(zone
		(layer "F.Cu")
		(hatch none 0.5)
		(connect_pads
			(clearance 0)
		)
		(min_thickness 0.25)
		(keepout
			(tracks not_allowed)
			(vias allowed)
			(pads allowed)
			(copperpour not_allowed)
			(footprints allowed)
		)
		(placement
			(enabled no)
			(sheetname "")
		)
		(fill
			(thermal_gap 0.5)
			(thermal_bridge_width 0.5)
			(island_removal_mode 0)
		)
		(polygon
			(pts
				(arc
					(start 16.599916 -37.20084)
					(mid 15.164816 -35.76574)
					(end 16.599916 -34.33064)
				)
				(arc
					(start 16.599916 -34.33064)
					(mid 21.730716 -29.19984)
					(end 16.599916 -24.06904)
				)
				(arc
					(start 16.599916 -24.06904)
					(mid 15.164816 -22.63394)
					(end 16.599916 -21.19884)
				)
				(arc
					(start 16.599916 -21.19884)
					(mid 24.600916 -29.19984)
					(end 16.599916 -37.20084)
				)
			)
		)
	)
	(zone
		(layer "F.Cu")
		(hatch none 0.5)
		(connect_pads
			(clearance 0)
		)
		(min_thickness 0.25)
		(keepout
			(tracks not_allowed)
			(vias allowed)
			(pads allowed)
			(copperpour not_allowed)
			(footprints allowed)
		)
		(placement
			(enabled no)
			(sheetname "")
		)
		(fill
			(thermal_gap 0.5)
			(thermal_bridge_width 0.5)
			(island_removal_mode 0)
		)
		(polygon
			(pts
				(arc
					(start 16.599916 -212.13064)
					(mid 18.035016 -213.56574)
					(end 16.599916 -215.00084)
				)
				(arc
					(start 16.599916 -215.00084)
					(mid 8.598916 -206.99984)
					(end 16.599916 -198.99884)
				)
				(arc
					(start 16.599916 -198.99884)
					(mid 18.035016 -200.43394)
					(end 16.599916 -201.86904)
				)
				(arc
					(start 16.599916 -201.86904)
					(mid 11.469116 -206.99984)
					(end 16.599916 -212.13064)
				)
			)
		)
	)
	(zone
		(layer "F.Cu")
		(hatch none 0.5)
		(connect_pads
			(clearance 0)
		)
		(min_thickness 0.25)
		(keepout
			(tracks allowed)
			(vias allowed)
			(pads allowed)
			(copperpour allowed)
			(footprints not_allowed)
		)
		(placement
			(enabled no)
			(sheetname "")
		)
		(fill
			(thermal_gap 0.5)
			(thermal_bridge_width 0.5)
			(island_removal_mode 0)
		)
		(polygon
			(pts
				(arc
					(start 83.000088 -32.29991)
					(mid 78.000098 -37.2999)
					(end 73.000108 -32.29991)
				)
				(arc
					(start 73.000108 -32.29991)
					(mid 78.000098 -27.29992)
					(end 83.000088 -32.29991)
				)
			)
		)
	)
	(zone
		(layer "F.Cu")
		(hatch none 0.5)
		(connect_pads
			(clearance 0)
		)
		(min_thickness 0.25)
		(keepout
			(tracks allowed)
			(vias allowed)
			(pads allowed)
			(copperpour allowed)
			(footprints not_allowed)
		)
		(placement
			(enabled no)
			(sheetname "")
		)
		(fill
			(thermal_gap 0.5)
			(thermal_bridge_width 0.5)
			(island_removal_mode 0)
		)
		(polygon
			(pts
				(xy 55.999888 -35.299904) (xy 55.999888 -10.299954) (xy 44.99991 -10.299954) (xy 44.99991 -35.299904)
			)
		)
	)
	(zone
		(layer "F.Cu")
		(hatch none 0.5)
		(connect_pads
			(clearance 0)
		)
		(min_thickness 0.25)
		(keepout
			(tracks not_allowed)
			(vias allowed)
			(pads allowed)
			(copperpour not_allowed)
			(footprints allowed)
		)
		(placement
			(enabled no)
			(sheetname "")
		)
		(fill
			(thermal_gap 0.5)
			(thermal_bridge_width 0.5)
			(island_removal_mode 0)
		)
		(polygon
			(pts
				(arc
					(start 77.999844 -129.20091)
					(mid 76.564744 -127.76581)
					(end 77.999844 -126.33071)
				)
				(arc
					(start 77.999844 -126.33071)
					(mid 83.130644 -121.19991)
					(end 77.999844 -116.06911)
				)
				(arc
					(start 77.999844 -116.06911)
					(mid 76.564744 -114.63401)
					(end 77.999844 -113.19891)
				)
				(arc
					(start 77.999844 -113.19891)
					(mid 86.000844 -121.19991)
					(end 77.999844 -129.20091)
				)
			)
		)
	)
	(zone
		(layer "F.Cu")
		(hatch none 0.5)
		(connect_pads
			(clearance 0)
		)
		(min_thickness 0.25)
		(keepout
			(tracks not_allowed)
			(vias allowed)
			(pads allowed)
			(copperpour not_allowed)
			(footprints allowed)
		)
		(placement
			(enabled no)
			(sheetname "")
		)
		(fill
			(thermal_gap 0.5)
			(thermal_bridge_width 0.5)
			(island_removal_mode 0)
		)
		(polygon
			(pts
				(arc
					(start 81.60004 -478.799906)
					(mid 78.000098 -482.399848)
					(end 74.399902 -478.799906)
				)
				(arc
					(start 74.399902 -477.799908)
					(mid 78.000098 -474.199712)
					(end 81.60004 -477.799908)
				)
			)
		)
	)
	(zone
		(layer "F.Cu")
		(hatch none 0.5)
		(connect_pads
			(clearance 0)
		)
		(min_thickness 0.25)
		(keepout
			(tracks allowed)
			(vias allowed)
			(pads allowed)
			(copperpour allowed)
			(footprints not_allowed)
		)
		(placement
			(enabled no)
			(sheetname "")
		)
		(fill
			(thermal_gap 0.5)
			(thermal_bridge_width 0.5)
			(island_removal_mode 0)
		)
		(polygon
			(pts
				(arc
					(start 74.399902 -78.300072)
					(mid 78.000098 -74.699876)
					(end 81.60004 -78.300072)
				)
				(arc
					(start 81.60004 -78.300072)
					(mid 78.000098 -81.900014)
					(end 74.399902 -78.300072)
				)
			)
		)
	)
	(zone
		(layer "F.Cu")
		(hatch none 0.5)
		(connect_pads
			(clearance 0)
		)
		(min_thickness 0.25)
		(keepout
			(tracks allowed)
			(vias allowed)
			(pads allowed)
			(copperpour allowed)
			(footprints not_allowed)
		)
		(placement
			(enabled no)
			(sheetname "")
		)
		(fill
			(thermal_gap 0.5)
			(thermal_bridge_width 0.5)
			(island_removal_mode 0)
		)
		(polygon
			(pts
				(xy 55.999888 -10.299954) (xy 44.99991 -10.299954) (xy 44.99991 -35.299904) (xy 55.999888 -35.299904)
			)
		)
	)
	(zone
		(layer "F.Cu")
		(hatch none 0.5)
		(connect_pads
			(clearance 0)
		)
		(min_thickness 0.25)
		(keepout
			(tracks not_allowed)
			(vias allowed)
			(pads allowed)
			(copperpour not_allowed)
			(footprints allowed)
		)
		(placement
			(enabled no)
			(sheetname "")
		)
		(fill
			(thermal_gap 0.5)
			(thermal_bridge_width 0.5)
			(island_removal_mode 0)
		)
		(polygon
			(pts
				(arc
					(start 95.400114 -242.26012)
					(mid 91.400122 -246.260112)
					(end 87.399876 -242.26012)
				)
				(arc
					(start 87.399876 -242.26012)
					(mid 91.400122 -238.259874)
					(end 95.400114 -242.26012)
				)
			)
		)
	)
	(zone
		(layer "F.Cu")
		(hatch none 0.5)
		(connect_pads
			(clearance 0)
		)
		(min_thickness 0.25)
		(keepout
			(tracks not_allowed)
			(vias allowed)
			(pads allowed)
			(copperpour not_allowed)
			(footprints allowed)
		)
		(placement
			(enabled no)
			(sheetname "")
		)
		(fill
			(thermal_gap 0.5)
			(thermal_bridge_width 0.5)
			(island_removal_mode 0)
		)
		(polygon
			(pts
				(arc
					(start 95.400114 -331.16012)
					(mid 91.400122 -335.160112)
					(end 87.399876 -331.16012)
				)
				(arc
					(start 87.399876 -331.16012)
					(mid 91.400122 -327.159874)
					(end 95.400114 -331.16012)
				)
			)
		)
	)
	(zone
		(layer "F.Cu")
		(hatch none 0.5)
		(connect_pads
			(clearance 0)
		)
		(min_thickness 0.25)
		(keepout
			(tracks not_allowed)
			(vias allowed)
			(pads allowed)
			(copperpour not_allowed)
			(footprints allowed)
		)
		(placement
			(enabled no)
			(sheetname "")
		)
		(fill
			(thermal_gap 0.5)
			(thermal_bridge_width 0.5)
			(island_removal_mode 0)
		)
		(polygon
			(pts
				(arc
					(start 77.999844 -218.10091)
					(mid 76.564744 -216.66581)
					(end 77.999844 -215.23071)
				)
				(arc
					(start 77.999844 -215.23071)
					(mid 83.130644 -210.09991)
					(end 77.999844 -204.96911)
				)
				(arc
					(start 77.999844 -204.96911)
					(mid 76.564744 -203.53401)
					(end 77.999844 -202.09891)
				)
				(arc
					(start 77.999844 -202.09891)
					(mid 86.000844 -210.09991)
					(end 77.999844 -218.10091)
				)
			)
		)
	)
	(zone
		(layer "F.Cu")
		(hatch none 0.5)
		(connect_pads
			(clearance 0)
		)
		(min_thickness 0.25)
		(keepout
			(tracks allowed)
			(vias allowed)
			(pads allowed)
			(copperpour allowed)
			(footprints not_allowed)
		)
		(placement
			(enabled no)
			(sheetname "")
		)
		(fill
			(thermal_gap 0.5)
			(thermal_bridge_width 0.5)
			(island_removal_mode 0)
		)
		(polygon
			(pts
				(xy 37.975032 -88.039956) (xy 37.975032 0.070104) (xy 28.02509 0.070104) (xy 28.02509 -88.039956)
			)
		)
	)
	(zone
		(layer "F.Cu")
		(hatch none 0.5)
		(connect_pads
			(clearance 0)
		)
		(min_thickness 0.25)
		(keepout
			(tracks allowed)
			(vias allowed)
			(pads allowed)
			(copperpour allowed)
			(footprints not_allowed)
		)
		(placement
			(enabled no)
			(sheetname "")
		)
		(fill
			(thermal_gap 0.5)
			(thermal_bridge_width 0.5)
			(island_removal_mode 0)
		)
		(polygon
			(pts
				(xy 37.975032 -530.040088) (xy 37.975032 -441.930028) (xy 28.02509 -441.930028) (xy 28.02509 -530.040088)
			)
		)
	)
	(zone
		(layer "F.Cu")
		(hatch none 0.5)
		(connect_pads
			(clearance 0)
		)
		(min_thickness 0.25)
		(keepout
			(tracks not_allowed)
			(vias allowed)
			(pads allowed)
			(copperpour not_allowed)
			(footprints allowed)
		)
		(placement
			(enabled no)
			(sheetname "")
		)
		(fill
			(thermal_gap 0.5)
			(thermal_bridge_width 0.5)
			(island_removal_mode 0)
		)
		(polygon
			(pts
				(arc
					(start 16.599916 -481.70084)
					(mid 15.164816 -480.26574)
					(end 16.599916 -478.83064)
				)
				(arc
					(start 16.599916 -478.83064)
					(mid 21.730716 -473.69984)
					(end 16.599916 -468.56904)
				)
				(arc
					(start 16.599916 -468.56904)
					(mid 15.164816 -467.13394)
					(end 16.599916 -465.69884)
				)
				(arc
					(start 16.599916 -465.69884)
					(mid 24.600916 -473.69984)
					(end 16.599916 -481.70084)
				)
			)
		)
	)
	(zone
		(layer "F.Cu")
		(hatch none 0.5)
		(connect_pads
			(clearance 0)
		)
		(min_thickness 0.25)
		(keepout
			(tracks not_allowed)
			(vias allowed)
			(pads allowed)
			(copperpour not_allowed)
			(footprints allowed)
		)
		(placement
			(enabled no)
			(sheetname "")
		)
		(fill
			(thermal_gap 0.5)
			(thermal_bridge_width 0.5)
			(island_removal_mode 0)
		)
		(polygon
			(pts
				(arc
					(start 86.399878 -464.51012)
					(mid 91.400122 -459.509876)
					(end 96.400112 -464.51012)
				)
				(arc
					(start 96.400112 -464.51012)
					(mid 91.400122 -469.51011)
					(end 86.399878 -464.51012)
				)
			)
		)
	)
	(zone
		(layer "F.Cu")
		(hatch none 0.5)
		(connect_pads
			(clearance 0)
		)
		(min_thickness 0.25)
		(keepout
			(tracks allowed)
			(vias allowed)
			(pads allowed)
			(copperpour allowed)
			(footprints not_allowed)
		)
		(placement
			(enabled no)
			(sheetname "")
		)
		(fill
			(thermal_gap 0.5)
			(thermal_bridge_width 0.5)
			(island_removal_mode 0)
		)
		(polygon
			(pts
				(xy 55.999888 -276.999954) (xy 44.99991 -276.999954) (xy 44.99991 -301.999904) (xy 55.999888 -301.999904)
			)
		)
	)
	(zone
		(layer "F.Cu")
		(hatch none 0.5)
		(connect_pads
			(clearance 0)
		)
		(min_thickness 0.25)
		(keepout
			(tracks not_allowed)
			(vias allowed)
			(pads allowed)
			(copperpour not_allowed)
			(footprints allowed)
		)
		(placement
			(enabled no)
			(sheetname "")
		)
		(fill
			(thermal_gap 0.5)
			(thermal_bridge_width 0.5)
			(island_removal_mode 0)
		)
		(polygon
			(pts
				(arc
					(start 73.000108 -430.150016)
					(mid 78.000098 -425.150026)
					(end 83.000088 -430.150016)
				)
				(arc
					(start 83.000088 -430.150016)
					(mid 78.000098 -435.150006)
					(end 73.000108 -430.150016)
				)
			)
		)
	)
	(zone
		(layer "F.Cu")
		(hatch none 0.5)
		(connect_pads
			(clearance 0)
		)
		(min_thickness 0.25)
		(keepout
			(tracks not_allowed)
			(vias allowed)
			(pads allowed)
			(copperpour not_allowed)
			(footprints allowed)
		)
		(placement
			(enabled no)
			(sheetname "")
		)
		(fill
			(thermal_gap 0.5)
			(thermal_bridge_width 0.5)
			(island_removal_mode 0)
		)
		(polygon
			(pts
				(arc
					(start 95.400114 -508.96012)
					(mid 91.400122 -512.960112)
					(end 87.399876 -508.96012)
				)
				(arc
					(start 87.399876 -508.96012)
					(mid 91.400122 -504.959874)
					(end 95.400114 -508.96012)
				)
			)
		)
	)
	(zone
		(layer "F.Cu")
		(hatch none 0.5)
		(connect_pads
			(clearance 0)
		)
		(min_thickness 0.25)
		(keepout
			(tracks allowed)
			(vias allowed)
			(pads allowed)
			(copperpour allowed)
			(footprints not_allowed)
		)
		(placement
			(enabled no)
			(sheetname "")
		)
		(fill
			(thermal_gap 0.5)
			(thermal_bridge_width 0.5)
			(island_removal_mode 0)
		)
		(polygon
			(pts
				(xy 55.999888 -321.449954) (xy 44.99991 -321.449954) (xy 44.99991 -346.449904) (xy 55.999888 -346.449904)
			)
		)
	)
	(zone
		(layer "F.Cu")
		(hatch none 0.5)
		(connect_pads
			(clearance 0)
		)
		(min_thickness 0.25)
		(keepout
			(tracks not_allowed)
			(vias allowed)
			(pads allowed)
			(copperpour not_allowed)
			(footprints allowed)
		)
		(placement
			(enabled no)
			(sheetname "")
		)
		(fill
			(thermal_gap 0.5)
			(thermal_bridge_width 0.5)
			(island_removal_mode 0)
		)
		(polygon
			(pts
				(arc
					(start 95.400114 -375.61012)
					(mid 91.400122 -379.610112)
					(end 87.399876 -375.61012)
				)
				(arc
					(start 87.399876 -375.61012)
					(mid 91.400122 -371.609874)
					(end 95.400114 -375.61012)
				)
			)
		)
	)
	(zone
		(layer "F.Cu")
		(hatch none 0.5)
		(connect_pads
			(clearance 0)
		)
		(min_thickness 0.25)
		(keepout
			(tracks not_allowed)
			(vias allowed)
			(pads allowed)
			(copperpour not_allowed)
			(footprints allowed)
		)
		(placement
			(enabled no)
			(sheetname "")
		)
		(fill
			(thermal_gap 0.5)
			(thermal_bridge_width 0.5)
			(island_removal_mode 0)
		)
		(polygon
			(pts
				(arc
					(start 12.683998 -223.205294)
					(mid 14.309598 -221.579694)
					(end 15.935198 -223.205294)
				)
				(arc
					(start 15.935198 -223.205294)
					(mid 14.309598 -224.830894)
					(end 12.683998 -223.205294)
				)
			)
		)
	)
	(zone
		(layer "F.Cu")
		(hatch none 0.5)
		(connect_pads
			(clearance 0)
		)
		(min_thickness 0.25)
		(keepout
			(tracks allowed)
			(vias allowed)
			(pads allowed)
			(copperpour allowed)
			(footprints not_allowed)
		)
		(placement
			(enabled no)
			(sheetname "")
		)
		(fill
			(thermal_gap 0.5)
			(thermal_bridge_width 0.5)
			(island_removal_mode 0)
		)
		(polygon
			(pts
				(arc
					(start 83.000088 -341.250016)
					(mid 78.000098 -346.250006)
					(end 73.000108 -341.250016)
				)
				(arc
					(start 73.000108 -341.250016)
					(mid 78.000098 -336.250026)
					(end 83.000088 -341.250016)
				)
			)
		)
	)
	(zone
		(layer "F.Cu")
		(hatch none 0.5)
		(connect_pads
			(clearance 0)
		)
		(min_thickness 0.25)
		(keepout
			(tracks not_allowed)
			(vias allowed)
			(pads allowed)
			(copperpour not_allowed)
			(footprints allowed)
		)
		(placement
			(enabled no)
			(sheetname "")
		)
		(fill
			(thermal_gap 0.5)
			(thermal_bridge_width 0.5)
			(island_removal_mode 0)
		)
		(polygon
			(pts
				(arc
					(start 75.3999 -477.799908)
					(mid 78.000098 -475.19971)
					(end 80.600042 -477.799908)
				)
				(arc
					(start 80.600042 -478.799906)
					(mid 78.000098 -481.39985)
					(end 75.3999 -478.799906)
				)
			)
		)
	)
	(zone
		(layer "F.Cu")
		(hatch none 0.5)
		(connect_pads
			(clearance 0)
		)
		(min_thickness 0.25)
		(keepout
			(tracks not_allowed)
			(vias allowed)
			(pads allowed)
			(copperpour not_allowed)
			(footprints allowed)
		)
		(placement
			(enabled no)
			(sheetname "")
		)
		(fill
			(thermal_gap 0.5)
			(thermal_bridge_width 0.5)
			(island_removal_mode 0)
		)
		(polygon
			(pts
				(arc
					(start 18.599912 -295.900094)
					(mid 16.599916 -297.90009)
					(end 14.59992 -295.900094)
				)
				(arc
					(start 14.59992 -295.900094)
					(mid 16.599916 -293.900098)
					(end 18.599912 -295.900094)
				)
			)
		)
	)
	(zone
		(layer "F.Cu")
		(hatch none 0.5)
		(connect_pads
			(clearance 0)
		)
		(min_thickness 0.25)
		(keepout
			(tracks allowed)
			(vias allowed)
			(pads allowed)
			(copperpour allowed)
			(footprints not_allowed)
		)
		(placement
			(enabled no)
			(sheetname "")
		)
		(fill
			(thermal_gap 0.5)
			(thermal_bridge_width 0.5)
			(island_removal_mode 0)
		)
		(polygon
			(pts
				(arc
					(start 96.400112 -64.46012)
					(mid 91.400122 -69.46011)
					(end 86.399878 -64.46012)
				)
				(arc
					(start 86.399878 -64.46012)
					(mid 91.400122 -59.459876)
					(end 96.400112 -64.46012)
				)
			)
		)
	)
	(zone
		(layers "F.Cu" "B.Cu" "In1.Cu" "In2.Cu" "In3.Cu" "In4.Cu" "In5.Cu" "In6.Cu")
		(hatch none 0.5)
		(connect_pads
			(clearance 0)
		)
		(min_thickness 0.25)
		(keepout
			(tracks not_allowed)
			(vias allowed)
			(pads allowed)
			(copperpour not_allowed)
			(footprints allowed)
		)
		(placement
			(enabled no)
			(sheetname "")
		)
		(fill
			(thermal_gap 0.5)
			(thermal_bridge_width 0.5)
			(island_removal_mode 0)
		)
		(polygon
			(pts
				(arc
					(start 75.487784 -341.250016)
					(mid 77.999844 -338.737956)
					(end 80.511904 -341.250016)
				)
				(arc
					(start 80.511904 -341.250016)
					(mid 77.999844 -343.762076)
					(end 75.487784 -341.250016)
				)
			)
		)
	)
	(zone
		(layers "F.Cu" "B.Cu" "In1.Cu" "In2.Cu" "In3.Cu" "In4.Cu" "In5.Cu" "In6.Cu")
		(hatch none 0.5)
		(connect_pads
			(clearance 0)
		)
		(min_thickness 0.25)
		(keepout
			(tracks allowed)
			(vias not_allowed)
			(pads allowed)
			(copperpour not_allowed)
			(footprints allowed)
		)
		(placement
			(enabled no)
			(sheetname "")
		)
		(fill
			(thermal_gap 0.5)
			(thermal_bridge_width 0.5)
			(island_removal_mode 0)
		)
		(polygon
			(pts
				(xy 43.37939 -271.60728) (xy 43.37939 -271.63268) (xy 43.37939 -275.59508) (xy 82.77479 -275.59508)
				(xy 82.80019 -275.59508) (xy 82.80019 -271.63268) (xy 82.80019 -271.60728)
			)
		)
	)
	(zone
		(layers "F.Cu" "B.Cu" "In1.Cu" "In2.Cu" "In3.Cu" "In4.Cu" "In5.Cu" "In6.Cu")
		(hatch none 0.5)
		(connect_pads
			(clearance 0)
		)
		(min_thickness 0.25)
		(keepout
			(tracks allowed)
			(vias not_allowed)
			(pads allowed)
			(copperpour not_allowed)
			(footprints allowed)
		)
		(placement
			(enabled no)
			(sheetname "")
		)
		(fill
			(thermal_gap 0.5)
			(thermal_bridge_width 0.5)
			(island_removal_mode 0)
		)
		(polygon
			(pts
				(xy 43.37939 -93.80728) (xy 43.37939 -93.83268) (xy 43.37939 -97.79508) (xy 82.77479 -97.79508)
				(xy 82.80019 -97.79508) (xy 82.80019 -93.83268) (xy 82.80019 -93.80728)
			)
		)
	)
	(zone
		(layers "F.Cu" "B.Cu" "In1.Cu" "In2.Cu" "In3.Cu" "In4.Cu" "In5.Cu" "In6.Cu")
		(hatch none 0.5)
		(connect_pads
			(clearance 0)
		)
		(min_thickness 0.25)
		(keepout
			(tracks not_allowed)
			(vias allowed)
			(pads allowed)
			(copperpour not_allowed)
			(footprints allowed)
		)
		(placement
			(enabled no)
			(sheetname "")
		)
		(fill
			(thermal_gap 0.5)
			(thermal_bridge_width 0.5)
			(island_removal_mode 0)
		)
		(polygon
			(pts
				(arc
					(start 77.999844 -474.693234)
					(mid 75.799681 -475.604571)
					(end 74.888344 -477.804734)
				)
				(xy 74.888344 -478.300034)
				(arc
					(start 74.888344 -478.795334)
					(mid 75.799681 -480.995497)
					(end 77.999844 -481.906834)
				)
				(arc
					(start 77.999844 -481.906834)
					(mid 80.200007 -480.995497)
					(end 81.111344 -478.795334)
				)
				(arc
					(start 81.111344 -477.804734)
					(mid 80.200007 -475.604571)
					(end 77.999844 -474.693234)
				)
			)
		)
	)
	(zone
		(layers "F.Cu" "B.Cu" "In1.Cu" "In2.Cu" "In3.Cu" "In4.Cu" "In5.Cu" "In6.Cu")
		(hatch none 0.5)
		(connect_pads
			(clearance 0)
		)
		(min_thickness 0.25)
		(keepout
			(tracks not_allowed)
			(vias allowed)
			(pads allowed)
			(copperpour not_allowed)
			(footprints allowed)
		)
		(placement
			(enabled no)
			(sheetname "")
		)
		(fill
			(thermal_gap 0.5)
			(thermal_bridge_width 0.5)
			(island_removal_mode 0)
		)
		(polygon
			(pts
				(arc
					(start 39.819072 -6.91007)
					(mid 41.499536 -5.229606)
					(end 43.18 -6.91007)
				)
				(arc
					(start 43.18 -6.91007)
					(mid 41.499536 -8.590534)
					(end 39.819072 -6.91007)
				)
			)
		)
	)
	(zone
		(layers "F.Cu" "B.Cu" "In1.Cu" "In2.Cu" "In3.Cu" "In4.Cu" "In5.Cu" "In6.Cu")
		(hatch none 0.5)
		(connect_pads
			(clearance 0)
		)
		(min_thickness 0.25)
		(keepout
			(tracks allowed)
			(vias not_allowed)
			(pads allowed)
			(copperpour not_allowed)
			(footprints allowed)
		)
		(placement
			(enabled no)
			(sheetname "")
		)
		(fill
			(thermal_gap 0.5)
			(thermal_bridge_width 0.5)
			(island_removal_mode 0)
		)
		(polygon
			(pts
				(xy 43.379644 -182.70728) (xy 43.379644 -182.73268) (xy 43.379644 -186.69508) (xy 82.775044 -186.69508)
				(xy 82.800444 -186.69508) (xy 82.800444 -182.73268) (xy 82.800444 -182.70728)
			)
		)
	)
	(zone
		(layers "F.Cu" "B.Cu" "In1.Cu" "In2.Cu" "In3.Cu" "In4.Cu" "In5.Cu" "In6.Cu")
		(hatch none 0.5)
		(connect_pads
			(clearance 0)
		)
		(min_thickness 0.25)
		(keepout
			(tracks not_allowed)
			(vias allowed)
			(pads allowed)
			(copperpour not_allowed)
			(footprints allowed)
		)
		(placement
			(enabled no)
			(sheetname "")
		)
		(fill
			(thermal_gap 0.5)
			(thermal_bridge_width 0.5)
			(island_removal_mode 0)
		)
		(polygon
			(pts
				(arc
					(start 39.819326 -184.71007)
					(mid 41.49979 -183.029606)
					(end 43.180254 -184.71007)
				)
				(arc
					(start 43.180254 -184.71007)
					(mid 41.49979 -186.390534)
					(end 39.819326 -184.71007)
				)
			)
		)
	)
	(zone
		(layers "F.Cu" "B.Cu" "In1.Cu" "In2.Cu" "In3.Cu" "In4.Cu" "In5.Cu" "In6.Cu")
		(hatch none 0.5)
		(connect_pads
			(clearance 0)
		)
		(min_thickness 0.25)
		(keepout
			(tracks allowed)
			(vias not_allowed)
			(pads allowed)
			(copperpour not_allowed)
			(footprints allowed)
		)
		(placement
			(enabled no)
			(sheetname "")
		)
		(fill
			(thermal_gap 0.5)
			(thermal_bridge_width 0.5)
			(island_removal_mode 0)
		)
		(polygon
			(pts
				(xy 43.37939 -316.05728) (xy 43.37939 -316.08268) (xy 43.37939 -320.04508) (xy 82.77479 -320.04508)
				(xy 82.80019 -320.04508) (xy 82.80019 -316.08268) (xy 82.80019 -316.05728)
			)
		)
	)
	(zone
		(layers "F.Cu" "B.Cu" "In1.Cu" "In2.Cu" "In3.Cu" "In4.Cu" "In5.Cu" "In6.Cu")
		(hatch none 0.5)
		(connect_pads
			(clearance 0)
		)
		(min_thickness 0.25)
		(keepout
			(tracks allowed)
			(vias not_allowed)
			(pads allowed)
			(copperpour not_allowed)
			(footprints allowed)
		)
		(placement
			(enabled no)
			(sheetname "")
		)
		(fill
			(thermal_gap 0.5)
			(thermal_bridge_width 0.5)
			(island_removal_mode 0)
		)
		(polygon
			(pts
				(xy 84.984844 -187.25388) (xy 85.010244 -187.25388) (xy 92.655644 -187.25388) (xy 92.655644 -182.14848)
				(xy 85.010244 -182.14848) (xy 84.984844 -182.14848)
			)
		)
	)
	(zone
		(layers "F.Cu" "B.Cu" "In1.Cu" "In2.Cu" "In3.Cu" "In4.Cu" "In5.Cu" "In6.Cu")
		(hatch none 0.5)
		(connect_pads
			(clearance 0)
		)
		(min_thickness 0.25)
		(keepout
			(tracks not_allowed)
			(vias allowed)
			(pads allowed)
			(copperpour not_allowed)
			(footprints allowed)
		)
		(placement
			(enabled no)
			(sheetname "")
		)
		(fill
			(thermal_gap 0.5)
			(thermal_bridge_width 0.5)
			(island_removal_mode 0)
		)
		(polygon
			(pts
				(arc
					(start 39.819072 -362.51007)
					(mid 41.499536 -360.829606)
					(end 43.18 -362.51007)
				)
				(arc
					(start 43.18 -362.51007)
					(mid 41.499536 -364.190534)
					(end 39.819072 -362.51007)
				)
			)
		)
	)
	(zone
		(layers "F.Cu" "B.Cu" "In1.Cu" "In2.Cu" "In3.Cu" "In4.Cu" "In5.Cu" "In6.Cu")
		(hatch none 0.5)
		(connect_pads
			(clearance 0)
		)
		(min_thickness 0.25)
		(keepout
			(tracks not_allowed)
			(vias allowed)
			(pads allowed)
			(copperpour not_allowed)
			(footprints allowed)
		)
		(placement
			(enabled no)
			(sheetname "")
		)
		(fill
			(thermal_gap 0.5)
			(thermal_bridge_width 0.5)
			(island_removal_mode 0)
		)
		(polygon
			(pts
				(arc
					(start 39.819072 -318.06007)
					(mid 41.499536 -316.379606)
					(end 43.18 -318.06007)
				)
				(arc
					(start 43.18 -318.06007)
					(mid 41.499536 -319.740534)
					(end 39.819072 -318.06007)
				)
			)
		)
	)
	(zone
		(layers "F.Cu" "B.Cu" "In1.Cu" "In2.Cu" "In3.Cu" "In4.Cu" "In5.Cu" "In6.Cu")
		(hatch none 0.5)
		(connect_pads
			(clearance 0)
		)
		(min_thickness 0.25)
		(keepout
			(tracks not_allowed)
			(vias allowed)
			(pads allowed)
			(copperpour not_allowed)
			(footprints allowed)
		)
		(placement
			(enabled no)
			(sheetname "")
		)
		(fill
			(thermal_gap 0.5)
			(thermal_bridge_width 0.5)
			(island_removal_mode 0)
		)
		(polygon
			(pts
				(arc
					(start 75.487784 -121.19991)
					(mid 77.999844 -118.68785)
					(end 80.511904 -121.19991)
				)
				(arc
					(start 80.511904 -121.19991)
					(mid 77.999844 -123.71197)
					(end 75.487784 -121.19991)
				)
			)
		)
	)
	(zone
		(layers "F.Cu" "B.Cu" "In1.Cu" "In2.Cu" "In3.Cu" "In4.Cu" "In5.Cu" "In6.Cu")
		(hatch none 0.5)
		(connect_pads
			(clearance 0)
		)
		(min_thickness 0.25)
		(keepout
			(tracks not_allowed)
			(vias allowed)
			(pads allowed)
			(copperpour not_allowed)
			(footprints allowed)
		)
		(placement
			(enabled no)
			(sheetname "")
		)
		(fill
			(thermal_gap 0.5)
			(thermal_bridge_width 0.5)
			(island_removal_mode 0)
		)
		(polygon
			(pts
				(arc
					(start 14.087856 -29.19984)
					(mid 16.599916 -26.68778)
					(end 19.111976 -29.19984)
				)
				(arc
					(start 19.111976 -29.19984)
					(mid 16.599916 -31.7119)
					(end 14.087856 -29.19984)
				)
			)
		)
	)
	(zone
		(layers "F.Cu" "B.Cu" "In1.Cu" "In2.Cu" "In3.Cu" "In4.Cu" "In5.Cu" "In6.Cu")
		(hatch none 0.5)
		(connect_pads
			(clearance 0)
		)
		(min_thickness 0.25)
		(keepout
			(tracks not_allowed)
			(vias allowed)
			(pads allowed)
			(copperpour not_allowed)
			(footprints allowed)
		)
		(placement
			(enabled no)
			(sheetname "")
		)
		(fill
			(thermal_gap 0.5)
			(thermal_bridge_width 0.5)
			(island_removal_mode 0)
		)
		(polygon
			(pts
				(arc
					(start 39.819326 -140.26007)
					(mid 41.49979 -138.579606)
					(end 43.180254 -140.26007)
				)
				(arc
					(start 43.180254 -140.26007)
					(mid 41.49979 -141.940534)
					(end 39.819326 -140.26007)
				)
			)
		)
	)
	(zone
		(layers "F.Cu" "B.Cu" "In1.Cu" "In2.Cu" "In3.Cu" "In4.Cu" "In5.Cu" "In6.Cu")
		(hatch none 0.5)
		(connect_pads
			(clearance 0)
		)
		(min_thickness 0.25)
		(keepout
			(tracks not_allowed)
			(vias allowed)
			(pads allowed)
			(copperpour not_allowed)
			(footprints allowed)
		)
		(placement
			(enabled no)
			(sheetname "")
		)
		(fill
			(thermal_gap 0.5)
			(thermal_bridge_width 0.5)
			(island_removal_mode 0)
		)
		(polygon
			(pts
				(arc
					(start 93.15577 -230.51008)
					(mid 94.83979 -228.82606)
					(end 96.52381 -230.51008)
				)
				(arc
					(start 96.52381 -230.51008)
					(mid 94.83979 -232.1941)
					(end 93.15577 -230.51008)
				)
			)
		)
	)
	(zone
		(layers "F.Cu" "B.Cu" "In1.Cu" "In2.Cu" "In3.Cu" "In4.Cu" "In5.Cu" "In6.Cu")
		(hatch none 0.5)
		(connect_pads
			(clearance 0)
		)
		(min_thickness 0.25)
		(keepout
			(tracks not_allowed)
			(vias allowed)
			(pads allowed)
			(copperpour not_allowed)
			(footprints allowed)
		)
		(placement
			(enabled no)
			(sheetname "")
		)
		(fill
			(thermal_gap 0.5)
			(thermal_bridge_width 0.5)
			(island_removal_mode 0)
		)
		(polygon
			(pts
				(arc
					(start 14.087856 -295.89984)
					(mid 16.599916 -293.38778)
					(end 19.111976 -295.89984)
				)
				(arc
					(start 19.111976 -295.89984)
					(mid 16.599916 -298.4119)
					(end 14.087856 -295.89984)
				)
			)
		)
	)
	(zone
		(layers "F.Cu" "B.Cu" "In1.Cu" "In2.Cu" "In3.Cu" "In4.Cu" "In5.Cu" "In6.Cu")
		(hatch none 0.5)
		(connect_pads
			(clearance 0)
		)
		(min_thickness 0.25)
		(keepout
			(tracks allowed)
			(vias not_allowed)
			(pads allowed)
			(copperpour not_allowed)
			(footprints allowed)
		)
		(placement
			(enabled no)
			(sheetname "")
		)
		(fill
			(thermal_gap 0.5)
			(thermal_bridge_width 0.5)
			(island_removal_mode 0)
		)
		(polygon
			(pts
				(xy 84.98459 -320.60388) (xy 85.00999 -320.60388) (xy 92.65539 -320.60388) (xy 92.65539 -315.49848)
				(xy 85.00999 -315.49848) (xy 84.98459 -315.49848)
			)
		)
	)
	(zone
		(layers "F.Cu" "B.Cu" "In1.Cu" "In2.Cu" "In3.Cu" "In4.Cu" "In5.Cu" "In6.Cu")
		(hatch none 0.5)
		(connect_pads
			(clearance 0)
		)
		(min_thickness 0.25)
		(keepout
			(tracks allowed)
			(vias not_allowed)
			(pads allowed)
			(copperpour not_allowed)
			(footprints allowed)
		)
		(placement
			(enabled no)
			(sheetname "")
		)
		(fill
			(thermal_gap 0.5)
			(thermal_bridge_width 0.5)
			(island_removal_mode 0)
		)
		(polygon
			(pts
				(xy 43.37939 -449.40728) (xy 43.37939 -449.43268) (xy 43.37939 -453.39508) (xy 82.77479 -453.39508)
				(xy 82.80019 -453.39508) (xy 82.80019 -449.43268) (xy 82.80019 -449.40728)
			)
		)
	)
	(zone
		(layers "F.Cu" "B.Cu" "In1.Cu" "In2.Cu" "In3.Cu" "In4.Cu" "In5.Cu" "In6.Cu")
		(hatch none 0.5)
		(connect_pads
			(clearance 0)
		)
		(min_thickness 0.25)
		(keepout
			(tracks not_allowed)
			(vias allowed)
			(pads allowed)
			(copperpour not_allowed)
			(footprints allowed)
		)
		(placement
			(enabled no)
			(sheetname "")
		)
		(fill
			(thermal_gap 0.5)
			(thermal_bridge_width 0.5)
			(island_removal_mode 0)
		)
		(polygon
			(pts
				(arc
					(start 86.878668 -331.16012)
					(mid 91.399868 -326.63892)
					(end 95.921068 -331.16012)
				)
				(arc
					(start 95.921068 -331.16012)
					(mid 91.399868 -335.68132)
					(end 86.878668 -331.16012)
				)
			)
		)
	)
	(zone
		(layers "F.Cu" "B.Cu" "In1.Cu" "In2.Cu" "In3.Cu" "In4.Cu" "In5.Cu" "In6.Cu")
		(hatch none 0.5)
		(connect_pads
			(clearance 0)
		)
		(min_thickness 0.25)
		(keepout
			(tracks not_allowed)
			(vias allowed)
			(pads allowed)
			(copperpour not_allowed)
			(footprints allowed)
		)
		(placement
			(enabled no)
			(sheetname "")
		)
		(fill
			(thermal_gap 0.5)
			(thermal_bridge_width 0.5)
			(island_removal_mode 0)
		)
		(polygon
			(pts
				(arc
					(start 14.087856 -206.99984)
					(mid 16.599916 -204.48778)
					(end 19.111976 -206.99984)
				)
				(arc
					(start 19.111976 -206.99984)
					(mid 16.599916 -209.5119)
					(end 14.087856 -206.99984)
				)
			)
		)
	)
	(zone
		(layers "F.Cu" "B.Cu" "In1.Cu" "In2.Cu" "In3.Cu" "In4.Cu" "In5.Cu" "In6.Cu")
		(hatch none 0.5)
		(connect_pads
			(clearance 0)
		)
		(min_thickness 0.25)
		(keepout
			(tracks not_allowed)
			(vias allowed)
			(pads allowed)
			(copperpour not_allowed)
			(footprints allowed)
		)
		(placement
			(enabled no)
			(sheetname "")
		)
		(fill
			(thermal_gap 0.5)
			(thermal_bridge_width 0.5)
			(island_removal_mode 0)
		)
		(polygon
			(pts
				(arc
					(start 93.15577 -274.96008)
					(mid 94.83979 -273.27606)
					(end 96.52381 -274.96008)
				)
				(arc
					(start 96.52381 -274.96008)
					(mid 94.83979 -276.6441)
					(end 93.15577 -274.96008)
				)
			)
		)
	)
	(zone
		(layers "F.Cu" "B.Cu" "In1.Cu" "In2.Cu" "In3.Cu" "In4.Cu" "In5.Cu" "In6.Cu")
		(hatch none 0.5)
		(connect_pads
			(clearance 0)
		)
		(min_thickness 0.25)
		(keepout
			(tracks not_allowed)
			(vias allowed)
			(pads allowed)
			(copperpour not_allowed)
			(footprints allowed)
		)
		(placement
			(enabled no)
			(sheetname "")
		)
		(fill
			(thermal_gap 0.5)
			(thermal_bridge_width 0.5)
			(island_removal_mode 0)
		)
		(polygon
			(pts
				(arc
					(start 39.819072 -273.61007)
					(mid 41.499536 -271.929606)
					(end 43.18 -273.61007)
				)
				(arc
					(start 43.18 -273.61007)
					(mid 41.499536 -275.290534)
					(end 39.819072 -273.61007)
				)
			)
		)
	)
	(zone
		(layers "F.Cu" "B.Cu" "In1.Cu" "In2.Cu" "In3.Cu" "In4.Cu" "In5.Cu" "In6.Cu")
		(hatch none 0.5)
		(connect_pads
			(clearance 0)
		)
		(min_thickness 0.25)
		(keepout
			(tracks not_allowed)
			(vias allowed)
			(pads allowed)
			(copperpour not_allowed)
			(footprints allowed)
		)
		(placement
			(enabled no)
			(sheetname "")
		)
		(fill
			(thermal_gap 0.5)
			(thermal_bridge_width 0.5)
			(island_removal_mode 0)
		)
		(polygon
			(pts
				(arc
					(start 39.819072 -95.81007)
					(mid 41.499536 -94.129606)
					(end 43.18 -95.81007)
				)
				(arc
					(start 43.18 -95.81007)
					(mid 41.499536 -97.490534)
					(end 39.819072 -95.81007)
				)
			)
		)
	)
	(zone
		(layers "F.Cu" "B.Cu" "In1.Cu" "In2.Cu" "In3.Cu" "In4.Cu" "In5.Cu" "In6.Cu")
		(hatch none 0.5)
		(connect_pads
			(clearance 0)
		)
		(min_thickness 0.25)
		(keepout
			(tracks not_allowed)
			(vias allowed)
			(pads allowed)
			(copperpour not_allowed)
			(footprints allowed)
		)
		(placement
			(enabled no)
			(sheetname "")
		)
		(fill
			(thermal_gap 0.5)
			(thermal_bridge_width 0.5)
			(island_removal_mode 0)
		)
		(polygon
			(pts
				(arc
					(start 86.878668 -508.96012)
					(mid 91.399868 -504.43892)
					(end 95.921068 -508.96012)
				)
				(arc
					(start 95.921068 -508.96012)
					(mid 91.399868 -513.48132)
					(end 86.878668 -508.96012)
				)
			)
		)
	)
	(zone
		(layers "F.Cu" "B.Cu" "In1.Cu" "In2.Cu" "In3.Cu" "In4.Cu" "In5.Cu" "In6.Cu")
		(hatch none 0.5)
		(connect_pads
			(clearance 0)
		)
		(min_thickness 0.25)
		(keepout
			(tracks allowed)
			(vias not_allowed)
			(pads allowed)
			(copperpour not_allowed)
			(footprints allowed)
		)
		(placement
			(enabled no)
			(sheetname "")
		)
		(fill
			(thermal_gap 0.5)
			(thermal_bridge_width 0.5)
			(island_removal_mode 0)
		)
		(polygon
			(pts
				(xy 84.98459 -365.05388) (xy 85.00999 -365.05388) (xy 92.65539 -365.05388) (xy 92.65539 -359.94848)
				(xy 85.00999 -359.94848) (xy 84.98459 -359.94848)
			)
		)
	)
	(zone
		(layers "F.Cu" "B.Cu" "In1.Cu" "In2.Cu" "In3.Cu" "In4.Cu" "In5.Cu" "In6.Cu")
		(hatch none 0.5)
		(connect_pads
			(clearance 0)
		)
		(min_thickness 0.25)
		(keepout
			(tracks not_allowed)
			(vias allowed)
			(pads allowed)
			(copperpour not_allowed)
			(footprints allowed)
		)
		(placement
			(enabled no)
			(sheetname "")
		)
		(fill
			(thermal_gap 0.5)
			(thermal_bridge_width 0.5)
			(island_removal_mode 0)
		)
		(polygon
			(pts
				(arc
					(start 75.487784 -430.150016)
					(mid 77.999844 -427.637956)
					(end 80.511904 -430.150016)
				)
				(arc
					(start 80.511904 -430.150016)
					(mid 77.999844 -432.662076)
					(end 75.487784 -430.150016)
				)
			)
		)
	)
	(zone
		(layers "F.Cu" "B.Cu" "In1.Cu" "In2.Cu" "In3.Cu" "In4.Cu" "In5.Cu" "In6.Cu")
		(hatch none 0.5)
		(connect_pads
			(clearance 0)
		)
		(min_thickness 0.25)
		(keepout
			(tracks not_allowed)
			(vias allowed)
			(pads allowed)
			(copperpour not_allowed)
			(footprints allowed)
		)
		(placement
			(enabled no)
			(sheetname "")
		)
		(fill
			(thermal_gap 0.5)
			(thermal_bridge_width 0.5)
			(island_removal_mode 0)
		)
		(polygon
			(pts
				(arc
					(start 86.878668 -464.509866)
					(mid 91.399868 -459.988666)
					(end 95.921068 -464.509866)
				)
				(arc
					(start 95.921068 -464.509866)
					(mid 91.399868 -469.031066)
					(end 86.878668 -464.509866)
				)
			)
		)
	)
	(zone
		(layers "F.Cu" "B.Cu" "In1.Cu" "In2.Cu" "In3.Cu" "In4.Cu" "In5.Cu" "In6.Cu")
		(hatch none 0.5)
		(connect_pads
			(clearance 0)
		)
		(min_thickness 0.25)
		(keepout
			(tracks not_allowed)
			(vias allowed)
			(pads allowed)
			(copperpour not_allowed)
			(footprints allowed)
		)
		(placement
			(enabled no)
			(sheetname "")
		)
		(fill
			(thermal_gap 0.5)
			(thermal_bridge_width 0.5)
			(island_removal_mode 0)
		)
		(polygon
			(pts
				(arc
					(start 86.878668 -153.359866)
					(mid 91.399868 -148.838666)
					(end 95.921068 -153.359866)
				)
				(arc
					(start 95.921068 -153.359866)
					(mid 91.399868 -157.881066)
					(end 86.878668 -153.359866)
				)
			)
		)
	)
	(zone
		(layers "F.Cu" "B.Cu" "In1.Cu" "In2.Cu" "In3.Cu" "In4.Cu" "In5.Cu" "In6.Cu")
		(hatch none 0.5)
		(connect_pads
			(clearance 0)
		)
		(min_thickness 0.25)
		(keepout
			(tracks not_allowed)
			(vias allowed)
			(pads allowed)
			(copperpour not_allowed)
			(footprints allowed)
		)
		(placement
			(enabled no)
			(sheetname "")
		)
		(fill
			(thermal_gap 0.5)
			(thermal_bridge_width 0.5)
			(island_removal_mode 0)
		)
		(polygon
			(pts
				(arc
					(start 93.15577 -363.86008)
					(mid 94.83979 -362.17606)
					(end 96.52381 -363.86008)
				)
				(arc
					(start 96.52381 -363.86008)
					(mid 94.83979 -365.5441)
					(end 93.15577 -363.86008)
				)
			)
		)
	)
	(zone
		(layers "F.Cu" "B.Cu" "In1.Cu" "In2.Cu" "In3.Cu" "In4.Cu" "In5.Cu" "In6.Cu")
		(hatch none 0.5)
		(connect_pads
			(clearance 0)
		)
		(min_thickness 0.25)
		(keepout
			(tracks not_allowed)
			(vias allowed)
			(pads allowed)
			(copperpour not_allowed)
			(footprints allowed)
		)
		(placement
			(enabled no)
			(sheetname "")
		)
		(fill
			(thermal_gap 0.5)
			(thermal_bridge_width 0.5)
			(island_removal_mode 0)
		)
		(polygon
			(pts
				(arc
					(start 39.819072 -406.96007)
					(mid 41.499536 -405.279606)
					(end 43.18 -406.96007)
				)
				(arc
					(start 43.18 -406.96007)
					(mid 41.499536 -408.640534)
					(end 39.819072 -406.96007)
				)
			)
		)
	)
	(zone
		(layers "F.Cu" "B.Cu" "In1.Cu" "In2.Cu" "In3.Cu" "In4.Cu" "In5.Cu" "In6.Cu")
		(hatch none 0.5)
		(connect_pads
			(clearance 0)
		)
		(min_thickness 0.25)
		(keepout
			(tracks not_allowed)
			(vias allowed)
			(pads allowed)
			(copperpour not_allowed)
			(footprints allowed)
		)
		(placement
			(enabled no)
			(sheetname "")
		)
		(fill
			(thermal_gap 0.5)
			(thermal_bridge_width 0.5)
			(island_removal_mode 0)
		)
		(polygon
			(pts
				(arc
					(start 86.878668 -64.46012)
					(mid 91.399868 -59.93892)
					(end 95.921068 -64.46012)
				)
				(arc
					(start 95.921068 -64.46012)
					(mid 91.399868 -68.98132)
					(end 86.878668 -64.46012)
				)
			)
		)
	)
	(zone
		(layers "F.Cu" "B.Cu" "In1.Cu" "In2.Cu" "In3.Cu" "In4.Cu" "In5.Cu" "In6.Cu")
		(hatch none 0.5)
		(connect_pads
			(clearance 0)
		)
		(min_thickness 0.25)
		(keepout
			(tracks not_allowed)
			(vias allowed)
			(pads allowed)
			(copperpour not_allowed)
			(footprints allowed)
		)
		(placement
			(enabled no)
			(sheetname "")
		)
		(fill
			(thermal_gap 0.5)
			(thermal_bridge_width 0.5)
			(island_removal_mode 0)
		)
		(polygon
			(pts
				(arc
					(start 39.819072 -451.41007)
					(mid 41.499536 -449.729606)
					(end 43.18 -451.41007)
				)
				(arc
					(start 43.18 -451.41007)
					(mid 41.499536 -453.090534)
					(end 39.819072 -451.41007)
				)
			)
		)
	)
	(zone
		(layers "F.Cu" "B.Cu" "In1.Cu" "In2.Cu" "In3.Cu" "In4.Cu" "In5.Cu" "In6.Cu")
		(hatch none 0.5)
		(connect_pads
			(clearance 0)
		)
		(min_thickness 0.25)
		(keepout
			(tracks allowed)
			(vias not_allowed)
			(pads allowed)
			(copperpour not_allowed)
			(footprints allowed)
		)
		(placement
			(enabled no)
			(sheetname "")
		)
		(fill
			(thermal_gap 0.5)
			(thermal_bridge_width 0.5)
			(island_removal_mode 0)
		)
		(polygon
			(pts
				(xy 84.98459 -409.50388) (xy 85.00999 -409.50388) (xy 92.65539 -409.50388) (xy 92.65539 -404.39848)
				(xy 85.00999 -404.39848) (xy 84.98459 -404.39848)
			)
		)
	)
	(zone
		(layers "F.Cu" "B.Cu" "In1.Cu" "In2.Cu" "In3.Cu" "In4.Cu" "In5.Cu" "In6.Cu")
		(hatch none 0.5)
		(connect_pads
			(clearance 0)
		)
		(min_thickness 0.25)
		(keepout
			(tracks not_allowed)
			(vias allowed)
			(pads allowed)
			(copperpour not_allowed)
			(footprints allowed)
		)
		(placement
			(enabled no)
			(sheetname "")
		)
		(fill
			(thermal_gap 0.5)
			(thermal_bridge_width 0.5)
			(island_removal_mode 0)
		)
		(polygon
			(pts
				(arc
					(start 3.938016 -251.031502)
					(mid 3.674107 -250.556351)
					(end 3.58267 -250.020582)
				)
				(arc
					(start 3.58267 -250.020582)
					(mid 5.7391 -248.497701)
					(end 6.453124 -251.039376)
				)
				(xy 5.833872 -251.039376)
				(arc
					(start 5.833872 -251.506482)
					(mid 5.200269 -251.636578)
					(end 4.566412 -251.507752)
				)
				(xy 4.566412 -251.031502)
			)
		)
	)
	(zone
		(layers "F.Cu" "B.Cu" "In1.Cu" "In2.Cu" "In3.Cu" "In4.Cu" "In5.Cu" "In6.Cu")
		(hatch none 0.5)
		(connect_pads
			(clearance 0)
		)
		(min_thickness 0.25)
		(keepout
			(tracks not_allowed)
			(vias allowed)
			(pads allowed)
			(copperpour not_allowed)
			(footprints allowed)
		)
		(placement
			(enabled no)
			(sheetname "")
		)
		(fill
			(thermal_gap 0.5)
			(thermal_bridge_width 0.5)
			(island_removal_mode 0)
		)
		(polygon
			(pts
				(arc
					(start 14.087856 -473.69984)
					(mid 16.599916 -471.18778)
					(end 19.111976 -473.69984)
				)
				(arc
					(start 19.111976 -473.69984)
					(mid 16.599916 -476.2119)
					(end 14.087856 -473.69984)
				)
			)
		)
	)
	(zone
		(layers "F.Cu" "B.Cu" "In1.Cu" "In2.Cu" "In3.Cu" "In4.Cu" "In5.Cu" "In6.Cu")
		(hatch none 0.5)
		(connect_pads
			(clearance 0)
		)
		(min_thickness 0.25)
		(keepout
			(tracks not_allowed)
			(vias allowed)
			(pads allowed)
			(copperpour not_allowed)
			(footprints allowed)
		)
		(placement
			(enabled no)
			(sheetname "")
		)
		(fill
			(thermal_gap 0.5)
			(thermal_bridge_width 0.5)
			(island_removal_mode 0)
		)
		(polygon
			(pts
				(arc
					(start 86.878668 -242.26012)
					(mid 91.399868 -237.73892)
					(end 95.921068 -242.26012)
				)
				(arc
					(start 95.921068 -242.26012)
					(mid 91.399868 -246.78132)
					(end 86.878668 -242.26012)
				)
			)
		)
	)
	(zone
		(layers "F.Cu" "B.Cu" "In1.Cu" "In2.Cu" "In3.Cu" "In4.Cu" "In5.Cu" "In6.Cu")
		(hatch none 0.5)
		(connect_pads
			(clearance 0)
		)
		(min_thickness 0.25)
		(keepout
			(tracks allowed)
			(vias not_allowed)
			(pads allowed)
			(copperpour not_allowed)
			(footprints allowed)
		)
		(placement
			(enabled no)
			(sheetname "")
		)
		(fill
			(thermal_gap 0.5)
			(thermal_bridge_width 0.5)
			(island_removal_mode 0)
		)
		(polygon
			(pts
				(xy 43.37939 -360.50728) (xy 43.37939 -360.53268) (xy 43.37939 -364.49508) (xy 82.77479 -364.49508)
				(xy 82.80019 -364.49508) (xy 82.80019 -360.53268) (xy 82.80019 -360.50728)
			)
		)
	)
	(zone
		(layers "F.Cu" "B.Cu" "In1.Cu" "In2.Cu" "In3.Cu" "In4.Cu" "In5.Cu" "In6.Cu")
		(hatch none 0.5)
		(connect_pads
			(clearance 0)
		)
		(min_thickness 0.25)
		(keepout
			(tracks not_allowed)
			(vias allowed)
			(pads allowed)
			(copperpour not_allowed)
			(footprints allowed)
		)
		(placement
			(enabled no)
			(sheetname "")
		)
		(fill
			(thermal_gap 0.5)
			(thermal_bridge_width 0.5)
			(island_removal_mode 0)
		)
		(polygon
			(pts
				(arc
					(start 93.15577 -408.31008)
					(mid 94.83979 -406.62606)
					(end 96.52381 -408.31008)
				)
				(arc
					(start 96.52381 -408.31008)
					(mid 94.83979 -409.9941)
					(end 93.15577 -408.31008)
				)
			)
		)
	)
	(zone
		(layers "F.Cu" "B.Cu" "In1.Cu" "In2.Cu" "In3.Cu" "In4.Cu" "In5.Cu" "In6.Cu")
		(hatch none 0.5)
		(connect_pads
			(clearance 0)
		)
		(min_thickness 0.25)
		(keepout
			(tracks allowed)
			(vias not_allowed)
			(pads allowed)
			(copperpour not_allowed)
			(footprints allowed)
		)
		(placement
			(enabled no)
			(sheetname "")
		)
		(fill
			(thermal_gap 0.5)
			(thermal_bridge_width 0.5)
			(island_removal_mode 0)
		)
		(polygon
			(pts
				(xy 43.37939 -4.90728) (xy 43.37939 -4.93268) (xy 43.37939 -8.89508) (xy 82.77479 -8.89508) (xy 82.80019 -8.89508)
				(xy 82.80019 -4.93268) (xy 82.80019 -4.90728)
			)
		)
	)
	(zone
		(layers "F.Cu" "B.Cu" "In1.Cu" "In2.Cu" "In3.Cu" "In4.Cu" "In5.Cu" "In6.Cu")
		(hatch none 0.5)
		(connect_pads
			(clearance 0)
		)
		(min_thickness 0.25)
		(keepout
			(tracks not_allowed)
			(vias allowed)
			(pads allowed)
			(copperpour not_allowed)
			(footprints allowed)
		)
		(placement
			(enabled no)
			(sheetname "")
		)
		(fill
			(thermal_gap 0.5)
			(thermal_bridge_width 0.5)
			(island_removal_mode 0)
		)
		(polygon
			(pts
				(arc
					(start 93.15577 -52.71008)
					(mid 94.83979 -51.02606)
					(end 96.52381 -52.71008)
				)
				(arc
					(start 96.52381 -52.71008)
					(mid 94.83979 -54.3941)
					(end 93.15577 -52.71008)
				)
			)
		)
	)
	(zone
		(layers "F.Cu" "B.Cu" "In1.Cu" "In2.Cu" "In3.Cu" "In4.Cu" "In5.Cu" "In6.Cu")
		(hatch none 0.5)
		(connect_pads
			(clearance 0)
		)
		(min_thickness 0.25)
		(keepout
			(tracks allowed)
			(vias not_allowed)
			(pads allowed)
			(copperpour not_allowed)
			(footprints allowed)
		)
		(placement
			(enabled no)
			(sheetname "")
		)
		(fill
			(thermal_gap 0.5)
			(thermal_bridge_width 0.5)
			(island_removal_mode 0)
		)
		(polygon
			(pts
				(xy 43.37939 -227.15728) (xy 43.37939 -227.18268) (xy 43.37939 -231.14508) (xy 82.77479 -231.14508)
				(xy 82.80019 -231.14508) (xy 82.80019 -227.18268) (xy 82.80019 -227.15728)
			)
		)
	)
	(zone
		(layers "F.Cu" "B.Cu" "In1.Cu" "In2.Cu" "In3.Cu" "In4.Cu" "In5.Cu" "In6.Cu")
		(hatch none 0.5)
		(connect_pads
			(clearance 0)
		)
		(min_thickness 0.25)
		(keepout
			(tracks allowed)
			(vias not_allowed)
			(pads allowed)
			(copperpour not_allowed)
			(footprints allowed)
		)
		(placement
			(enabled no)
			(sheetname "")
		)
		(fill
			(thermal_gap 0.5)
			(thermal_bridge_width 0.5)
			(island_removal_mode 0)
		)
		(polygon
			(pts
				(xy 3.732022 -269.103856) (xy 1.369822 -269.103856) (xy 1.369822 -353.254056) (xy 9.015222 -353.254056)
				(xy 9.015222 -269.103856) (xy 6.678422 -269.103856) (xy 6.678422 -266.386056) (xy 3.732022 -266.386056)
			)
		)
	)
	(zone
		(layers "F.Cu" "B.Cu" "In1.Cu" "In2.Cu" "In3.Cu" "In4.Cu" "In5.Cu" "In6.Cu")
		(hatch none 0.5)
		(connect_pads
			(clearance 0)
		)
		(min_thickness 0.25)
		(keepout
			(tracks allowed)
			(vias not_allowed)
			(pads allowed)
			(copperpour not_allowed)
			(footprints allowed)
		)
		(placement
			(enabled no)
			(sheetname "")
		)
		(fill
			(thermal_gap 0.5)
			(thermal_bridge_width 0.5)
			(island_removal_mode 0)
		)
		(polygon
			(pts
				(xy 43.379644 -138.25728) (xy 43.379644 -138.28268) (xy 43.379644 -142.24508) (xy 82.775044 -142.24508)
				(xy 82.800444 -142.24508) (xy 82.800444 -138.28268) (xy 82.800444 -138.25728)
			)
		)
	)
	(zone
		(layers "F.Cu" "B.Cu" "In1.Cu" "In2.Cu" "In3.Cu" "In4.Cu" "In5.Cu" "In6.Cu")
		(hatch none 0.5)
		(connect_pads
			(clearance 0)
		)
		(min_thickness 0.25)
		(keepout
			(tracks not_allowed)
			(vias allowed)
			(pads allowed)
			(copperpour not_allowed)
			(footprints allowed)
		)
		(placement
			(enabled no)
			(sheetname "")
		)
		(fill
			(thermal_gap 0.5)
			(thermal_bridge_width 0.5)
			(island_removal_mode 0)
		)
		(polygon
			(pts
				(arc
					(start 86.878668 -375.61012)
					(mid 91.399868 -371.08892)
					(end 95.921068 -375.61012)
				)
				(arc
					(start 95.921068 -375.61012)
					(mid 91.399868 -380.13132)
					(end 86.878668 -375.61012)
				)
			)
		)
	)
	(zone
		(layers "F.Cu" "B.Cu" "In1.Cu" "In2.Cu" "In3.Cu" "In4.Cu" "In5.Cu" "In6.Cu")
		(hatch none 0.5)
		(connect_pads
			(clearance 0)
		)
		(min_thickness 0.25)
		(keepout
			(tracks not_allowed)
			(vias allowed)
			(pads allowed)
			(copperpour not_allowed)
			(footprints allowed)
		)
		(placement
			(enabled no)
			(sheetname "")
		)
		(fill
			(thermal_gap 0.5)
			(thermal_bridge_width 0.5)
			(island_removal_mode 0)
		)
		(polygon
			(pts
				(arc
					(start 93.15577 -8.26008)
					(mid 94.83979 -6.57606)
					(end 96.52381 -8.26008)
				)
				(arc
					(start 96.52381 -8.26008)
					(mid 94.83979 -9.9441)
					(end 93.15577 -8.26008)
				)
			)
		)
	)
	(zone
		(layers "F.Cu" "B.Cu" "In1.Cu" "In2.Cu" "In3.Cu" "In4.Cu" "In5.Cu" "In6.Cu")
		(hatch none 0.5)
		(connect_pads
			(clearance 0)
		)
		(min_thickness 0.25)
		(keepout
			(tracks not_allowed)
			(vias allowed)
			(pads allowed)
			(copperpour not_allowed)
			(footprints allowed)
		)
		(placement
			(enabled no)
			(sheetname "")
		)
		(fill
			(thermal_gap 0.5)
			(thermal_bridge_width 0.5)
			(island_removal_mode 0)
		)
		(polygon
			(pts
				(arc
					(start 93.15577 -97.16008)
					(mid 94.83979 -95.47606)
					(end 96.52381 -97.16008)
				)
				(arc
					(start 96.52381 -97.16008)
					(mid 94.83979 -98.8441)
					(end 93.15577 -97.16008)
				)
			)
		)
	)
	(zone
		(layers "F.Cu" "B.Cu" "In1.Cu" "In2.Cu" "In3.Cu" "In4.Cu" "In5.Cu" "In6.Cu")
		(hatch none 0.5)
		(connect_pads
			(clearance 0)
		)
		(min_thickness 0.25)
		(keepout
			(tracks not_allowed)
			(vias allowed)
			(pads allowed)
			(copperpour not_allowed)
			(footprints allowed)
		)
		(placement
			(enabled no)
			(sheetname "")
		)
		(fill
			(thermal_gap 0.5)
			(thermal_bridge_width 0.5)
			(island_removal_mode 0)
		)
		(polygon
			(pts
				(arc
					(start 75.488038 -519.049762)
					(mid 78.000098 -516.537702)
					(end 80.512158 -519.049762)
				)
				(arc
					(start 80.512158 -519.049762)
					(mid 78.000098 -521.561822)
					(end 75.488038 -519.049762)
				)
			)
		)
	)
	(zone
		(layers "F.Cu" "B.Cu" "In1.Cu" "In2.Cu" "In3.Cu" "In4.Cu" "In5.Cu" "In6.Cu")
		(hatch none 0.5)
		(connect_pads
			(clearance 0)
		)
		(min_thickness 0.25)
		(keepout
			(tracks not_allowed)
			(vias allowed)
			(pads allowed)
			(copperpour not_allowed)
			(footprints allowed)
		)
		(placement
			(enabled no)
			(sheetname "")
		)
		(fill
			(thermal_gap 0.5)
			(thermal_bridge_width 0.5)
			(island_removal_mode 0)
		)
		(polygon
			(pts
				(arc
					(start 39.819072 -229.16007)
					(mid 41.499536 -227.479606)
					(end 43.18 -229.16007)
				)
				(arc
					(start 43.18 -229.16007)
					(mid 41.499536 -230.840534)
					(end 39.819072 -229.16007)
				)
			)
		)
	)
	(zone
		(layers "F.Cu" "B.Cu" "In1.Cu" "In2.Cu" "In3.Cu" "In4.Cu" "In5.Cu" "In6.Cu")
		(hatch none 0.5)
		(connect_pads
			(clearance 0)
		)
		(min_thickness 0.25)
		(keepout
			(tracks allowed)
			(vias not_allowed)
			(pads allowed)
			(copperpour not_allowed)
			(footprints allowed)
		)
		(placement
			(enabled no)
			(sheetname "")
		)
		(fill
			(thermal_gap 0.5)
			(thermal_bridge_width 0.5)
			(island_removal_mode 0)
		)
		(polygon
			(pts
				(xy 84.984844 -142.80388) (xy 85.010244 -142.80388) (xy 92.655644 -142.80388) (xy 92.655644 -137.69848)
				(xy 85.010244 -137.69848) (xy 84.984844 -137.69848)
			)
		)
	)
	(zone
		(layers "F.Cu" "B.Cu" "In1.Cu" "In2.Cu" "In3.Cu" "In4.Cu" "In5.Cu" "In6.Cu")
		(hatch none 0.5)
		(connect_pads
			(clearance 0)
		)
		(min_thickness 0.25)
		(keepout
			(tracks not_allowed)
			(vias allowed)
			(pads allowed)
			(copperpour not_allowed)
			(footprints allowed)
		)
		(placement
			(enabled no)
			(sheetname "")
		)
		(fill
			(thermal_gap 0.5)
			(thermal_bridge_width 0.5)
			(island_removal_mode 0)
		)
		(polygon
			(pts
				(arc
					(start 14.087856 -118.09984)
					(mid 16.599916 -115.58778)
					(end 19.111976 -118.09984)
				)
				(arc
					(start 19.111976 -118.09984)
					(mid 16.599916 -120.6119)
					(end 14.087856 -118.09984)
				)
			)
		)
	)
	(zone
		(layers "F.Cu" "B.Cu" "In1.Cu" "In2.Cu" "In3.Cu" "In4.Cu" "In5.Cu" "In6.Cu")
		(hatch none 0.5)
		(connect_pads
			(clearance 0)
		)
		(min_thickness 0.25)
		(keepout
			(tracks not_allowed)
			(vias allowed)
			(pads allowed)
			(copperpour not_allowed)
			(footprints allowed)
		)
		(placement
			(enabled no)
			(sheetname "")
		)
		(fill
			(thermal_gap 0.5)
			(thermal_bridge_width 0.5)
			(island_removal_mode 0)
		)
		(polygon
			(pts
				(arc
					(start 3.939032 -342.030812)
					(mid 3.675123 -341.555661)
					(end 3.583686 -341.019892)
				)
				(arc
					(start 3.583686 -341.019892)
					(mid 5.740116 -339.497011)
					(end 6.45414 -342.038686)
				)
				(xy 5.834888 -342.038686)
				(arc
					(start 5.834888 -342.505792)
					(mid 5.201285 -342.635888)
					(end 4.567428 -342.507062)
				)
				(xy 4.567428 -342.030812)
			)
		)
	)
	(zone
		(layers "F.Cu" "B.Cu" "In1.Cu" "In2.Cu" "In3.Cu" "In4.Cu" "In5.Cu" "In6.Cu")
		(hatch none 0.5)
		(connect_pads
			(clearance 0)
		)
		(min_thickness 0.25)
		(keepout
			(tracks not_allowed)
			(vias allowed)
			(pads allowed)
			(copperpour not_allowed)
			(footprints allowed)
		)
		(placement
			(enabled no)
			(sheetname "")
		)
		(fill
			(thermal_gap 0.5)
			(thermal_bridge_width 0.5)
			(island_removal_mode 0)
		)
		(polygon
			(pts
				(arc
					(start 75.487784 -210.09991)
					(mid 77.999844 -207.58785)
					(end 80.511904 -210.09991)
				)
				(arc
					(start 80.511904 -210.09991)
					(mid 77.999844 -212.61197)
					(end 75.487784 -210.09991)
				)
			)
		)
	)
	(zone
		(layers "F.Cu" "B.Cu" "In1.Cu" "In2.Cu" "In3.Cu" "In4.Cu" "In5.Cu" "In6.Cu")
		(hatch none 0.5)
		(connect_pads
			(clearance 0)
		)
		(min_thickness 0.25)
		(keepout
			(tracks allowed)
			(vias not_allowed)
			(pads allowed)
			(copperpour not_allowed)
			(footprints allowed)
		)
		(placement
			(enabled no)
			(sheetname "")
		)
		(fill
			(thermal_gap 0.5)
			(thermal_bridge_width 0.5)
			(island_removal_mode 0)
		)
		(polygon
			(pts
				(xy 84.98459 -276.15388) (xy 85.00999 -276.15388) (xy 92.65539 -276.15388) (xy 92.65539 -271.04848)
				(xy 85.00999 -271.04848) (xy 84.98459 -271.04848)
			)
		)
	)
	(zone
		(layers "F.Cu" "B.Cu" "In1.Cu" "In2.Cu" "In3.Cu" "In4.Cu" "In5.Cu" "In6.Cu")
		(hatch none 0.5)
		(connect_pads
			(clearance 0)
		)
		(min_thickness 0.25)
		(keepout
			(tracks not_allowed)
			(vias allowed)
			(pads allowed)
			(copperpour not_allowed)
			(footprints allowed)
		)
		(placement
			(enabled no)
			(sheetname "")
		)
		(fill
			(thermal_gap 0.5)
			(thermal_bridge_width 0.5)
			(island_removal_mode 0)
		)
		(polygon
			(pts
				(arc
					(start 3.585464 -267.86967)
					(mid 5.199634 -266.2555)
					(end 6.813804 -267.86967)
				)
				(arc
					(start 6.813804 -267.86967)
					(mid 5.199634 -269.48384)
					(end 3.585464 -267.86967)
				)
			)
		)
	)
	(zone
		(layers "F.Cu" "B.Cu" "In1.Cu" "In2.Cu" "In3.Cu" "In4.Cu" "In5.Cu" "In6.Cu")
		(hatch none 0.5)
		(connect_pads
			(clearance 0)
		)
		(min_thickness 0.25)
		(keepout
			(tracks allowed)
			(vias not_allowed)
			(pads allowed)
			(copperpour not_allowed)
			(footprints allowed)
		)
		(placement
			(enabled no)
			(sheetname "")
		)
		(fill
			(thermal_gap 0.5)
			(thermal_bridge_width 0.5)
			(island_removal_mode 0)
		)
		(polygon
			(pts
				(xy 3.731006 -178.104546) (xy 1.368806 -178.104546) (xy 1.368806 -262.254746) (xy 9.014206 -262.254746)
				(xy 9.014206 -178.104546) (xy 6.677406 -178.104546) (xy 6.677406 -175.386746) (xy 3.731006 -175.386746)
			)
		)
	)
	(zone
		(layers "F.Cu" "B.Cu" "In1.Cu" "In2.Cu" "In3.Cu" "In4.Cu" "In5.Cu" "In6.Cu")
		(hatch none 0.5)
		(connect_pads
			(clearance 0)
		)
		(min_thickness 0.25)
		(keepout
			(tracks not_allowed)
			(vias allowed)
			(pads allowed)
			(copperpour not_allowed)
			(footprints allowed)
		)
		(placement
			(enabled no)
			(sheetname "")
		)
		(fill
			(thermal_gap 0.5)
			(thermal_bridge_width 0.5)
			(island_removal_mode 0)
		)
		(polygon
			(pts
				(arc
					(start 86.878668 -197.81012)
					(mid 91.399868 -193.28892)
					(end 95.921068 -197.81012)
				)
				(arc
					(start 95.921068 -197.81012)
					(mid 91.399868 -202.33132)
					(end 86.878668 -197.81012)
				)
			)
		)
	)
	(zone
		(layers "F.Cu" "B.Cu" "In1.Cu" "In2.Cu" "In3.Cu" "In4.Cu" "In5.Cu" "In6.Cu")
		(hatch none 0.5)
		(connect_pads
			(clearance 0)
		)
		(min_thickness 0.25)
		(keepout
			(tracks allowed)
			(vias not_allowed)
			(pads allowed)
			(copperpour not_allowed)
			(footprints allowed)
		)
		(placement
			(enabled no)
			(sheetname "")
		)
		(fill
			(thermal_gap 0.5)
			(thermal_bridge_width 0.5)
			(island_removal_mode 0)
		)
		(polygon
			(pts
				(xy 43.37939 -49.35728) (xy 43.37939 -49.38268) (xy 43.37939 -53.34508) (xy 82.77479 -53.34508)
				(xy 82.80019 -53.34508) (xy 82.80019 -49.38268) (xy 82.80019 -49.35728)
			)
		)
	)
	(zone
		(layers "F.Cu" "B.Cu" "In1.Cu" "In2.Cu" "In3.Cu" "In4.Cu" "In5.Cu" "In6.Cu")
		(hatch none 0.5)
		(connect_pads
			(clearance 0)
		)
		(min_thickness 0.25)
		(keepout
			(tracks not_allowed)
			(vias allowed)
			(pads allowed)
			(copperpour not_allowed)
			(footprints allowed)
		)
		(placement
			(enabled no)
			(sheetname "")
		)
		(fill
			(thermal_gap 0.5)
			(thermal_bridge_width 0.5)
			(island_removal_mode 0)
		)
		(polygon
			(pts
				(arc
					(start 86.878668 -20.01012)
					(mid 91.399868 -15.48892)
					(end 95.921068 -20.01012)
				)
				(arc
					(start 95.921068 -20.01012)
					(mid 91.399868 -24.53132)
					(end 86.878668 -20.01012)
				)
			)
		)
	)
	(zone
		(layers "F.Cu" "B.Cu" "In1.Cu" "In2.Cu" "In3.Cu" "In4.Cu" "In5.Cu" "In6.Cu")
		(name "Package Keepin")
		(hatch none 0.5)
		(connect_pads
			(clearance 0)
		)
		(min_thickness 0.25)
		(keepout
			(tracks allowed)
			(vias allowed)
			(pads allowed)
			(copperpour allowed)
			(footprints allowed)
		)
		(placement
			(enabled no)
			(sheetname "")
		)
		(fill
			(thermal_gap 0.5)
			(thermal_bridge_width 0.5)
			(island_removal_mode 0)
		)
		(polygon
			(pts
				(arc
					(start 101.000052 -1.016)
					(mid 101.695842 -1.304206)
					(end 101.984048 -1.999996)
				)
				(arc
					(start 101.984048 -527.99996)
					(mid 101.695842 -528.69575)
					(end 101.000052 -528.983956)
				)
				(arc
					(start 26.500074 -528.983956)
					(mid 26.157836 -528.842249)
					(end 26.01595 -528.500086)
				)
				(arc
					(start 26.01595 -527.500088)
					(mid 25.279084 -525.721009)
					(end 23.50008 -524.983964)
				)
				(arc
					(start 1.500124 -524.983964)
					(mid 1.157812 -524.842332)
					(end 1.016 -524.500094)
				)
				(arc
					(start 1.016 -5.500116)
					(mid 1.157797 -5.157789)
					(end 1.500124 -5.015992)
				)
				(arc
					(start 23.50008 -5.015992)
					(mid 25.279069 -4.279111)
					(end 26.01595 -2.500122)
				)
				(arc
					(start 26.01595 -1.500124)
					(mid 26.157747 -1.157797)
					(end 26.500074 -1.016)
				)
			)
		)
	)
	(zone
		(layers "F.Cu" "B.Cu" "In1.Cu" "In2.Cu" "In3.Cu" "In4.Cu" "In5.Cu" "In6.Cu")
		(hatch none 0.5)
		(connect_pads
			(clearance 0)
		)
		(min_thickness 0.25)
		(keepout
			(tracks allowed)
			(vias not_allowed)
			(pads allowed)
			(copperpour not_allowed)
			(footprints allowed)
		)
		(placement
			(enabled no)
			(sheetname "")
		)
		(fill
			(thermal_gap 0.5)
			(thermal_bridge_width 0.5)
			(island_removal_mode 0)
		)
		(polygon
			(pts
				(xy 20.605242 -440.603132) (xy 20.605242 -423.077132) (xy 16.541242 -423.077132) (xy 16.541242 -440.603132)
			)
		)
	)
	(zone
		(layers "F.Cu" "B.Cu" "In1.Cu" "In2.Cu" "In3.Cu" "In4.Cu" "In5.Cu" "In6.Cu")
		(hatch none 0.5)
		(connect_pads
			(clearance 0)
		)
		(min_thickness 0.25)
		(keepout
			(tracks not_allowed)
			(vias allowed)
			(pads allowed)
			(copperpour not_allowed)
			(footprints allowed)
		)
		(placement
			(enabled no)
			(sheetname "")
		)
		(fill
			(thermal_gap 0.5)
			(thermal_bridge_width 0.5)
			(island_removal_mode 0)
		)
		(polygon
			(pts
				(arc
					(start 86.878668 -108.909866)
					(mid 91.399868 -104.388666)
					(end 95.921068 -108.909866)
				)
				(arc
					(start 95.921068 -108.909866)
					(mid 91.399868 -113.431066)
					(end 86.878668 -108.909866)
				)
			)
		)
	)
	(zone
		(layers "F.Cu" "B.Cu" "In1.Cu" "In2.Cu" "In3.Cu" "In4.Cu" "In5.Cu" "In6.Cu")
		(hatch none 0.5)
		(connect_pads
			(clearance 0)
		)
		(min_thickness 0.25)
		(keepout
			(tracks allowed)
			(vias not_allowed)
			(pads allowed)
			(copperpour not_allowed)
			(footprints allowed)
		)
		(placement
			(enabled no)
			(sheetname "")
		)
		(fill
			(thermal_gap 0.5)
			(thermal_bridge_width 0.5)
			(island_removal_mode 0)
		)
		(polygon
			(pts
				(xy 84.98459 -498.40388) (xy 85.00999 -498.40388) (xy 92.65539 -498.40388) (xy 92.65539 -493.29848)
				(xy 85.00999 -493.29848) (xy 84.98459 -493.29848)
			)
		)
	)
	(zone
		(layers "F.Cu" "B.Cu" "In1.Cu" "In2.Cu" "In3.Cu" "In4.Cu" "In5.Cu" "In6.Cu")
		(hatch none 0.5)
		(connect_pads
			(clearance 0)
		)
		(min_thickness 0.25)
		(keepout
			(tracks allowed)
			(vias not_allowed)
			(pads allowed)
			(copperpour not_allowed)
			(footprints allowed)
		)
		(placement
			(enabled no)
			(sheetname "")
		)
		(fill
			(thermal_gap 0.5)
			(thermal_bridge_width 0.5)
			(island_removal_mode 0)
		)
		(polygon
			(pts
				(xy 84.98459 -453.95388) (xy 85.00999 -453.95388) (xy 92.65539 -453.95388) (xy 92.65539 -448.84848)
				(xy 85.00999 -448.84848) (xy 84.98459 -448.84848)
			)
		)
	)
	(zone
		(layers "F.Cu" "B.Cu" "In1.Cu" "In2.Cu" "In3.Cu" "In4.Cu" "In5.Cu" "In6.Cu")
		(hatch none 0.5)
		(connect_pads
			(clearance 0)
		)
		(min_thickness 0.25)
		(keepout
			(tracks allowed)
			(vias not_allowed)
			(pads allowed)
			(copperpour not_allowed)
			(footprints allowed)
		)
		(placement
			(enabled no)
			(sheetname "")
		)
		(fill
			(thermal_gap 0.5)
			(thermal_bridge_width 0.5)
			(island_removal_mode 0)
		)
		(polygon
			(pts
				(xy 84.98459 -53.90388) (xy 85.00999 -53.90388) (xy 92.65539 -53.90388) (xy 92.65539 -48.79848)
				(xy 85.00999 -48.79848) (xy 84.98459 -48.79848)
			)
		)
	)
	(zone
		(layers "F.Cu" "B.Cu" "In1.Cu" "In2.Cu" "In3.Cu" "In4.Cu" "In5.Cu" "In6.Cu")
		(hatch none 0.5)
		(connect_pads
			(clearance 0)
		)
		(min_thickness 0.25)
		(keepout
			(tracks not_allowed)
			(vias allowed)
			(pads allowed)
			(copperpour not_allowed)
			(footprints allowed)
		)
		(placement
			(enabled no)
			(sheetname "")
		)
		(fill
			(thermal_gap 0.5)
			(thermal_bridge_width 0.5)
			(island_removal_mode 0)
		)
		(polygon
			(pts
				(arc
					(start 14.087856 -384.79984)
					(mid 16.599916 -382.28778)
					(end 19.111976 -384.79984)
				)
				(arc
					(start 19.111976 -384.79984)
					(mid 16.599916 -387.3119)
					(end 14.087856 -384.79984)
				)
			)
		)
	)
	(zone
		(layers "F.Cu" "B.Cu" "In1.Cu" "In2.Cu" "In3.Cu" "In4.Cu" "In5.Cu" "In6.Cu")
		(hatch none 0.5)
		(connect_pads
			(clearance 0)
		)
		(min_thickness 0.25)
		(keepout
			(tracks not_allowed)
			(vias allowed)
			(pads allowed)
			(copperpour not_allowed)
			(footprints allowed)
		)
		(placement
			(enabled no)
			(sheetname "")
		)
		(fill
			(thermal_gap 0.5)
			(thermal_bridge_width 0.5)
			(island_removal_mode 0)
		)
		(polygon
			(pts
				(arc
					(start 86.878668 -286.709866)
					(mid 91.399868 -282.188666)
					(end 95.921068 -286.709866)
				)
				(arc
					(start 95.921068 -286.709866)
					(mid 91.399868 -291.231066)
					(end 86.878668 -286.709866)
				)
			)
		)
	)
	(zone
		(layers "F.Cu" "B.Cu" "In1.Cu" "In2.Cu" "In3.Cu" "In4.Cu" "In5.Cu" "In6.Cu")
		(hatch none 0.5)
		(connect_pads
			(clearance 0)
		)
		(min_thickness 0.25)
		(keepout
			(tracks not_allowed)
			(vias allowed)
			(pads allowed)
			(copperpour not_allowed)
			(footprints allowed)
		)
		(placement
			(enabled no)
			(sheetname "")
		)
		(fill
			(thermal_gap 0.5)
			(thermal_bridge_width 0.5)
			(island_removal_mode 0)
		)
		(polygon
			(pts
				(arc
					(start 93.15577 -452.76008)
					(mid 94.83979 -451.07606)
					(end 96.52381 -452.76008)
				)
				(arc
					(start 96.52381 -452.76008)
					(mid 94.83979 -454.4441)
					(end 93.15577 -452.76008)
				)
			)
		)
	)
	(zone
		(layers "F.Cu" "B.Cu" "In1.Cu" "In2.Cu" "In3.Cu" "In4.Cu" "In5.Cu" "In6.Cu")
		(hatch none 0.5)
		(connect_pads
			(clearance 0)
		)
		(min_thickness 0.25)
		(keepout
			(tracks not_allowed)
			(vias allowed)
			(pads allowed)
			(copperpour not_allowed)
			(footprints allowed)
		)
		(placement
			(enabled no)
			(sheetname "")
		)
		(fill
			(thermal_gap 0.5)
			(thermal_bridge_width 0.5)
			(island_removal_mode 0)
		)
		(polygon
			(pts
				(arc
					(start 74.888344 -78.299818)
					(mid 77.999844 -75.188318)
					(end 81.111344 -78.299818)
				)
				(arc
					(start 81.111344 -78.299818)
					(mid 77.999844 -81.411318)
					(end 74.888344 -78.299818)
				)
			)
		)
	)
	(zone
		(layers "F.Cu" "B.Cu" "In1.Cu" "In2.Cu" "In3.Cu" "In4.Cu" "In5.Cu" "In6.Cu")
		(hatch none 0.5)
		(connect_pads
			(clearance 0)
		)
		(min_thickness 0.25)
		(keepout
			(tracks not_allowed)
			(vias allowed)
			(pads allowed)
			(copperpour not_allowed)
			(footprints allowed)
		)
		(placement
			(enabled no)
			(sheetname "")
		)
		(fill
			(thermal_gap 0.5)
			(thermal_bridge_width 0.5)
			(island_removal_mode 0)
		)
		(polygon
			(pts
				(arc
					(start 86.878668 -420.06012)
					(mid 91.399868 -415.53892)
					(end 95.921068 -420.06012)
				)
				(arc
					(start 95.921068 -420.06012)
					(mid 91.399868 -424.58132)
					(end 86.878668 -420.06012)
				)
			)
		)
	)
	(zone
		(layers "F.Cu" "B.Cu" "In1.Cu" "In2.Cu" "In3.Cu" "In4.Cu" "In5.Cu" "In6.Cu")
		(hatch none 0.5)
		(connect_pads
			(clearance 0)
		)
		(min_thickness 0.25)
		(keepout
			(tracks allowed)
			(vias not_allowed)
			(pads allowed)
			(copperpour not_allowed)
			(footprints allowed)
		)
		(placement
			(enabled no)
			(sheetname "")
		)
		(fill
			(thermal_gap 0.5)
			(thermal_bridge_width 0.5)
			(island_removal_mode 0)
		)
		(polygon
			(pts
				(xy 84.98459 -231.70388) (xy 85.00999 -231.70388) (xy 92.65539 -231.70388) (xy 92.65539 -226.59848)
				(xy 85.00999 -226.59848) (xy 84.98459 -226.59848)
			)
		)
	)
	(zone
		(layers "F.Cu" "B.Cu" "In1.Cu" "In2.Cu" "In3.Cu" "In4.Cu" "In5.Cu" "In6.Cu")
		(hatch none 0.5)
		(connect_pads
			(clearance 0)
		)
		(min_thickness 0.25)
		(keepout
			(tracks not_allowed)
			(vias allowed)
			(pads allowed)
			(copperpour not_allowed)
			(footprints allowed)
		)
		(placement
			(enabled no)
			(sheetname "")
		)
		(fill
			(thermal_gap 0.5)
			(thermal_bridge_width 0.5)
			(island_removal_mode 0)
		)
		(polygon
			(pts
				(arc
					(start 39.819072 -51.36007)
					(mid 41.499536 -49.679606)
					(end 43.18 -51.36007)
				)
				(arc
					(start 43.18 -51.36007)
					(mid 41.499536 -53.040534)
					(end 39.819072 -51.36007)
				)
			)
		)
	)
	(zone
		(layers "F.Cu" "B.Cu" "In1.Cu" "In2.Cu" "In3.Cu" "In4.Cu" "In5.Cu" "In6.Cu")
		(hatch none 0.5)
		(connect_pads
			(clearance 0)
		)
		(min_thickness 0.25)
		(keepout
			(tracks not_allowed)
			(vias allowed)
			(pads allowed)
			(copperpour not_allowed)
			(footprints allowed)
		)
		(placement
			(enabled no)
			(sheetname "")
		)
		(fill
			(thermal_gap 0.5)
			(thermal_bridge_width 0.5)
			(island_removal_mode 0)
		)
		(polygon
			(pts
				(arc
					(start 93.15577 -497.21008)
					(mid 94.83979 -495.52606)
					(end 96.52381 -497.21008)
				)
				(arc
					(start 96.52381 -497.21008)
					(mid 94.83979 -498.8941)
					(end 93.15577 -497.21008)
				)
			)
		)
	)
	(zone
		(layers "F.Cu" "B.Cu" "In1.Cu" "In2.Cu" "In3.Cu" "In4.Cu" "In5.Cu" "In6.Cu")
		(hatch none 0.5)
		(connect_pads
			(clearance 0)
		)
		(min_thickness 0.25)
		(keepout
			(tracks allowed)
			(vias not_allowed)
			(pads allowed)
			(copperpour not_allowed)
			(footprints allowed)
		)
		(placement
			(enabled no)
			(sheetname "")
		)
		(fill
			(thermal_gap 0.5)
			(thermal_bridge_width 0.5)
			(island_removal_mode 0)
		)
		(polygon
			(pts
				(xy 43.37939 -404.95728) (xy 43.37939 -404.98268) (xy 43.37939 -408.94508) (xy 82.77479 -408.94508)
				(xy 82.80019 -408.94508) (xy 82.80019 -404.98268) (xy 82.80019 -404.95728)
			)
		)
	)
	(zone
		(layers "F.Cu" "B.Cu" "In1.Cu" "In2.Cu" "In3.Cu" "In4.Cu" "In5.Cu" "In6.Cu")
		(hatch none 0.5)
		(connect_pads
			(clearance 0)
		)
		(min_thickness 0.25)
		(keepout
			(tracks not_allowed)
			(vias allowed)
			(pads allowed)
			(copperpour not_allowed)
			(footprints allowed)
		)
		(placement
			(enabled no)
			(sheetname "")
		)
		(fill
			(thermal_gap 0.5)
			(thermal_bridge_width 0.5)
			(island_removal_mode 0)
		)
		(polygon
			(pts
				(arc
					(start 75.487784 -32.29991)
					(mid 77.999844 -29.78785)
					(end 80.511904 -32.29991)
				)
				(arc
					(start 80.511904 -32.29991)
					(mid 77.999844 -34.81197)
					(end 75.487784 -32.29991)
				)
			)
		)
	)
	(zone
		(layers "F.Cu" "B.Cu" "In1.Cu" "In2.Cu" "In3.Cu" "In4.Cu" "In5.Cu" "In6.Cu")
		(name "Route Keepin")
		(hatch none 0.5)
		(connect_pads
			(clearance 0)
		)
		(min_thickness 0.25)
		(keepout
			(tracks allowed)
			(vias allowed)
			(pads allowed)
			(copperpour allowed)
			(footprints allowed)
		)
		(placement
			(enabled no)
			(sheetname "")
		)
		(fill
			(thermal_gap 0.5)
			(thermal_bridge_width 0.5)
			(island_removal_mode 0)
		)
		(polygon
			(pts
				(arc
					(start 101.000052 -0.508)
					(mid 102.055052 -0.944996)
					(end 102.492048 -1.999996)
				)
				(arc
					(start 102.492048 -527.99996)
					(mid 102.055052 -529.05496)
					(end 101.000052 -529.491956)
				)
				(arc
					(start 26.500074 -529.491956)
					(mid 25.798626 -529.201459)
					(end 25.50795 -528.500086)
				)
				(arc
					(start 25.50795 -527.500088)
					(mid 24.919874 -526.08022)
					(end 23.50008 -525.491964)
				)
				(arc
					(start 1.500124 -525.491964)
					(mid 0.798602 -525.201542)
					(end 0.508 -524.500094)
				)
				(arc
					(start 0.508 -5.500116)
					(mid 0.798586 -4.798578)
					(end 1.500124 -4.507992)
				)
				(arc
					(start 23.50008 -4.507992)
					(mid 24.919858 -3.9199)
					(end 25.50795 -2.500122)
				)
				(arc
					(start 25.50795 -1.500124)
					(mid 25.798536 -0.798586)
					(end 26.500074 -0.508)
				)
			)
		)
	)
	(zone
		(layers "F.Cu" "B.Cu" "In1.Cu" "In2.Cu" "In3.Cu" "In4.Cu" "In5.Cu" "In6.Cu")
		(hatch none 0.5)
		(connect_pads
			(clearance 0)
		)
		(min_thickness 0.25)
		(keepout
			(tracks not_allowed)
			(vias allowed)
			(pads allowed)
			(copperpour not_allowed)
			(footprints allowed)
		)
		(placement
			(enabled no)
			(sheetname "")
		)
		(fill
			(thermal_gap 0.5)
			(thermal_bridge_width 0.5)
			(island_removal_mode 0)
		)
		(polygon
			(pts
				(arc
					(start 39.819072 -495.86007)
					(mid 41.499536 -494.179606)
					(end 43.18 -495.86007)
				)
				(arc
					(start 43.18 -495.86007)
					(mid 41.499536 -497.540534)
					(end 39.819072 -495.86007)
				)
			)
		)
	)
	(zone
		(layers "F.Cu" "B.Cu" "In1.Cu" "In2.Cu" "In3.Cu" "In4.Cu" "In5.Cu" "In6.Cu")
		(hatch none 0.5)
		(connect_pads
			(clearance 0)
		)
		(min_thickness 0.25)
		(keepout
			(tracks allowed)
			(vias not_allowed)
			(pads allowed)
			(copperpour not_allowed)
			(footprints allowed)
		)
		(placement
			(enabled no)
			(sheetname "")
		)
		(fill
			(thermal_gap 0.5)
			(thermal_bridge_width 0.5)
			(island_removal_mode 0)
		)
		(polygon
			(pts
				(xy 84.98459 -9.45388) (xy 85.00999 -9.45388) (xy 92.65539 -9.45388) (xy 92.65539 -4.34848) (xy 85.00999 -4.34848)
				(xy 84.98459 -4.34848)
			)
		)
	)
	(zone
		(layers "F.Cu" "B.Cu" "In1.Cu" "In2.Cu" "In3.Cu" "In4.Cu" "In5.Cu" "In6.Cu")
		(hatch none 0.5)
		(connect_pads
			(clearance 0)
		)
		(min_thickness 0.25)
		(keepout
			(tracks not_allowed)
			(vias allowed)
			(pads allowed)
			(copperpour not_allowed)
			(footprints allowed)
		)
		(placement
			(enabled no)
			(sheetname "")
		)
		(fill
			(thermal_gap 0.5)
			(thermal_bridge_width 0.5)
			(island_removal_mode 0)
		)
		(polygon
			(pts
				(arc
					(start 93.156024 -141.61008)
					(mid 94.840044 -139.92606)
					(end 96.524064 -141.61008)
				)
				(arc
					(start 96.524064 -141.61008)
					(mid 94.840044 -143.2941)
					(end 93.156024 -141.61008)
				)
			)
		)
	)
	(zone
		(layers "F.Cu" "B.Cu" "In1.Cu" "In2.Cu" "In3.Cu" "In4.Cu" "In5.Cu" "In6.Cu")
		(hatch none 0.5)
		(connect_pads
			(clearance 0)
		)
		(min_thickness 0.25)
		(keepout
			(tracks allowed)
			(vias not_allowed)
			(pads allowed)
			(copperpour not_allowed)
			(footprints allowed)
		)
		(placement
			(enabled no)
			(sheetname "")
		)
		(fill
			(thermal_gap 0.5)
			(thermal_bridge_width 0.5)
			(island_removal_mode 0)
		)
		(polygon
			(pts
				(xy 43.37939 -493.85728) (xy 43.37939 -493.88268) (xy 43.37939 -497.84508) (xy 82.77479 -497.84508)
				(xy 82.80019 -497.84508) (xy 82.80019 -493.88268) (xy 82.80019 -493.85728)
			)
		)
	)
	(zone
		(layers "F.Cu" "B.Cu" "In1.Cu" "In2.Cu" "In3.Cu" "In4.Cu" "In5.Cu" "In6.Cu")
		(hatch none 0.5)
		(connect_pads
			(clearance 0)
		)
		(min_thickness 0.25)
		(keepout
			(tracks allowed)
			(vias not_allowed)
			(pads allowed)
			(copperpour not_allowed)
			(footprints allowed)
		)
		(placement
			(enabled no)
			(sheetname "")
		)
		(fill
			(thermal_gap 0.5)
			(thermal_bridge_width 0.5)
			(island_removal_mode 0)
		)
		(polygon
			(pts
				(xy 84.98459 -98.35388) (xy 85.00999 -98.35388) (xy 92.65539 -98.35388) (xy 92.65539 -93.24848)
				(xy 85.00999 -93.24848) (xy 84.98459 -93.24848)
			)
		)
	)
	(zone
		(layers "F.Cu" "B.Cu" "In1.Cu" "In2.Cu" "In3.Cu" "In4.Cu" "In5.Cu" "In6.Cu")
		(hatch none 0.5)
		(connect_pads
			(clearance 0)
		)
		(min_thickness 0.25)
		(keepout
			(tracks not_allowed)
			(vias allowed)
			(pads allowed)
			(copperpour not_allowed)
			(footprints allowed)
		)
		(placement
			(enabled no)
			(sheetname "")
		)
		(fill
			(thermal_gap 0.5)
			(thermal_bridge_width 0.5)
			(island_removal_mode 0)
		)
		(polygon
			(pts
				(arc
					(start 93.15577 -319.41008)
					(mid 94.83979 -317.72606)
					(end 96.52381 -319.41008)
				)
				(arc
					(start 96.52381 -319.41008)
					(mid 94.83979 -321.0941)
					(end 93.15577 -319.41008)
				)
			)
		)
	)
	(zone
		(layers "F.Cu" "B.Cu" "In1.Cu" "In2.Cu" "In3.Cu" "In4.Cu" "In5.Cu" "In6.Cu")
		(hatch none 0.5)
		(connect_pads
			(clearance 0)
		)
		(min_thickness 0.25)
		(keepout
			(tracks not_allowed)
			(vias allowed)
			(pads allowed)
			(copperpour not_allowed)
			(footprints allowed)
		)
		(placement
			(enabled no)
			(sheetname "")
		)
		(fill
			(thermal_gap 0.5)
			(thermal_bridge_width 0.5)
			(island_removal_mode 0)
		)
		(polygon
			(pts
				(arc
					(start 93.156024 -186.06008)
					(mid 94.840044 -184.37606)
					(end 96.524064 -186.06008)
				)
				(arc
					(start 96.524064 -186.06008)
					(mid 94.840044 -187.7441)
					(end 93.156024 -186.06008)
				)
			)
		)
	)
	(zone
		(layers "F.Cu" "B.Cu" "In2.Cu" "In3.Cu" "In4.Cu" "In5.Cu")
		(hatch none 0.5)
		(connect_pads
			(clearance 0)
		)
		(min_thickness 0.25)
		(keepout
			(tracks not_allowed)
			(vias allowed)
			(pads allowed)
			(copperpour not_allowed)
			(footprints allowed)
		)
		(placement
			(enabled no)
			(sheetname "")
		)
		(fill yes
			(thermal_gap 0.5)
			(thermal_bridge_width 0.5)
			(island_removal_mode 0)
		)
		(polygon
			(pts
				(arc
					(start 81.107788 -477.799908)
					(mid 77.999844 -474.691964)
					(end 74.8919 -477.799908)
				)
				(arc
					(start 74.8919 -478.799906)
					(mid 77.999844 -481.90785)
					(end 81.107788 -478.799906)
				)
			)
		)
	)
	(zone
		(layer "B.Cu")
		(hatch none 0.5)
		(connect_pads
			(clearance 0)
		)
		(min_thickness 0.25)
		(keepout
			(tracks not_allowed)
			(vias allowed)
			(pads allowed)
			(copperpour not_allowed)
			(footprints allowed)
		)
		(placement
			(enabled no)
			(sheetname "")
		)
		(fill
			(thermal_gap 0.5)
			(thermal_bridge_width 0.5)
			(island_removal_mode 0)
		)
		(polygon
			(pts
				(arc
					(start 21.599906 -207.000094)
					(mid 16.599916 -202.000104)
					(end 11.599926 -207.000094)
				)
				(arc
					(start 11.599926 -207.000094)
					(mid 16.599916 -212.000084)
					(end 21.599906 -207.000094)
				)
			)
		)
	)
	(zone
		(layer "B.Cu")
		(hatch none 0.5)
		(connect_pads
			(clearance 0)
		)
		(min_thickness 0.25)
		(keepout
			(tracks allowed)
			(vias allowed)
			(pads allowed)
			(copperpour allowed)
			(footprints not_allowed)
		)
		(placement
			(enabled no)
			(sheetname "")
		)
		(fill
			(thermal_gap 0.5)
			(thermal_bridge_width 0.5)
			(island_removal_mode 0)
		)
		(polygon
			(pts
				(arc
					(start 73.000108 -210.09991)
					(mid 78.000098 -215.0999)
					(end 83.000088 -210.09991)
				)
				(arc
					(start 83.000088 -210.09991)
					(mid 78.000098 -205.09992)
					(end 73.000108 -210.09991)
				)
			)
		)
	)
	(zone
		(layer "B.Cu")
		(hatch none 0.5)
		(connect_pads
			(clearance 0)
		)
		(min_thickness 0.25)
		(keepout
			(tracks allowed)
			(vias allowed)
			(pads allowed)
			(copperpour allowed)
			(footprints not_allowed)
		)
		(placement
			(enabled no)
			(sheetname "")
		)
		(fill
			(thermal_gap 0.5)
			(thermal_bridge_width 0.5)
			(island_removal_mode 0)
		)
		(polygon
			(pts
				(xy 39.180008 -358.585008) (xy 39.180008 -366.434878) (xy 97.16008 -366.434878) (xy 97.16008 -358.585008)
			)
		)
	)
	(zone
		(layer "B.Cu")
		(hatch none 0.5)
		(connect_pads
			(clearance 0)
		)
		(min_thickness 0.25)
		(keepout
			(tracks allowed)
			(vias allowed)
			(pads allowed)
			(copperpour allowed)
			(footprints not_allowed)
		)
		(placement
			(enabled no)
			(sheetname "")
		)
		(fill
			(thermal_gap 0.5)
			(thermal_bridge_width 0.5)
			(island_removal_mode 0)
		)
		(polygon
			(pts
				(arc
					(start 11.599926 -295.900094)
					(mid 16.599916 -300.900084)
					(end 21.599906 -295.900094)
				)
				(arc
					(start 21.599906 -295.900094)
					(mid 16.599916 -290.900104)
					(end 11.599926 -295.900094)
				)
			)
		)
	)
	(zone
		(layer "B.Cu")
		(hatch none 0.5)
		(connect_pads
			(clearance 0)
		)
		(min_thickness 0.25)
		(keepout
			(tracks not_allowed)
			(vias allowed)
			(pads allowed)
			(copperpour not_allowed)
			(footprints allowed)
		)
		(placement
			(enabled no)
			(sheetname "")
		)
		(fill
			(thermal_gap 0.5)
			(thermal_bridge_width 0.5)
			(island_removal_mode 0)
		)
		(polygon
			(pts
				(arc
					(start 21.599906 -384.800094)
					(mid 16.599916 -379.800104)
					(end 11.599926 -384.800094)
				)
				(arc
					(start 11.599926 -384.800094)
					(mid 16.599916 -389.800084)
					(end 21.599906 -384.800094)
				)
			)
		)
	)
	(zone
		(layer "B.Cu")
		(hatch none 0.5)
		(connect_pads
			(clearance 0)
		)
		(min_thickness 0.25)
		(keepout
			(tracks allowed)
			(vias allowed)
			(pads allowed)
			(copperpour allowed)
			(footprints not_allowed)
		)
		(placement
			(enabled no)
			(sheetname "")
		)
		(fill
			(thermal_gap 0.5)
			(thermal_bridge_width 0.5)
			(island_removal_mode 0)
		)
		(polygon
			(pts
				(xy 39.180008 -403.035008) (xy 39.180008 -410.884878) (xy 97.16008 -410.884878) (xy 97.16008 -403.035008)
			)
		)
	)
	(zone
		(layer "B.Cu")
		(hatch none 0.5)
		(connect_pads
			(clearance 0)
		)
		(min_thickness 0.25)
		(keepout
			(tracks not_allowed)
			(vias allowed)
			(pads allowed)
			(copperpour not_allowed)
			(footprints allowed)
		)
		(placement
			(enabled no)
			(sheetname "")
		)
		(fill
			(thermal_gap 0.5)
			(thermal_bridge_width 0.5)
			(island_removal_mode 0)
		)
		(polygon
			(pts
				(arc
					(start 96.400112 -108.91012)
					(mid 91.400122 -103.91013)
					(end 86.399878 -108.91012)
				)
				(arc
					(start 86.399878 -108.91012)
					(mid 91.400122 -113.910364)
					(end 96.400112 -108.91012)
				)
			)
		)
	)
	(zone
		(layer "B.Cu")
		(hatch none 0.5)
		(connect_pads
			(clearance 0)
		)
		(min_thickness 0.25)
		(keepout
			(tracks allowed)
			(vias allowed)
			(pads allowed)
			(copperpour allowed)
			(footprints not_allowed)
		)
		(placement
			(enabled no)
			(sheetname "")
		)
		(fill
			(thermal_gap 0.5)
			(thermal_bridge_width 0.5)
			(island_removal_mode 0)
		)
		(polygon
			(pts
				(arc
					(start 11.599926 -29.200094)
					(mid 16.599916 -34.200084)
					(end 21.599906 -29.200094)
				)
				(arc
					(start 21.599906 -29.200094)
					(mid 16.599916 -24.200104)
					(end 11.599926 -29.200094)
				)
			)
		)
	)
	(zone
		(layer "B.Cu")
		(hatch none 0.5)
		(connect_pads
			(clearance 0)
		)
		(min_thickness 0.25)
		(keepout
			(tracks not_allowed)
			(vias allowed)
			(pads allowed)
			(copperpour not_allowed)
			(footprints allowed)
		)
		(placement
			(enabled no)
			(sheetname "")
		)
		(fill
			(thermal_gap 0.5)
			(thermal_bridge_width 0.5)
			(island_removal_mode 0)
		)
		(polygon
			(pts
				(arc
					(start 96.400112 -464.51012)
					(mid 91.400122 -459.51013)
					(end 86.399878 -464.51012)
				)
				(arc
					(start 86.399878 -464.51012)
					(mid 91.400122 -469.510364)
					(end 96.400112 -464.51012)
				)
			)
		)
	)
	(zone
		(layer "B.Cu")
		(hatch none 0.5)
		(connect_pads
			(clearance 0)
		)
		(min_thickness 0.25)
		(keepout
			(tracks not_allowed)
			(vias allowed)
			(pads allowed)
			(copperpour not_allowed)
			(footprints allowed)
		)
		(placement
			(enabled no)
			(sheetname "")
		)
		(fill
			(thermal_gap 0.5)
			(thermal_bridge_width 0.5)
			(island_removal_mode 0)
		)
		(polygon
			(pts
				(arc
					(start 81.60004 -78.300072)
					(mid 78.000098 -74.70013)
					(end 74.399902 -78.300072)
				)
				(arc
					(start 74.399902 -78.300072)
					(mid 78.000098 -81.900268)
					(end 81.60004 -78.300072)
				)
			)
		)
	)
	(zone
		(layer "B.Cu")
		(hatch none 0.5)
		(connect_pads
			(clearance 0)
		)
		(min_thickness 0.25)
		(keepout
			(tracks not_allowed)
			(vias allowed)
			(pads allowed)
			(copperpour not_allowed)
			(footprints allowed)
		)
		(placement
			(enabled no)
			(sheetname "")
		)
		(fill
			(thermal_gap 0.5)
			(thermal_bridge_width 0.5)
			(island_removal_mode 0)
		)
		(polygon
			(pts
				(arc
					(start 21.599906 -295.900094)
					(mid 16.599916 -290.900104)
					(end 11.599926 -295.900094)
				)
				(arc
					(start 11.599926 -295.900094)
					(mid 16.599916 -300.900084)
					(end 21.599906 -295.900094)
				)
			)
		)
	)
	(zone
		(layer "B.Cu")
		(hatch none 0.5)
		(connect_pads
			(clearance 0)
		)
		(min_thickness 0.25)
		(keepout
			(tracks not_allowed)
			(vias allowed)
			(pads allowed)
			(copperpour not_allowed)
			(footprints allowed)
		)
		(placement
			(enabled no)
			(sheetname "")
		)
		(fill
			(thermal_gap 0.5)
			(thermal_bridge_width 0.5)
			(island_removal_mode 0)
		)
		(polygon
			(pts
				(arc
					(start 21.599906 -473.700094)
					(mid 16.599916 -468.700104)
					(end 11.599926 -473.700094)
				)
				(arc
					(start 11.599926 -473.700094)
					(mid 16.599916 -478.700084)
					(end 21.599906 -473.700094)
				)
			)
		)
	)
	(zone
		(layer "B.Cu")
		(hatch none 0.5)
		(connect_pads
			(clearance 0)
		)
		(min_thickness 0.25)
		(keepout
			(tracks not_allowed)
			(vias allowed)
			(pads allowed)
			(copperpour not_allowed)
			(footprints allowed)
		)
		(placement
			(enabled no)
			(sheetname "")
		)
		(fill
			(thermal_gap 0.5)
			(thermal_bridge_width 0.5)
			(island_removal_mode 0)
		)
		(polygon
			(pts
				(arc
					(start 96.400112 -286.71012)
					(mid 91.400122 -281.71013)
					(end 86.399878 -286.71012)
				)
				(arc
					(start 86.399878 -286.71012)
					(mid 91.400122 -291.710364)
					(end 96.400112 -286.71012)
				)
			)
		)
	)
	(zone
		(layer "B.Cu")
		(hatch none 0.5)
		(connect_pads
			(clearance 0)
		)
		(min_thickness 0.25)
		(keepout
			(tracks not_allowed)
			(vias allowed)
			(pads allowed)
			(copperpour not_allowed)
			(footprints allowed)
		)
		(placement
			(enabled no)
			(sheetname "")
		)
		(fill
			(thermal_gap 0.5)
			(thermal_bridge_width 0.5)
			(island_removal_mode 0)
		)
		(polygon
			(pts
				(arc
					(start 76.000102 -32.29991)
					(mid 78.000098 -34.299906)
					(end 80.000094 -32.29991)
				)
				(arc
					(start 80.000094 -32.29991)
					(mid 78.000098 -30.299914)
					(end 76.000102 -32.29991)
				)
			)
		)
	)
	(zone
		(layer "B.Cu")
		(hatch none 0.5)
		(connect_pads
			(clearance 0)
		)
		(min_thickness 0.25)
		(keepout
			(tracks not_allowed)
			(vias allowed)
			(pads allowed)
			(copperpour not_allowed)
			(footprints allowed)
		)
		(placement
			(enabled no)
			(sheetname "")
		)
		(fill
			(thermal_gap 0.5)
			(thermal_bridge_width 0.5)
			(island_removal_mode 0)
		)
		(polygon
			(pts
				(arc
					(start 96.400112 -375.61012)
					(mid 91.400122 -370.61013)
					(end 86.399878 -375.61012)
				)
				(arc
					(start 86.399878 -375.61012)
					(mid 91.400122 -380.610364)
					(end 96.400112 -375.61012)
				)
			)
		)
	)
	(zone
		(layer "B.Cu")
		(hatch none 0.5)
		(connect_pads
			(clearance 0)
		)
		(min_thickness 0.25)
		(keepout
			(tracks allowed)
			(vias allowed)
			(pads allowed)
			(copperpour allowed)
			(footprints not_allowed)
		)
		(placement
			(enabled no)
			(sheetname "")
		)
		(fill
			(thermal_gap 0.5)
			(thermal_bridge_width 0.5)
			(island_removal_mode 0)
		)
		(polygon
			(pts
				(arc
					(start 86.000082 -430.150016)
					(mid 78.000098 -422.150032)
					(end 70.000114 -430.150016)
				)
				(arc
					(start 70.000114 -430.150016)
					(mid 78.000098 -438.15)
					(end 86.000082 -430.150016)
				)
			)
		)
	)
	(zone
		(layer "B.Cu")
		(hatch none 0.5)
		(connect_pads
			(clearance 0)
		)
		(min_thickness 0.25)
		(keepout
			(tracks not_allowed)
			(vias allowed)
			(pads allowed)
			(copperpour not_allowed)
			(footprints allowed)
		)
		(placement
			(enabled no)
			(sheetname "")
		)
		(fill
			(thermal_gap 0.5)
			(thermal_bridge_width 0.5)
			(island_removal_mode 0)
		)
		(polygon
			(pts
				(arc
					(start 89.211404 -516.95858)
					(mid 87.585804 -515.33298)
					(end 85.960204 -516.95858)
				)
				(arc
					(start 85.960204 -516.95858)
					(mid 87.585804 -518.58418)
					(end 89.211404 -516.95858)
				)
			)
		)
	)
	(zone
		(layer "B.Cu")
		(hatch none 0.5)
		(connect_pads
			(clearance 0)
		)
		(min_thickness 0.25)
		(keepout
			(tracks allowed)
			(vias allowed)
			(pads allowed)
			(copperpour allowed)
			(footprints not_allowed)
		)
		(placement
			(enabled no)
			(sheetname "")
		)
		(fill
			(thermal_gap 0.5)
			(thermal_bridge_width 0.5)
			(island_removal_mode 0)
		)
		(polygon
			(pts
				(xy 39.180008 -314.135008) (xy 39.180008 -321.984878) (xy 97.16008 -321.984878) (xy 97.16008 -314.135008)
			)
		)
	)
	(zone
		(layer "B.Cu")
		(hatch none 0.5)
		(connect_pads
			(clearance 0)
		)
		(min_thickness 0.25)
		(keepout
			(tracks allowed)
			(vias allowed)
			(pads allowed)
			(copperpour allowed)
			(footprints not_allowed)
		)
		(placement
			(enabled no)
			(sheetname "")
		)
		(fill
			(thermal_gap 0.5)
			(thermal_bridge_width 0.5)
			(island_removal_mode 0)
		)
		(polygon
			(pts
				(xy 39.180008 -2.985008) (xy 39.180008 -10.834878) (xy 97.16008 -10.834878) (xy 97.16008 -2.985008)
			)
		)
	)
	(zone
		(layer "B.Cu")
		(hatch none 0.5)
		(connect_pads
			(clearance 0)
		)
		(min_thickness 0.25)
		(keepout
			(tracks not_allowed)
			(vias allowed)
			(pads allowed)
			(copperpour not_allowed)
			(footprints allowed)
		)
		(placement
			(enabled no)
			(sheetname "")
		)
		(fill
			(thermal_gap 0.5)
			(thermal_bridge_width 0.5)
			(island_removal_mode 0)
		)
		(polygon
			(pts
				(arc
					(start 96.400112 -197.81012)
					(mid 91.400122 -192.81013)
					(end 86.399878 -197.81012)
				)
				(arc
					(start 86.399878 -197.81012)
					(mid 91.400122 -202.810364)
					(end 96.400112 -197.81012)
				)
			)
		)
	)
	(zone
		(layer "B.Cu")
		(hatch none 0.5)
		(connect_pads
			(clearance 0)
		)
		(min_thickness 0.25)
		(keepout
			(tracks allowed)
			(vias allowed)
			(pads allowed)
			(copperpour allowed)
			(footprints not_allowed)
		)
		(placement
			(enabled no)
			(sheetname "")
		)
		(fill
			(thermal_gap 0.5)
			(thermal_bridge_width 0.5)
			(island_removal_mode 0)
		)
		(polygon
			(pts
				(arc
					(start 86.000082 -210.09991)
					(mid 78.000098 -202.099926)
					(end 70.000114 -210.09991)
				)
				(arc
					(start 70.000114 -210.09991)
					(mid 78.000098 -218.099894)
					(end 86.000082 -210.09991)
				)
			)
		)
	)
	(zone
		(layer "B.Cu")
		(hatch none 0.5)
		(connect_pads
			(clearance 0)
		)
		(min_thickness 0.25)
		(keepout
			(tracks not_allowed)
			(vias allowed)
			(pads allowed)
			(copperpour not_allowed)
			(footprints allowed)
		)
		(placement
			(enabled no)
			(sheetname "")
		)
		(fill
			(thermal_gap 0.5)
			(thermal_bridge_width 0.5)
			(island_removal_mode 0)
		)
		(polygon
			(pts
				(arc
					(start 74.399902 -478.799906)
					(mid 78.000098 -482.400102)
					(end 81.60004 -478.799906)
				)
				(arc
					(start 81.60004 -477.799908)
					(mid 78.000098 -474.199966)
					(end 74.399902 -477.799908)
				)
			)
		)
	)
	(zone
		(layer "B.Cu")
		(hatch none 0.5)
		(connect_pads
			(clearance 0)
		)
		(min_thickness 0.25)
		(keepout
			(tracks not_allowed)
			(vias allowed)
			(pads allowed)
			(copperpour not_allowed)
			(footprints allowed)
		)
		(placement
			(enabled no)
			(sheetname "")
		)
		(fill
			(thermal_gap 0.5)
			(thermal_bridge_width 0.5)
			(island_removal_mode 0)
		)
		(polygon
			(pts
				(arc
					(start 76.000102 -519.050016)
					(mid 78.000098 -521.050012)
					(end 80.000094 -519.050016)
				)
				(arc
					(start 80.000094 -519.050016)
					(mid 78.000098 -517.05002)
					(end 76.000102 -519.050016)
				)
			)
		)
	)
	(zone
		(layer "B.Cu")
		(hatch none 0.5)
		(connect_pads
			(clearance 0)
		)
		(min_thickness 0.25)
		(keepout
			(tracks not_allowed)
			(vias allowed)
			(pads allowed)
			(copperpour not_allowed)
			(footprints allowed)
		)
		(placement
			(enabled no)
			(sheetname "")
		)
		(fill
			(thermal_gap 0.5)
			(thermal_bridge_width 0.5)
			(island_removal_mode 0)
		)
		(polygon
			(pts
				(arc
					(start 15.635732 -224.098358)
					(mid 14.010132 -222.472758)
					(end 12.384532 -224.098358)
				)
				(arc
					(start 12.384532 -224.098358)
					(mid 14.010132 -225.723958)
					(end 15.635732 -224.098358)
				)
			)
		)
	)
	(zone
		(layer "B.Cu")
		(hatch none 0.5)
		(connect_pads
			(clearance 0)
		)
		(min_thickness 0.25)
		(keepout
			(tracks allowed)
			(vias allowed)
			(pads allowed)
			(copperpour allowed)
			(footprints not_allowed)
		)
		(placement
			(enabled no)
			(sheetname "")
		)
		(fill
			(thermal_gap 0.5)
			(thermal_bridge_width 0.5)
			(island_removal_mode 0)
		)
		(polygon
			(pts
				(arc
					(start 86.000082 -32.29991)
					(mid 78.000098 -24.299926)
					(end 70.000114 -32.29991)
				)
				(arc
					(start 70.000114 -32.29991)
					(mid 78.000098 -40.299894)
					(end 86.000082 -32.29991)
				)
			)
		)
	)
	(zone
		(layer "B.Cu")
		(hatch none 0.5)
		(connect_pads
			(clearance 0)
		)
		(min_thickness 0.25)
		(keepout
			(tracks not_allowed)
			(vias allowed)
			(pads allowed)
			(copperpour not_allowed)
			(footprints allowed)
		)
		(placement
			(enabled no)
			(sheetname "")
		)
		(fill
			(thermal_gap 0.5)
			(thermal_bridge_width 0.5)
			(island_removal_mode 0)
		)
		(polygon
			(pts
				(arc
					(start 21.599906 -118.100094)
					(mid 16.599916 -113.100104)
					(end 11.599926 -118.100094)
				)
				(arc
					(start 11.599926 -118.100094)
					(mid 16.599916 -123.100084)
					(end 21.599906 -118.100094)
				)
			)
		)
	)
	(zone
		(layer "B.Cu")
		(hatch none 0.5)
		(connect_pads
			(clearance 0)
		)
		(min_thickness 0.25)
		(keepout
			(tracks not_allowed)
			(vias allowed)
			(pads allowed)
			(copperpour not_allowed)
			(footprints allowed)
		)
		(placement
			(enabled no)
			(sheetname "")
		)
		(fill
			(thermal_gap 0.5)
			(thermal_bridge_width 0.5)
			(island_removal_mode 0)
		)
		(polygon
			(pts
				(arc
					(start 83.000088 -210.09991)
					(mid 78.000098 -205.09992)
					(end 73.000108 -210.09991)
				)
				(arc
					(start 73.000108 -210.09991)
					(mid 78.000098 -215.0999)
					(end 83.000088 -210.09991)
				)
			)
		)
	)
	(zone
		(layer "B.Cu")
		(hatch none 0.5)
		(connect_pads
			(clearance 0)
		)
		(min_thickness 0.25)
		(keepout
			(tracks not_allowed)
			(vias allowed)
			(pads allowed)
			(copperpour not_allowed)
			(footprints allowed)
		)
		(placement
			(enabled no)
			(sheetname "")
		)
		(fill
			(thermal_gap 0.5)
			(thermal_bridge_width 0.5)
			(island_removal_mode 0)
		)
		(polygon
			(pts
				(arc
					(start 14.59992 -207.000094)
					(mid 16.599916 -209.00009)
					(end 18.599912 -207.000094)
				)
				(arc
					(start 18.599912 -207.000094)
					(mid 16.599916 -205.000098)
					(end 14.59992 -207.000094)
				)
			)
		)
	)
	(zone
		(layer "B.Cu")
		(hatch none 0.5)
		(connect_pads
			(clearance 0)
		)
		(min_thickness 0.25)
		(keepout
			(tracks not_allowed)
			(vias allowed)
			(pads allowed)
			(copperpour not_allowed)
			(footprints allowed)
		)
		(placement
			(enabled no)
			(sheetname "")
		)
		(fill
			(thermal_gap 0.5)
			(thermal_bridge_width 0.5)
			(island_removal_mode 0)
		)
		(polygon
			(pts
				(arc
					(start 96.400112 -242.26012)
					(mid 91.400122 -237.26013)
					(end 86.399878 -242.26012)
				)
				(arc
					(start 86.399878 -242.26012)
					(mid 91.400122 -247.260364)
					(end 96.400112 -242.26012)
				)
			)
		)
	)
	(zone
		(layer "B.Cu")
		(hatch none 0.5)
		(connect_pads
			(clearance 0)
		)
		(min_thickness 0.25)
		(keepout
			(tracks not_allowed)
			(vias allowed)
			(pads allowed)
			(copperpour not_allowed)
			(footprints allowed)
		)
		(placement
			(enabled no)
			(sheetname "")
		)
		(fill
			(thermal_gap 0.5)
			(thermal_bridge_width 0.5)
			(island_removal_mode 0)
		)
		(polygon
			(pts
				(arc
					(start 87.399876 -64.46012)
					(mid 91.400122 -68.460366)
					(end 95.400114 -64.46012)
				)
				(arc
					(start 95.400114 -64.46012)
					(mid 91.400122 -60.460128)
					(end 87.399876 -64.46012)
				)
			)
		)
	)
	(zone
		(layer "B.Cu")
		(hatch none 0.5)
		(connect_pads
			(clearance 0)
		)
		(min_thickness 0.25)
		(keepout
			(tracks allowed)
			(vias allowed)
			(pads allowed)
			(copperpour allowed)
			(footprints not_allowed)
		)
		(placement
			(enabled no)
			(sheetname "")
		)
		(fill
			(thermal_gap 0.5)
			(thermal_bridge_width 0.5)
			(island_removal_mode 0)
		)
		(polygon
			(pts
				(arc
					(start 86.000082 -519.050016)
					(mid 78.000098 -511.050032)
					(end 70.000114 -519.050016)
				)
				(arc
					(start 70.000114 -519.050016)
					(mid 78.000098 -527.05)
					(end 86.000082 -519.050016)
				)
			)
		)
	)
	(zone
		(layer "B.Cu")
		(hatch none 0.5)
		(connect_pads
			(clearance 0)
		)
		(min_thickness 0.25)
		(keepout
			(tracks allowed)
			(vias allowed)
			(pads allowed)
			(copperpour allowed)
			(footprints not_allowed)
		)
		(placement
			(enabled no)
			(sheetname "")
		)
		(fill
			(thermal_gap 0.5)
			(thermal_bridge_width 0.5)
			(island_removal_mode 0)
		)
		(polygon
			(pts
				(arc
					(start 73.000108 -121.19991)
					(mid 78.000098 -126.1999)
					(end 83.000088 -121.19991)
				)
				(arc
					(start 83.000088 -121.19991)
					(mid 78.000098 -116.19992)
					(end 73.000108 -121.19991)
				)
			)
		)
	)
	(zone
		(layer "B.Cu")
		(hatch none 0.5)
		(connect_pads
			(clearance 0)
		)
		(min_thickness 0.25)
		(keepout
			(tracks not_allowed)
			(vias allowed)
			(pads allowed)
			(copperpour not_allowed)
			(footprints allowed)
		)
		(placement
			(enabled no)
			(sheetname "")
		)
		(fill
			(thermal_gap 0.5)
			(thermal_bridge_width 0.5)
			(island_removal_mode 0)
		)
		(polygon
			(pts
				(arc
					(start 75.3999 -478.799906)
					(mid 78.000098 -481.400104)
					(end 80.600042 -478.799906)
				)
				(arc
					(start 80.600042 -477.799908)
					(mid 78.000098 -475.199964)
					(end 75.3999 -477.799908)
				)
			)
		)
	)
	(zone
		(layer "B.Cu")
		(hatch none 0.5)
		(connect_pads
			(clearance 0)
		)
		(min_thickness 0.25)
		(keepout
			(tracks not_allowed)
			(vias allowed)
			(pads allowed)
			(copperpour not_allowed)
			(footprints allowed)
		)
		(placement
			(enabled no)
			(sheetname "")
		)
		(fill
			(thermal_gap 0.5)
			(thermal_bridge_width 0.5)
			(island_removal_mode 0)
		)
		(polygon
			(pts
				(arc
					(start 21.599906 -29.200094)
					(mid 16.599916 -24.200104)
					(end 11.599926 -29.200094)
				)
				(arc
					(start 11.599926 -29.200094)
					(mid 16.599916 -34.200084)
					(end 21.599906 -29.200094)
				)
			)
		)
	)
	(zone
		(layer "B.Cu")
		(hatch none 0.5)
		(connect_pads
			(clearance 0)
		)
		(min_thickness 0.25)
		(keepout
			(tracks allowed)
			(vias allowed)
			(pads allowed)
			(copperpour allowed)
			(footprints not_allowed)
		)
		(placement
			(enabled no)
			(sheetname "")
		)
		(fill
			(thermal_gap 0.5)
			(thermal_bridge_width 0.5)
			(island_removal_mode 0)
		)
		(polygon
			(pts
				(arc
					(start 11.599926 -207.000094)
					(mid 16.599916 -212.000084)
					(end 21.599906 -207.000094)
				)
				(arc
					(start 21.599906 -207.000094)
					(mid 16.599916 -202.000104)
					(end 11.599926 -207.000094)
				)
			)
		)
	)
	(zone
		(layer "B.Cu")
		(hatch none 0.5)
		(connect_pads
			(clearance 0)
		)
		(min_thickness 0.25)
		(keepout
			(tracks not_allowed)
			(vias allowed)
			(pads allowed)
			(copperpour not_allowed)
			(footprints allowed)
		)
		(placement
			(enabled no)
			(sheetname "")
		)
		(fill
			(thermal_gap 0.5)
			(thermal_bridge_width 0.5)
			(island_removal_mode 0)
		)
		(polygon
			(pts
				(arc
					(start 14.59992 -29.200094)
					(mid 16.599916 -31.20009)
					(end 18.599912 -29.200094)
				)
				(arc
					(start 18.599912 -29.200094)
					(mid 16.599916 -27.200098)
					(end 14.59992 -29.200094)
				)
			)
		)
	)
	(zone
		(layer "B.Cu")
		(hatch none 0.5)
		(connect_pads
			(clearance 0)
		)
		(min_thickness 0.25)
		(keepout
			(tracks allowed)
			(vias allowed)
			(pads allowed)
			(copperpour allowed)
			(footprints not_allowed)
		)
		(placement
			(enabled no)
			(sheetname "")
		)
		(fill
			(thermal_gap 0.5)
			(thermal_bridge_width 0.5)
			(island_removal_mode 0)
		)
		(polygon
			(pts
				(xy 39.180008 -91.885008) (xy 39.180008 -99.734878) (xy 97.16008 -99.734878) (xy 97.16008 -91.885008)
			)
		)
	)
	(zone
		(layer "B.Cu")
		(hatch none 0.5)
		(connect_pads
			(clearance 0)
		)
		(min_thickness 0.25)
		(keepout
			(tracks not_allowed)
			(vias allowed)
			(pads allowed)
			(copperpour not_allowed)
			(footprints allowed)
		)
		(placement
			(enabled no)
			(sheetname "")
		)
		(fill
			(thermal_gap 0.5)
			(thermal_bridge_width 0.5)
			(island_removal_mode 0)
		)
		(polygon
			(pts
				(arc
					(start 96.400112 -331.16012)
					(mid 91.400122 -326.16013)
					(end 86.399878 -331.16012)
				)
				(arc
					(start 86.399878 -331.16012)
					(mid 91.400122 -336.160364)
					(end 96.400112 -331.16012)
				)
			)
		)
	)
	(zone
		(layer "B.Cu")
		(hatch none 0.5)
		(connect_pads
			(clearance 0)
		)
		(min_thickness 0.25)
		(keepout
			(tracks allowed)
			(vias allowed)
			(pads allowed)
			(copperpour allowed)
			(footprints not_allowed)
		)
		(placement
			(enabled no)
			(sheetname "")
		)
		(fill
			(thermal_gap 0.5)
			(thermal_bridge_width 0.5)
			(island_removal_mode 0)
		)
		(polygon
			(pts
				(arc
					(start 11.599926 -118.100094)
					(mid 16.599916 -123.100084)
					(end 21.599906 -118.100094)
				)
				(arc
					(start 21.599906 -118.100094)
					(mid 16.599916 -113.100104)
					(end 11.599926 -118.100094)
				)
			)
		)
	)
	(zone
		(layer "B.Cu")
		(hatch none 0.5)
		(connect_pads
			(clearance 0)
		)
		(min_thickness 0.25)
		(keepout
			(tracks not_allowed)
			(vias allowed)
			(pads allowed)
			(copperpour not_allowed)
			(footprints allowed)
		)
		(placement
			(enabled no)
			(sheetname "")
		)
		(fill
			(thermal_gap 0.5)
			(thermal_bridge_width 0.5)
			(island_removal_mode 0)
		)
		(polygon
			(pts
				(arc
					(start 87.399876 -153.36012)
					(mid 91.400122 -157.360366)
					(end 95.400114 -153.36012)
				)
				(arc
					(start 95.400114 -153.36012)
					(mid 91.400122 -149.360128)
					(end 87.399876 -153.36012)
				)
			)
		)
	)
	(zone
		(layer "B.Cu")
		(hatch none 0.5)
		(connect_pads
			(clearance 0)
		)
		(min_thickness 0.25)
		(keepout
			(tracks not_allowed)
			(vias allowed)
			(pads allowed)
			(copperpour not_allowed)
			(footprints allowed)
		)
		(placement
			(enabled no)
			(sheetname "")
		)
		(fill
			(thermal_gap 0.5)
			(thermal_bridge_width 0.5)
			(island_removal_mode 0)
		)
		(polygon
			(pts
				(arc
					(start 87.399876 -331.16012)
					(mid 91.400122 -335.160366)
					(end 95.400114 -331.16012)
				)
				(arc
					(start 95.400114 -331.16012)
					(mid 91.400122 -327.160128)
					(end 87.399876 -331.16012)
				)
			)
		)
	)
	(zone
		(layer "B.Cu")
		(hatch none 0.5)
		(connect_pads
			(clearance 0)
		)
		(min_thickness 0.25)
		(keepout
			(tracks not_allowed)
			(vias allowed)
			(pads allowed)
			(copperpour not_allowed)
			(footprints allowed)
		)
		(placement
			(enabled no)
			(sheetname "")
		)
		(fill
			(thermal_gap 0.5)
			(thermal_bridge_width 0.5)
			(island_removal_mode 0)
		)
		(polygon
			(pts
				(arc
					(start 83.000088 -341.250016)
					(mid 78.000098 -336.250026)
					(end 73.000108 -341.250016)
				)
				(arc
					(start 73.000108 -341.250016)
					(mid 78.000098 -346.250006)
					(end 83.000088 -341.250016)
				)
			)
		)
	)
	(zone
		(layer "B.Cu")
		(hatch none 0.5)
		(connect_pads
			(clearance 0)
		)
		(min_thickness 0.25)
		(keepout
			(tracks not_allowed)
			(vias allowed)
			(pads allowed)
			(copperpour not_allowed)
			(footprints allowed)
		)
		(placement
			(enabled no)
			(sheetname "")
		)
		(fill
			(thermal_gap 0.5)
			(thermal_bridge_width 0.5)
			(island_removal_mode 0)
		)
		(polygon
			(pts
				(arc
					(start 100.576888 -16.810228)
					(mid 98.951288 -15.184628)
					(end 97.325688 -16.810228)
				)
				(arc
					(start 97.325688 -16.810228)
					(mid 98.951288 -18.435828)
					(end 100.576888 -16.810228)
				)
			)
		)
	)
	(zone
		(layer "B.Cu")
		(hatch none 0.5)
		(connect_pads
			(clearance 0)
		)
		(min_thickness 0.25)
		(keepout
			(tracks allowed)
			(vias allowed)
			(pads allowed)
			(copperpour allowed)
			(footprints not_allowed)
		)
		(placement
			(enabled no)
			(sheetname "")
		)
		(fill
			(thermal_gap 0.5)
			(thermal_bridge_width 0.5)
			(island_removal_mode 0)
		)
		(polygon
			(pts
				(xy 39.180008 -447.485008) (xy 39.180008 -455.334878) (xy 97.16008 -455.334878) (xy 97.16008 -447.485008)
			)
		)
	)
	(zone
		(layer "B.Cu")
		(hatch none 0.5)
		(connect_pads
			(clearance 0)
		)
		(min_thickness 0.25)
		(keepout
			(tracks not_allowed)
			(vias allowed)
			(pads allowed)
			(copperpour not_allowed)
			(footprints allowed)
		)
		(placement
			(enabled no)
			(sheetname "")
		)
		(fill
			(thermal_gap 0.5)
			(thermal_bridge_width 0.5)
			(island_removal_mode 0)
		)
		(polygon
			(pts
				(arc
					(start 83.000088 -32.29991)
					(mid 78.000098 -27.29992)
					(end 73.000108 -32.29991)
				)
				(arc
					(start 73.000108 -32.29991)
					(mid 78.000098 -37.2999)
					(end 83.000088 -32.29991)
				)
			)
		)
	)
	(zone
		(layer "B.Cu")
		(hatch none 0.5)
		(connect_pads
			(clearance 0)
		)
		(min_thickness 0.25)
		(keepout
			(tracks allowed)
			(vias allowed)
			(pads allowed)
			(copperpour allowed)
			(footprints not_allowed)
		)
		(placement
			(enabled no)
			(sheetname "")
		)
		(fill
			(thermal_gap 0.5)
			(thermal_bridge_width 0.5)
			(island_removal_mode 0)
		)
		(polygon
			(pts
				(arc
					(start 86.000082 -121.19991)
					(mid 78.000098 -113.199926)
					(end 70.000114 -121.19991)
				)
				(arc
					(start 70.000114 -121.19991)
					(mid 78.000098 -129.199894)
					(end 86.000082 -121.19991)
				)
			)
		)
	)
	(zone
		(layer "B.Cu")
		(hatch none 0.5)
		(connect_pads
			(clearance 0)
		)
		(min_thickness 0.25)
		(keepout
			(tracks allowed)
			(vias allowed)
			(pads allowed)
			(copperpour allowed)
			(footprints not_allowed)
		)
		(placement
			(enabled no)
			(sheetname "")
		)
		(fill
			(thermal_gap 0.5)
			(thermal_bridge_width 0.5)
			(island_removal_mode 0)
		)
		(polygon
			(pts
				(xy 39.180008 -269.685008) (xy 39.180008 -277.534878) (xy 97.16008 -277.534878) (xy 97.16008 -269.685008)
			)
		)
	)
	(zone
		(layer "B.Cu")
		(hatch none 0.5)
		(connect_pads
			(clearance 0)
		)
		(min_thickness 0.25)
		(keepout
			(tracks not_allowed)
			(vias allowed)
			(pads allowed)
			(copperpour not_allowed)
			(footprints allowed)
		)
		(placement
			(enabled no)
			(sheetname "")
		)
		(fill
			(thermal_gap 0.5)
			(thermal_bridge_width 0.5)
			(island_removal_mode 0)
		)
		(polygon
			(pts
				(arc
					(start 83.000088 -430.150016)
					(mid 78.000098 -425.150026)
					(end 73.000108 -430.150016)
				)
				(arc
					(start 73.000108 -430.150016)
					(mid 78.000098 -435.150006)
					(end 83.000088 -430.150016)
				)
			)
		)
	)
	(zone
		(layer "B.Cu")
		(hatch none 0.5)
		(connect_pads
			(clearance 0)
		)
		(min_thickness 0.25)
		(keepout
			(tracks allowed)
			(vias allowed)
			(pads allowed)
			(copperpour allowed)
			(footprints not_allowed)
		)
		(placement
			(enabled no)
			(sheetname "")
		)
		(fill
			(thermal_gap 0.5)
			(thermal_bridge_width 0.5)
			(island_removal_mode 0)
		)
		(polygon
			(pts
				(xy 39.180008 -47.435008) (xy 39.180008 -55.284878) (xy 97.16008 -55.284878) (xy 97.16008 -47.435008)
			)
		)
	)
	(zone
		(layer "B.Cu")
		(hatch none 0.5)
		(connect_pads
			(clearance 0)
		)
		(min_thickness 0.25)
		(keepout
			(tracks allowed)
			(vias allowed)
			(pads allowed)
			(copperpour allowed)
			(footprints not_allowed)
		)
		(placement
			(enabled no)
			(sheetname "")
		)
		(fill
			(thermal_gap 0.5)
			(thermal_bridge_width 0.5)
			(island_removal_mode 0)
		)
		(polygon
			(pts
				(arc
					(start 73.000108 -341.250016)
					(mid 78.000098 -346.250006)
					(end 83.000088 -341.250016)
				)
				(arc
					(start 83.000088 -341.250016)
					(mid 78.000098 -336.250026)
					(end 73.000108 -341.250016)
				)
			)
		)
	)
	(zone
		(layer "B.Cu")
		(hatch none 0.5)
		(connect_pads
			(clearance 0)
		)
		(min_thickness 0.25)
		(keepout
			(tracks not_allowed)
			(vias allowed)
			(pads allowed)
			(copperpour not_allowed)
			(footprints allowed)
		)
		(placement
			(enabled no)
			(sheetname "")
		)
		(fill
			(thermal_gap 0.5)
			(thermal_bridge_width 0.5)
			(island_removal_mode 0)
		)
		(polygon
			(pts
				(arc
					(start 96.400112 -508.96012)
					(mid 91.400122 -503.96013)
					(end 86.399878 -508.96012)
				)
				(arc
					(start 86.399878 -508.96012)
					(mid 91.400122 -513.960364)
					(end 96.400112 -508.96012)
				)
			)
		)
	)
	(zone
		(layer "B.Cu")
		(hatch none 0.5)
		(connect_pads
			(clearance 0)
		)
		(min_thickness 0.25)
		(keepout
			(tracks not_allowed)
			(vias allowed)
			(pads allowed)
			(copperpour not_allowed)
			(footprints allowed)
		)
		(placement
			(enabled no)
			(sheetname "")
		)
		(fill
			(thermal_gap 0.5)
			(thermal_bridge_width 0.5)
			(island_removal_mode 0)
		)
		(polygon
			(pts
				(arc
					(start 14.59992 -295.900094)
					(mid 16.599916 -297.90009)
					(end 18.599912 -295.900094)
				)
				(arc
					(start 18.599912 -295.900094)
					(mid 16.599916 -293.900098)
					(end 14.59992 -295.900094)
				)
			)
		)
	)
	(zone
		(layer "B.Cu")
		(hatch none 0.5)
		(connect_pads
			(clearance 0)
		)
		(min_thickness 0.25)
		(keepout
			(tracks allowed)
			(vias allowed)
			(pads allowed)
			(copperpour allowed)
			(footprints not_allowed)
		)
		(placement
			(enabled no)
			(sheetname "")
		)
		(fill
			(thermal_gap 0.5)
			(thermal_bridge_width 0.5)
			(island_removal_mode 0)
		)
		(polygon
			(pts
				(xy 39.180008 -180.785008) (xy 39.180008 -188.634878) (xy 97.16008 -188.634878) (xy 97.16008 -180.785008)
			)
		)
	)
	(zone
		(layer "B.Cu")
		(hatch none 0.5)
		(connect_pads
			(clearance 0)
		)
		(min_thickness 0.25)
		(keepout
			(tracks not_allowed)
			(vias allowed)
			(pads allowed)
			(copperpour not_allowed)
			(footprints allowed)
		)
		(placement
			(enabled no)
			(sheetname "")
		)
		(fill
			(thermal_gap 0.5)
			(thermal_bridge_width 0.5)
			(island_removal_mode 0)
		)
		(polygon
			(pts
				(arc
					(start 96.400112 -64.46012)
					(mid 91.400122 -59.46013)
					(end 86.399878 -64.46012)
				)
				(arc
					(start 86.399878 -64.46012)
					(mid 91.400122 -69.460364)
					(end 96.400112 -64.46012)
				)
			)
		)
	)
	(zone
		(layer "B.Cu")
		(hatch none 0.5)
		(connect_pads
			(clearance 0)
		)
		(min_thickness 0.25)
		(keepout
			(tracks allowed)
			(vias allowed)
			(pads allowed)
			(copperpour allowed)
			(footprints not_allowed)
		)
		(placement
			(enabled no)
			(sheetname "")
		)
		(fill
			(thermal_gap 0.5)
			(thermal_bridge_width 0.5)
			(island_removal_mode 0)
		)
		(polygon
			(pts
				(arc
					(start 24.5999 -295.900094)
					(mid 16.599916 -287.90011)
					(end 8.599932 -295.900094)
				)
				(arc
					(start 8.599932 -295.900094)
					(mid 16.599916 -303.900078)
					(end 24.5999 -295.900094)
				)
			)
		)
	)
	(zone
		(layer "B.Cu")
		(hatch none 0.5)
		(connect_pads
			(clearance 0)
		)
		(min_thickness 0.25)
		(keepout
			(tracks allowed)
			(vias allowed)
			(pads allowed)
			(copperpour allowed)
			(footprints not_allowed)
		)
		(placement
			(enabled no)
			(sheetname "")
		)
		(fill
			(thermal_gap 0.5)
			(thermal_bridge_width 0.5)
			(island_removal_mode 0)
		)
		(polygon
			(pts
				(arc
					(start 86.000082 -341.250016)
					(mid 78.000098 -333.250032)
					(end 70.000114 -341.250016)
				)
				(arc
					(start 70.000114 -341.250016)
					(mid 78.000098 -349.25)
					(end 86.000082 -341.250016)
				)
			)
		)
	)
	(zone
		(layer "B.Cu")
		(hatch none 0.5)
		(connect_pads
			(clearance 0)
		)
		(min_thickness 0.25)
		(keepout
			(tracks not_allowed)
			(vias allowed)
			(pads allowed)
			(copperpour not_allowed)
			(footprints allowed)
		)
		(placement
			(enabled no)
			(sheetname "")
		)
		(fill
			(thermal_gap 0.5)
			(thermal_bridge_width 0.5)
			(island_removal_mode 0)
		)
		(polygon
			(pts
				(arc
					(start 14.59992 -473.700094)
					(mid 16.599916 -475.70009)
					(end 18.599912 -473.700094)
				)
				(arc
					(start 18.599912 -473.700094)
					(mid 16.599916 -471.700098)
					(end 14.59992 -473.700094)
				)
			)
		)
	)
	(zone
		(layer "B.Cu")
		(hatch none 0.5)
		(connect_pads
			(clearance 0)
		)
		(min_thickness 0.25)
		(keepout
			(tracks not_allowed)
			(vias allowed)
			(pads allowed)
			(copperpour not_allowed)
			(footprints allowed)
		)
		(placement
			(enabled no)
			(sheetname "")
		)
		(fill
			(thermal_gap 0.5)
			(thermal_bridge_width 0.5)
			(island_removal_mode 0)
		)
		(polygon
			(pts
				(arc
					(start 75.3999 -78.300072)
					(mid 78.000098 -80.90027)
					(end 80.600042 -78.300072)
				)
				(arc
					(start 80.600042 -78.300072)
					(mid 78.000098 -75.700128)
					(end 75.3999 -78.300072)
				)
			)
		)
	)
	(zone
		(layer "B.Cu")
		(hatch none 0.5)
		(connect_pads
			(clearance 0)
		)
		(min_thickness 0.25)
		(keepout
			(tracks not_allowed)
			(vias allowed)
			(pads allowed)
			(copperpour not_allowed)
			(footprints allowed)
		)
		(placement
			(enabled no)
			(sheetname "")
		)
		(fill
			(thermal_gap 0.5)
			(thermal_bridge_width 0.5)
			(island_removal_mode 0)
		)
		(polygon
			(pts
				(arc
					(start 96.400112 -153.36012)
					(mid 91.400122 -148.36013)
					(end 86.399878 -153.36012)
				)
				(arc
					(start 86.399878 -153.36012)
					(mid 91.400122 -158.360364)
					(end 96.400112 -153.36012)
				)
			)
		)
	)
	(zone
		(layer "B.Cu")
		(hatch none 0.5)
		(connect_pads
			(clearance 0)
		)
		(min_thickness 0.25)
		(keepout
			(tracks not_allowed)
			(vias allowed)
			(pads allowed)
			(copperpour not_allowed)
			(footprints allowed)
		)
		(placement
			(enabled no)
			(sheetname "")
		)
		(fill
			(thermal_gap 0.5)
			(thermal_bridge_width 0.5)
			(island_removal_mode 0)
		)
		(polygon
			(pts
				(arc
					(start 76.000102 -430.150016)
					(mid 78.000098 -432.150012)
					(end 80.000094 -430.150016)
				)
				(arc
					(start 80.000094 -430.150016)
					(mid 78.000098 -428.15002)
					(end 76.000102 -430.150016)
				)
			)
		)
	)
	(zone
		(layer "B.Cu")
		(hatch none 0.5)
		(connect_pads
			(clearance 0)
		)
		(min_thickness 0.25)
		(keepout
			(tracks not_allowed)
			(vias allowed)
			(pads allowed)
			(copperpour not_allowed)
			(footprints allowed)
		)
		(placement
			(enabled no)
			(sheetname "")
		)
		(fill
			(thermal_gap 0.5)
			(thermal_bridge_width 0.5)
			(island_removal_mode 0)
		)
		(polygon
			(pts
				(arc
					(start 87.399876 -108.91012)
					(mid 91.400122 -112.910366)
					(end 95.400114 -108.91012)
				)
				(arc
					(start 95.400114 -108.91012)
					(mid 91.400122 -104.910128)
					(end 87.399876 -108.91012)
				)
			)
		)
	)
	(zone
		(layer "B.Cu")
		(hatch none 0.5)
		(connect_pads
			(clearance 0)
		)
		(min_thickness 0.25)
		(keepout
			(tracks not_allowed)
			(vias allowed)
			(pads allowed)
			(copperpour not_allowed)
			(footprints allowed)
		)
		(placement
			(enabled no)
			(sheetname "")
		)
		(fill
			(thermal_gap 0.5)
			(thermal_bridge_width 0.5)
			(island_removal_mode 0)
		)
		(polygon
			(pts
				(arc
					(start 87.399876 -20.01012)
					(mid 91.400122 -24.010366)
					(end 95.400114 -20.01012)
				)
				(arc
					(start 95.400114 -20.01012)
					(mid 91.400122 -16.010128)
					(end 87.399876 -20.01012)
				)
			)
		)
	)
	(zone
		(layer "B.Cu")
		(hatch none 0.5)
		(connect_pads
			(clearance 0)
		)
		(min_thickness 0.25)
		(keepout
			(tracks not_allowed)
			(vias allowed)
			(pads allowed)
			(copperpour not_allowed)
			(footprints allowed)
		)
		(placement
			(enabled no)
			(sheetname "")
		)
		(fill
			(thermal_gap 0.5)
			(thermal_bridge_width 0.5)
			(island_removal_mode 0)
		)
		(polygon
			(pts
				(arc
					(start 96.400112 -20.01012)
					(mid 91.400122 -15.01013)
					(end 86.399878 -20.01012)
				)
				(arc
					(start 86.399878 -20.01012)
					(mid 91.400122 -25.010364)
					(end 96.400112 -20.01012)
				)
			)
		)
	)
	(zone
		(layer "B.Cu")
		(hatch none 0.5)
		(connect_pads
			(clearance 0)
		)
		(min_thickness 0.25)
		(keepout
			(tracks not_allowed)
			(vias allowed)
			(pads allowed)
			(copperpour not_allowed)
			(footprints allowed)
		)
		(placement
			(enabled no)
			(sheetname "")
		)
		(fill
			(thermal_gap 0.5)
			(thermal_bridge_width 0.5)
			(island_removal_mode 0)
		)
		(polygon
			(pts
				(arc
					(start 87.399876 -464.51012)
					(mid 91.400122 -468.510366)
					(end 95.400114 -464.51012)
				)
				(arc
					(start 95.400114 -464.51012)
					(mid 91.400122 -460.510128)
					(end 87.399876 -464.51012)
				)
			)
		)
	)
	(zone
		(layer "B.Cu")
		(hatch none 0.5)
		(connect_pads
			(clearance 0)
		)
		(min_thickness 0.25)
		(keepout
			(tracks allowed)
			(vias allowed)
			(pads allowed)
			(copperpour allowed)
			(footprints not_allowed)
		)
		(placement
			(enabled no)
			(sheetname "")
		)
		(fill
			(thermal_gap 0.5)
			(thermal_bridge_width 0.5)
			(island_removal_mode 0)
		)
		(polygon
			(pts
				(xy 39.180008 -136.335008) (xy 39.180008 -144.184878) (xy 97.16008 -144.184878) (xy 97.16008 -136.335008)
			)
		)
	)
	(zone
		(layer "B.Cu")
		(hatch none 0.5)
		(connect_pads
			(clearance 0)
		)
		(min_thickness 0.25)
		(keepout
			(tracks not_allowed)
			(vias allowed)
			(pads allowed)
			(copperpour not_allowed)
			(footprints allowed)
		)
		(placement
			(enabled no)
			(sheetname "")
		)
		(fill
			(thermal_gap 0.5)
			(thermal_bridge_width 0.5)
			(island_removal_mode 0)
		)
		(polygon
			(pts
				(arc
					(start 87.399876 -197.81012)
					(mid 91.400122 -201.810366)
					(end 95.400114 -197.81012)
				)
				(arc
					(start 95.400114 -197.81012)
					(mid 91.400122 -193.810128)
					(end 87.399876 -197.81012)
				)
			)
		)
	)
	(zone
		(layer "B.Cu")
		(hatch none 0.5)
		(connect_pads
			(clearance 0)
		)
		(min_thickness 0.25)
		(keepout
			(tracks allowed)
			(vias allowed)
			(pads allowed)
			(copperpour allowed)
			(footprints not_allowed)
		)
		(placement
			(enabled no)
			(sheetname "")
		)
		(fill
			(thermal_gap 0.5)
			(thermal_bridge_width 0.5)
			(island_removal_mode 0)
		)
		(polygon
			(pts
				(xy 39.180008 -225.235008) (xy 39.180008 -233.084878) (xy 97.16008 -233.084878) (xy 97.16008 -225.235008)
			)
		)
	)
	(zone
		(layer "B.Cu")
		(hatch none 0.5)
		(connect_pads
			(clearance 0)
		)
		(min_thickness 0.25)
		(keepout
			(tracks not_allowed)
			(vias allowed)
			(pads allowed)
			(copperpour not_allowed)
			(footprints allowed)
		)
		(placement
			(enabled no)
			(sheetname "")
		)
		(fill
			(thermal_gap 0.5)
			(thermal_bridge_width 0.5)
			(island_removal_mode 0)
		)
		(polygon
			(pts
				(arc
					(start 14.59992 -384.800094)
					(mid 16.599916 -386.80009)
					(end 18.599912 -384.800094)
				)
				(arc
					(start 18.599912 -384.800094)
					(mid 16.599916 -382.800098)
					(end 14.59992 -384.800094)
				)
			)
		)
	)
	(zone
		(layer "B.Cu")
		(hatch none 0.5)
		(connect_pads
			(clearance 0)
		)
		(min_thickness 0.25)
		(keepout
			(tracks allowed)
			(vias allowed)
			(pads allowed)
			(copperpour allowed)
			(footprints not_allowed)
		)
		(placement
			(enabled no)
			(sheetname "")
		)
		(fill
			(thermal_gap 0.5)
			(thermal_bridge_width 0.5)
			(island_removal_mode 0)
		)
		(polygon
			(pts
				(arc
					(start 24.5999 -207.000094)
					(mid 16.599916 -199.00011)
					(end 8.599932 -207.000094)
				)
				(arc
					(start 8.599932 -207.000094)
					(mid 16.599916 -215.000078)
					(end 24.5999 -207.000094)
				)
			)
		)
	)
	(zone
		(layer "B.Cu")
		(hatch none 0.5)
		(connect_pads
			(clearance 0)
		)
		(min_thickness 0.25)
		(keepout
			(tracks allowed)
			(vias allowed)
			(pads allowed)
			(copperpour allowed)
			(footprints not_allowed)
		)
		(placement
			(enabled no)
			(sheetname "")
		)
		(fill
			(thermal_gap 0.5)
			(thermal_bridge_width 0.5)
			(island_removal_mode 0)
		)
		(polygon
			(pts
				(arc
					(start 73.000108 -519.050016)
					(mid 78.000098 -524.050006)
					(end 83.000088 -519.050016)
				)
				(arc
					(start 83.000088 -519.050016)
					(mid 78.000098 -514.050026)
					(end 73.000108 -519.050016)
				)
			)
		)
	)
	(zone
		(layer "B.Cu")
		(hatch none 0.5)
		(connect_pads
			(clearance 0)
		)
		(min_thickness 0.25)
		(keepout
			(tracks allowed)
			(vias allowed)
			(pads allowed)
			(copperpour allowed)
			(footprints not_allowed)
		)
		(placement
			(enabled no)
			(sheetname "")
		)
		(fill
			(thermal_gap 0.5)
			(thermal_bridge_width 0.5)
			(island_removal_mode 0)
		)
		(polygon
			(pts
				(arc
					(start 24.5999 -29.200094)
					(mid 16.599916 -21.20011)
					(end 8.599932 -29.200094)
				)
				(arc
					(start 8.599932 -29.200094)
					(mid 16.599916 -37.200078)
					(end 24.5999 -29.200094)
				)
			)
		)
	)
	(zone
		(layer "B.Cu")
		(hatch none 0.5)
		(connect_pads
			(clearance 0)
		)
		(min_thickness 0.25)
		(keepout
			(tracks not_allowed)
			(vias allowed)
			(pads allowed)
			(copperpour not_allowed)
			(footprints allowed)
		)
		(placement
			(enabled no)
			(sheetname "")
		)
		(fill
			(thermal_gap 0.5)
			(thermal_bridge_width 0.5)
			(island_removal_mode 0)
		)
		(polygon
			(pts
				(arc
					(start 83.000088 -121.19991)
					(mid 78.000098 -116.19992)
					(end 73.000108 -121.19991)
				)
				(arc
					(start 73.000108 -121.19991)
					(mid 78.000098 -126.1999)
					(end 83.000088 -121.19991)
				)
			)
		)
	)
	(zone
		(layer "B.Cu")
		(hatch none 0.5)
		(connect_pads
			(clearance 0)
		)
		(min_thickness 0.25)
		(keepout
			(tracks not_allowed)
			(vias allowed)
			(pads allowed)
			(copperpour not_allowed)
			(footprints allowed)
		)
		(placement
			(enabled no)
			(sheetname "")
		)
		(fill
			(thermal_gap 0.5)
			(thermal_bridge_width 0.5)
			(island_removal_mode 0)
		)
		(polygon
			(pts
				(arc
					(start 76.000102 -210.09991)
					(mid 78.000098 -212.099906)
					(end 80.000094 -210.09991)
				)
				(arc
					(start 80.000094 -210.09991)
					(mid 78.000098 -208.099914)
					(end 76.000102 -210.09991)
				)
			)
		)
	)
	(zone
		(layer "B.Cu")
		(hatch none 0.5)
		(connect_pads
			(clearance 0)
		)
		(min_thickness 0.25)
		(keepout
			(tracks allowed)
			(vias allowed)
			(pads allowed)
			(copperpour allowed)
			(footprints not_allowed)
		)
		(placement
			(enabled no)
			(sheetname "")
		)
		(fill
			(thermal_gap 0.5)
			(thermal_bridge_width 0.5)
			(island_removal_mode 0)
		)
		(polygon
			(pts
				(xy 39.180008 -491.935008) (xy 39.180008 -499.784878) (xy 97.16008 -499.784878) (xy 97.16008 -491.935008)
			)
		)
	)
	(zone
		(layer "B.Cu")
		(hatch none 0.5)
		(connect_pads
			(clearance 0)
		)
		(min_thickness 0.25)
		(keepout
			(tracks not_allowed)
			(vias allowed)
			(pads allowed)
			(copperpour not_allowed)
			(footprints allowed)
		)
		(placement
			(enabled no)
			(sheetname "")
		)
		(fill
			(thermal_gap 0.5)
			(thermal_bridge_width 0.5)
			(island_removal_mode 0)
		)
		(polygon
			(pts
				(arc
					(start 96.400112 -420.06012)
					(mid 91.400122 -415.06013)
					(end 86.399878 -420.06012)
				)
				(arc
					(start 86.399878 -420.06012)
					(mid 91.400122 -425.060364)
					(end 96.400112 -420.06012)
				)
			)
		)
	)
	(zone
		(layer "B.Cu")
		(hatch none 0.5)
		(connect_pads
			(clearance 0)
		)
		(min_thickness 0.25)
		(keepout
			(tracks allowed)
			(vias allowed)
			(pads allowed)
			(copperpour allowed)
			(footprints not_allowed)
		)
		(placement
			(enabled no)
			(sheetname "")
		)
		(fill
			(thermal_gap 0.5)
			(thermal_bridge_width 0.5)
			(island_removal_mode 0)
		)
		(polygon
			(pts
				(arc
					(start 24.5999 -118.100094)
					(mid 16.599916 -110.10011)
					(end 8.599932 -118.100094)
				)
				(arc
					(start 8.599932 -118.100094)
					(mid 16.599916 -126.100078)
					(end 24.5999 -118.100094)
				)
			)
		)
	)
	(zone
		(layer "B.Cu")
		(hatch none 0.5)
		(connect_pads
			(clearance 0)
		)
		(min_thickness 0.25)
		(keepout
			(tracks allowed)
			(vias allowed)
			(pads allowed)
			(copperpour allowed)
			(footprints not_allowed)
		)
		(placement
			(enabled no)
			(sheetname "")
		)
		(fill
			(thermal_gap 0.5)
			(thermal_bridge_width 0.5)
			(island_removal_mode 0)
		)
		(polygon
			(pts
				(arc
					(start 24.5999 -473.700094)
					(mid 16.599916 -465.70011)
					(end 8.599932 -473.700094)
				)
				(arc
					(start 8.599932 -473.700094)
					(mid 16.599916 -481.700078)
					(end 24.5999 -473.700094)
				)
			)
		)
	)
	(zone
		(layer "B.Cu")
		(hatch none 0.5)
		(connect_pads
			(clearance 0)
		)
		(min_thickness 0.25)
		(keepout
			(tracks not_allowed)
			(vias allowed)
			(pads allowed)
			(copperpour not_allowed)
			(footprints allowed)
		)
		(placement
			(enabled no)
			(sheetname "")
		)
		(fill
			(thermal_gap 0.5)
			(thermal_bridge_width 0.5)
			(island_removal_mode 0)
		)
		(polygon
			(pts
				(arc
					(start 87.399876 -420.06012)
					(mid 91.400122 -424.060366)
					(end 95.400114 -420.06012)
				)
				(arc
					(start 95.400114 -420.06012)
					(mid 91.400122 -416.060128)
					(end 87.399876 -420.06012)
				)
			)
		)
	)
	(zone
		(layer "B.Cu")
		(hatch none 0.5)
		(connect_pads
			(clearance 0)
		)
		(min_thickness 0.25)
		(keepout
			(tracks allowed)
			(vias allowed)
			(pads allowed)
			(copperpour allowed)
			(footprints not_allowed)
		)
		(placement
			(enabled no)
			(sheetname "")
		)
		(fill
			(thermal_gap 0.5)
			(thermal_bridge_width 0.5)
			(island_removal_mode 0)
		)
		(polygon
			(pts
				(arc
					(start 11.599926 -473.700094)
					(mid 16.599916 -478.700084)
					(end 21.599906 -473.700094)
				)
				(arc
					(start 21.599906 -473.700094)
					(mid 16.599916 -468.700104)
					(end 11.599926 -473.700094)
				)
			)
		)
	)
	(zone
		(layer "B.Cu")
		(hatch none 0.5)
		(connect_pads
			(clearance 0)
		)
		(min_thickness 0.25)
		(keepout
			(tracks not_allowed)
			(vias allowed)
			(pads allowed)
			(copperpour not_allowed)
			(footprints allowed)
		)
		(placement
			(enabled no)
			(sheetname "")
		)
		(fill
			(thermal_gap 0.5)
			(thermal_bridge_width 0.5)
			(island_removal_mode 0)
		)
		(polygon
			(pts
				(arc
					(start 83.000088 -519.050016)
					(mid 78.000098 -514.050026)
					(end 73.000108 -519.050016)
				)
				(arc
					(start 73.000108 -519.050016)
					(mid 78.000098 -524.050006)
					(end 83.000088 -519.050016)
				)
			)
		)
	)
	(zone
		(layer "B.Cu")
		(hatch none 0.5)
		(connect_pads
			(clearance 0)
		)
		(min_thickness 0.25)
		(keepout
			(tracks not_allowed)
			(vias allowed)
			(pads allowed)
			(copperpour not_allowed)
			(footprints allowed)
		)
		(placement
			(enabled no)
			(sheetname "")
		)
		(fill
			(thermal_gap 0.5)
			(thermal_bridge_width 0.5)
			(island_removal_mode 0)
		)
		(polygon
			(pts
				(arc
					(start 76.000102 -341.250016)
					(mid 78.000098 -343.250012)
					(end 80.000094 -341.250016)
				)
				(arc
					(start 80.000094 -341.250016)
					(mid 78.000098 -339.25002)
					(end 76.000102 -341.250016)
				)
			)
		)
	)
	(zone
		(layer "B.Cu")
		(hatch none 0.5)
		(connect_pads
			(clearance 0)
		)
		(min_thickness 0.25)
		(keepout
			(tracks not_allowed)
			(vias allowed)
			(pads allowed)
			(copperpour not_allowed)
			(footprints allowed)
		)
		(placement
			(enabled no)
			(sheetname "")
		)
		(fill
			(thermal_gap 0.5)
			(thermal_bridge_width 0.5)
			(island_removal_mode 0)
		)
		(polygon
			(pts
				(arc
					(start 76.000102 -121.19991)
					(mid 78.000098 -123.199906)
					(end 80.000094 -121.19991)
				)
				(arc
					(start 80.000094 -121.19991)
					(mid 78.000098 -119.199914)
					(end 76.000102 -121.19991)
				)
			)
		)
	)
	(zone
		(layer "B.Cu")
		(hatch none 0.5)
		(connect_pads
			(clearance 0)
		)
		(min_thickness 0.25)
		(keepout
			(tracks not_allowed)
			(vias allowed)
			(pads allowed)
			(copperpour not_allowed)
			(footprints allowed)
		)
		(placement
			(enabled no)
			(sheetname "")
		)
		(fill
			(thermal_gap 0.5)
			(thermal_bridge_width 0.5)
			(island_removal_mode 0)
		)
		(polygon
			(pts
				(arc
					(start 87.399876 -375.61012)
					(mid 91.400122 -379.610366)
					(end 95.400114 -375.61012)
				)
				(arc
					(start 95.400114 -375.61012)
					(mid 91.400122 -371.610128)
					(end 87.399876 -375.61012)
				)
			)
		)
	)
	(zone
		(layer "B.Cu")
		(hatch none 0.5)
		(connect_pads
			(clearance 0)
		)
		(min_thickness 0.25)
		(keepout
			(tracks not_allowed)
			(vias allowed)
			(pads allowed)
			(copperpour not_allowed)
			(footprints allowed)
		)
		(placement
			(enabled no)
			(sheetname "")
		)
		(fill
			(thermal_gap 0.5)
			(thermal_bridge_width 0.5)
			(island_removal_mode 0)
		)
		(polygon
			(pts
				(arc
					(start 87.399876 -508.96012)
					(mid 91.400122 -512.960366)
					(end 95.400114 -508.96012)
				)
				(arc
					(start 95.400114 -508.96012)
					(mid 91.400122 -504.960128)
					(end 87.399876 -508.96012)
				)
			)
		)
	)
	(zone
		(layer "B.Cu")
		(hatch none 0.5)
		(connect_pads
			(clearance 0)
		)
		(min_thickness 0.25)
		(keepout
			(tracks allowed)
			(vias allowed)
			(pads allowed)
			(copperpour allowed)
			(footprints not_allowed)
		)
		(placement
			(enabled no)
			(sheetname "")
		)
		(fill
			(thermal_gap 0.5)
			(thermal_bridge_width 0.5)
			(island_removal_mode 0)
		)
		(polygon
			(pts
				(arc
					(start 11.599926 -384.800094)
					(mid 16.599916 -389.800084)
					(end 21.599906 -384.800094)
				)
				(arc
					(start 21.599906 -384.800094)
					(mid 16.599916 -379.800104)
					(end 11.599926 -384.800094)
				)
			)
		)
	)
	(zone
		(layer "B.Cu")
		(hatch none 0.5)
		(connect_pads
			(clearance 0)
		)
		(min_thickness 0.25)
		(keepout
			(tracks not_allowed)
			(vias allowed)
			(pads allowed)
			(copperpour not_allowed)
			(footprints allowed)
		)
		(placement
			(enabled no)
			(sheetname "")
		)
		(fill
			(thermal_gap 0.5)
			(thermal_bridge_width 0.5)
			(island_removal_mode 0)
		)
		(polygon
			(pts
				(arc
					(start 87.399876 -286.71012)
					(mid 91.400122 -290.710366)
					(end 95.400114 -286.71012)
				)
				(arc
					(start 95.400114 -286.71012)
					(mid 91.400122 -282.710128)
					(end 87.399876 -286.71012)
				)
			)
		)
	)
	(zone
		(layer "B.Cu")
		(hatch none 0.5)
		(connect_pads
			(clearance 0)
		)
		(min_thickness 0.25)
		(keepout
			(tracks not_allowed)
			(vias allowed)
			(pads allowed)
			(copperpour not_allowed)
			(footprints allowed)
		)
		(placement
			(enabled no)
			(sheetname "")
		)
		(fill
			(thermal_gap 0.5)
			(thermal_bridge_width 0.5)
			(island_removal_mode 0)
		)
		(polygon
			(pts
				(arc
					(start 14.59992 -118.100094)
					(mid 16.599916 -120.10009)
					(end 18.599912 -118.100094)
				)
				(arc
					(start 18.599912 -118.100094)
					(mid 16.599916 -116.100098)
					(end 14.59992 -118.100094)
				)
			)
		)
	)
	(zone
		(layer "B.Cu")
		(hatch none 0.5)
		(connect_pads
			(clearance 0)
		)
		(min_thickness 0.25)
		(keepout
			(tracks not_allowed)
			(vias allowed)
			(pads allowed)
			(copperpour not_allowed)
			(footprints allowed)
		)
		(placement
			(enabled no)
			(sheetname "")
		)
		(fill
			(thermal_gap 0.5)
			(thermal_bridge_width 0.5)
			(island_removal_mode 0)
		)
		(polygon
			(pts
				(arc
					(start 87.399876 -242.26012)
					(mid 91.400122 -246.260366)
					(end 95.400114 -242.26012)
				)
				(arc
					(start 95.400114 -242.26012)
					(mid 91.400122 -238.260128)
					(end 87.399876 -242.26012)
				)
			)
		)
	)
	(zone
		(layer "B.Cu")
		(hatch none 0.5)
		(connect_pads
			(clearance 0)
		)
		(min_thickness 0.25)
		(keepout
			(tracks allowed)
			(vias allowed)
			(pads allowed)
			(copperpour allowed)
			(footprints not_allowed)
		)
		(placement
			(enabled no)
			(sheetname "")
		)
		(fill
			(thermal_gap 0.5)
			(thermal_bridge_width 0.5)
			(island_removal_mode 0)
		)
		(polygon
			(pts
				(arc
					(start 24.5999 -384.800094)
					(mid 16.599916 -376.80011)
					(end 8.599932 -384.800094)
				)
				(arc
					(start 8.599932 -384.800094)
					(mid 16.599916 -392.800078)
					(end 24.5999 -384.800094)
				)
			)
		)
	)
	(zone
		(layer "B.Cu")
		(hatch none 0.5)
		(connect_pads
			(clearance 0)
		)
		(min_thickness 0.25)
		(keepout
			(tracks allowed)
			(vias allowed)
			(pads allowed)
			(copperpour allowed)
			(footprints not_allowed)
		)
		(placement
			(enabled no)
			(sheetname "")
		)
		(fill
			(thermal_gap 0.5)
			(thermal_bridge_width 0.5)
			(island_removal_mode 0)
		)
		(polygon
			(pts
				(arc
					(start 73.000108 -430.150016)
					(mid 78.000098 -435.150006)
					(end 83.000088 -430.150016)
				)
				(arc
					(start 83.000088 -430.150016)
					(mid 78.000098 -425.150026)
					(end 73.000108 -430.150016)
				)
			)
		)
	)
	(zone
		(layer "B.Cu")
		(hatch none 0.5)
		(connect_pads
			(clearance 0)
		)
		(min_thickness 0.25)
		(keepout
			(tracks allowed)
			(vias allowed)
			(pads allowed)
			(copperpour allowed)
			(footprints not_allowed)
		)
		(placement
			(enabled no)
			(sheetname "")
		)
		(fill
			(thermal_gap 0.5)
			(thermal_bridge_width 0.5)
			(island_removal_mode 0)
		)
		(polygon
			(pts
				(arc
					(start 73.000108 -32.29991)
					(mid 78.000098 -37.2999)
					(end 83.000088 -32.29991)
				)
				(arc
					(start 83.000088 -32.29991)
					(mid 78.000098 -27.29992)
					(end 73.000108 -32.29991)
				)
			)
		)
	)
	(zone
		(layers "In2.Cu" "In3.Cu" "In4.Cu" "In5.Cu")
		(hatch none 0.5)
		(connect_pads
			(clearance 0)
		)
		(min_thickness 0.25)
		(keepout
			(tracks not_allowed)
			(vias allowed)
			(pads allowed)
			(copperpour not_allowed)
			(footprints allowed)
		)
		(placement
			(enabled no)
			(sheetname "")
		)
		(fill yes
			(thermal_gap 0.5)
			(thermal_bridge_width 0.5)
			(island_removal_mode 0)
		)
		(polygon
			(pts
				(arc
					(start 78.000098 -524.180562)
					(mid 72.869298 -519.049762)
					(end 78.000098 -513.918962)
				)
				(arc
					(start 78.000098 -513.918962)
					(mid 78.050898 -513.969762)
					(end 78.000098 -514.020562)
				)
				(arc
					(start 78.000098 -514.020562)
					(mid 72.970898 -519.049762)
					(end 78.000098 -524.078962)
				)
				(arc
					(start 78.000098 -524.078962)
					(mid 78.050898 -524.129762)
					(end 78.000098 -524.180562)
				)
			)
		)
	)
	(zone
		(layers "In2.Cu" "In3.Cu" "In4.Cu" "In5.Cu")
		(hatch none 0.5)
		(connect_pads
			(clearance 0)
		)
		(min_thickness 0.25)
		(keepout
			(tracks not_allowed)
			(vias allowed)
			(pads allowed)
			(copperpour not_allowed)
			(footprints allowed)
		)
		(placement
			(enabled no)
			(sheetname "")
		)
		(fill yes
			(thermal_gap 0.5)
			(thermal_bridge_width 0.5)
			(island_removal_mode 0)
		)
		(polygon
			(pts
				(arc
					(start 16.60017 -201.97445)
					(mid 11.57478 -206.99984)
					(end 16.60017 -212.02523)
				)
				(arc
					(start 16.60017 -212.25383)
					(mid 12.885038 -210.714972)
					(end 11.34618 -206.99984)
				)
				(arc
					(start 11.34618 -206.99984)
					(mid 12.885038 -203.284708)
					(end 16.60017 -201.74585)
				)
			)
		)
	)
	(zone
		(layers "In2.Cu" "In3.Cu" "In4.Cu" "In5.Cu")
		(hatch none 0.5)
		(connect_pads
			(clearance 0)
		)
		(min_thickness 0.25)
		(keepout
			(tracks not_allowed)
			(vias allowed)
			(pads allowed)
			(copperpour not_allowed)
			(footprints allowed)
		)
		(placement
			(enabled no)
			(sheetname "")
		)
		(fill yes
			(thermal_gap 0.5)
			(thermal_bridge_width 0.5)
			(island_removal_mode 0)
		)
		(polygon
			(pts
				(arc
					(start 16.60017 -379.77445)
					(mid 21.62556 -384.79984)
					(end 16.60017 -389.82523)
				)
				(arc
					(start 16.60017 -390.05383)
					(mid 20.315302 -388.514972)
					(end 21.85416 -384.79984)
				)
				(arc
					(start 21.85416 -384.79984)
					(mid 20.315302 -381.084708)
					(end 16.60017 -379.54585)
				)
			)
		)
	)
	(zone
		(layers "In2.Cu" "In3.Cu" "In4.Cu" "In5.Cu")
		(hatch none 0.5)
		(connect_pads
			(clearance 0)
		)
		(min_thickness 0.25)
		(keepout
			(tracks not_allowed)
			(vias allowed)
			(pads allowed)
			(copperpour not_allowed)
			(footprints allowed)
		)
		(placement
			(enabled no)
			(sheetname "")
		)
		(fill yes
			(thermal_gap 0.5)
			(thermal_bridge_width 0.5)
			(island_removal_mode 0)
		)
		(polygon
			(pts
				(arc
					(start 78.000098 -524.180562)
					(mid 83.130898 -519.049762)
					(end 78.000098 -513.918962)
				)
				(arc
					(start 78.000098 -513.918962)
					(mid 77.949298 -513.969762)
					(end 78.000098 -514.020562)
				)
				(arc
					(start 78.000098 -514.020562)
					(mid 83.029298 -519.049762)
					(end 78.000098 -524.078962)
				)
				(arc
					(start 78.000098 -524.078962)
					(mid 77.949298 -524.129762)
					(end 78.000098 -524.180562)
				)
			)
		)
	)
	(zone
		(layers "In2.Cu" "In3.Cu" "In4.Cu" "In5.Cu")
		(hatch none 0.5)
		(connect_pads
			(clearance 0)
		)
		(min_thickness 0.25)
		(keepout
			(tracks not_allowed)
			(vias allowed)
			(pads allowed)
			(copperpour not_allowed)
			(footprints allowed)
		)
		(placement
			(enabled no)
			(sheetname "")
		)
		(fill yes
			(thermal_gap 0.5)
			(thermal_bridge_width 0.5)
			(island_removal_mode 0)
		)
		(polygon
			(pts
				(arc
					(start 78.000098 -346.380562)
					(mid 72.869298 -341.249762)
					(end 78.000098 -336.118962)
				)
				(arc
					(start 78.000098 -336.118962)
					(mid 78.050898 -336.169762)
					(end 78.000098 -336.220562)
				)
				(arc
					(start 78.000098 -336.220562)
					(mid 72.970898 -341.249762)
					(end 78.000098 -346.278962)
				)
				(arc
					(start 78.000098 -346.278962)
					(mid 78.050898 -346.329762)
					(end 78.000098 -346.380562)
				)
			)
		)
	)
	(zone
		(layers "In2.Cu" "In3.Cu" "In4.Cu" "In5.Cu")
		(hatch none 0.5)
		(connect_pads
			(clearance 0)
		)
		(min_thickness 0.25)
		(keepout
			(tracks not_allowed)
			(vias allowed)
			(pads allowed)
			(copperpour not_allowed)
			(footprints allowed)
		)
		(placement
			(enabled no)
			(sheetname "")
		)
		(fill yes
			(thermal_gap 0.5)
			(thermal_bridge_width 0.5)
			(island_removal_mode 0)
		)
		(polygon
			(pts
				(arc
					(start 16.60017 -201.97445)
					(mid 21.62556 -206.99984)
					(end 16.60017 -212.02523)
				)
				(arc
					(start 16.60017 -212.25383)
					(mid 20.315302 -210.714972)
					(end 21.85416 -206.99984)
				)
				(arc
					(start 21.85416 -206.99984)
					(mid 20.315302 -203.284708)
					(end 16.60017 -201.74585)
				)
			)
		)
	)
	(zone
		(layers "In2.Cu" "In3.Cu" "In4.Cu" "In5.Cu")
		(hatch none 0.5)
		(connect_pads
			(clearance 0)
		)
		(min_thickness 0.25)
		(keepout
			(tracks not_allowed)
			(vias allowed)
			(pads allowed)
			(copperpour not_allowed)
			(footprints allowed)
		)
		(placement
			(enabled no)
			(sheetname "")
		)
		(fill yes
			(thermal_gap 0.5)
			(thermal_bridge_width 0.5)
			(island_removal_mode 0)
		)
		(polygon
			(pts
				(arc
					(start 16.60017 -290.87445)
					(mid 11.57478 -295.89984)
					(end 16.60017 -300.92523)
				)
				(arc
					(start 16.60017 -301.15383)
					(mid 12.885038 -299.614972)
					(end 11.34618 -295.89984)
				)
				(arc
					(start 11.34618 -295.89984)
					(mid 12.885038 -292.184708)
					(end 16.60017 -290.64585)
				)
			)
		)
	)
	(zone
		(layers "In2.Cu" "In3.Cu" "In4.Cu" "In5.Cu")
		(hatch none 0.5)
		(connect_pads
			(clearance 0)
		)
		(min_thickness 0.25)
		(keepout
			(tracks not_allowed)
			(vias allowed)
			(pads allowed)
			(copperpour not_allowed)
			(footprints allowed)
		)
		(placement
			(enabled no)
			(sheetname "")
		)
		(fill yes
			(thermal_gap 0.5)
			(thermal_bridge_width 0.5)
			(island_removal_mode 0)
		)
		(polygon
			(pts
				(arc
					(start 78.000098 -126.330456)
					(mid 72.869298 -121.199656)
					(end 78.000098 -116.068856)
				)
				(arc
					(start 78.000098 -116.068856)
					(mid 78.050898 -116.119656)
					(end 78.000098 -116.170456)
				)
				(arc
					(start 78.000098 -116.170456)
					(mid 72.970898 -121.199656)
					(end 78.000098 -126.228856)
				)
				(arc
					(start 78.000098 -126.228856)
					(mid 78.050898 -126.279656)
					(end 78.000098 -126.330456)
				)
			)
		)
	)
	(zone
		(layers "In2.Cu" "In3.Cu" "In4.Cu" "In5.Cu")
		(hatch none 0.5)
		(connect_pads
			(clearance 0)
		)
		(min_thickness 0.25)
		(keepout
			(tracks not_allowed)
			(vias allowed)
			(pads allowed)
			(copperpour not_allowed)
			(footprints allowed)
		)
		(placement
			(enabled no)
			(sheetname "")
		)
		(fill yes
			(thermal_gap 0.5)
			(thermal_bridge_width 0.5)
			(island_removal_mode 0)
		)
		(polygon
			(pts
				(arc
					(start 78.000098 -37.430456)
					(mid 83.130898 -32.299656)
					(end 78.000098 -27.168856)
				)
				(arc
					(start 78.000098 -27.168856)
					(mid 77.949298 -27.219656)
					(end 78.000098 -27.270456)
				)
				(arc
					(start 78.000098 -27.270456)
					(mid 83.029298 -32.299656)
					(end 78.000098 -37.328856)
				)
				(arc
					(start 78.000098 -37.328856)
					(mid 77.949298 -37.379656)
					(end 78.000098 -37.430456)
				)
			)
		)
	)
	(zone
		(layers "In2.Cu" "In3.Cu" "In4.Cu" "In5.Cu")
		(hatch none 0.5)
		(connect_pads
			(clearance 0)
		)
		(min_thickness 0.25)
		(keepout
			(tracks not_allowed)
			(vias allowed)
			(pads allowed)
			(copperpour not_allowed)
			(footprints allowed)
		)
		(placement
			(enabled no)
			(sheetname "")
		)
		(fill yes
			(thermal_gap 0.5)
			(thermal_bridge_width 0.5)
			(island_removal_mode 0)
		)
		(polygon
			(pts
				(arc
					(start 16.60017 -379.77445)
					(mid 11.57478 -384.79984)
					(end 16.60017 -389.82523)
				)
				(arc
					(start 16.60017 -390.05383)
					(mid 12.885038 -388.514972)
					(end 11.34618 -384.79984)
				)
				(arc
					(start 11.34618 -384.79984)
					(mid 12.885038 -381.084708)
					(end 16.60017 -379.54585)
				)
			)
		)
	)
	(zone
		(layers "In2.Cu" "In3.Cu" "In4.Cu" "In5.Cu")
		(hatch none 0.5)
		(connect_pads
			(clearance 0)
		)
		(min_thickness 0.25)
		(keepout
			(tracks not_allowed)
			(vias allowed)
			(pads allowed)
			(copperpour not_allowed)
			(footprints allowed)
		)
		(placement
			(enabled no)
			(sheetname "")
		)
		(fill yes
			(thermal_gap 0.5)
			(thermal_bridge_width 0.5)
			(island_removal_mode 0)
		)
		(polygon
			(pts
				(arc
					(start 78.000098 -435.280562)
					(mid 83.130898 -430.149762)
					(end 78.000098 -425.018962)
				)
				(arc
					(start 78.000098 -425.018962)
					(mid 77.949298 -425.069762)
					(end 78.000098 -425.120562)
				)
				(arc
					(start 78.000098 -425.120562)
					(mid 83.029298 -430.149762)
					(end 78.000098 -435.178962)
				)
				(arc
					(start 78.000098 -435.178962)
					(mid 77.949298 -435.229762)
					(end 78.000098 -435.280562)
				)
			)
		)
	)
	(zone
		(layers "In2.Cu" "In3.Cu" "In4.Cu" "In5.Cu")
		(hatch none 0.5)
		(connect_pads
			(clearance 0)
		)
		(min_thickness 0.25)
		(keepout
			(tracks not_allowed)
			(vias allowed)
			(pads allowed)
			(copperpour not_allowed)
			(footprints allowed)
		)
		(placement
			(enabled no)
			(sheetname "")
		)
		(fill yes
			(thermal_gap 0.5)
			(thermal_bridge_width 0.5)
			(island_removal_mode 0)
		)
		(polygon
			(pts
				(arc
					(start 16.599916 -24.17445)
					(mid 21.625306 -29.19984)
					(end 16.599916 -34.22523)
				)
				(arc
					(start 16.599916 -34.45383)
					(mid 20.315048 -32.914972)
					(end 21.853906 -29.19984)
				)
				(arc
					(start 21.853906 -29.19984)
					(mid 20.315048 -25.484708)
					(end 16.599916 -23.94585)
				)
			)
		)
	)
	(zone
		(layers "In2.Cu" "In3.Cu" "In4.Cu" "In5.Cu")
		(hatch none 0.5)
		(connect_pads
			(clearance 0)
		)
		(min_thickness 0.25)
		(keepout
			(tracks not_allowed)
			(vias allowed)
			(pads allowed)
			(copperpour not_allowed)
			(footprints allowed)
		)
		(placement
			(enabled no)
			(sheetname "")
		)
		(fill yes
			(thermal_gap 0.5)
			(thermal_bridge_width 0.5)
			(island_removal_mode 0)
		)
		(polygon
			(pts
				(arc
					(start 16.599916 -24.17445)
					(mid 11.574526 -29.19984)
					(end 16.599916 -34.22523)
				)
				(arc
					(start 16.599916 -34.45383)
					(mid 12.884784 -32.914972)
					(end 11.345926 -29.19984)
				)
				(arc
					(start 11.345926 -29.19984)
					(mid 12.884784 -25.484708)
					(end 16.599916 -23.94585)
				)
			)
		)
	)
	(zone
		(layers "In2.Cu" "In3.Cu" "In4.Cu" "In5.Cu")
		(hatch none 0.5)
		(connect_pads
			(clearance 0)
		)
		(min_thickness 0.25)
		(keepout
			(tracks not_allowed)
			(vias allowed)
			(pads allowed)
			(copperpour not_allowed)
			(footprints allowed)
		)
		(placement
			(enabled no)
			(sheetname "")
		)
		(fill yes
			(thermal_gap 0.5)
			(thermal_bridge_width 0.5)
			(island_removal_mode 0)
		)
		(polygon
			(pts
				(arc
					(start 78.000098 -215.230456)
					(mid 83.130898 -210.099656)
					(end 78.000098 -204.968856)
				)
				(arc
					(start 78.000098 -204.968856)
					(mid 77.949298 -205.019656)
					(end 78.000098 -205.070456)
				)
				(arc
					(start 78.000098 -205.070456)
					(mid 83.029298 -210.099656)
					(end 78.000098 -215.128856)
				)
				(arc
					(start 78.000098 -215.128856)
					(mid 77.949298 -215.179656)
					(end 78.000098 -215.230456)
				)
			)
		)
	)
	(zone
		(layers "In2.Cu" "In3.Cu" "In4.Cu" "In5.Cu")
		(hatch none 0.5)
		(connect_pads
			(clearance 0)
		)
		(min_thickness 0.25)
		(keepout
			(tracks not_allowed)
			(vias allowed)
			(pads allowed)
			(copperpour not_allowed)
			(footprints allowed)
		)
		(placement
			(enabled no)
			(sheetname "")
		)
		(fill yes
			(thermal_gap 0.5)
			(thermal_bridge_width 0.5)
			(island_removal_mode 0)
		)
		(polygon
			(pts
				(arc
					(start 78.000098 -346.380562)
					(mid 83.130898 -341.249762)
					(end 78.000098 -336.118962)
				)
				(arc
					(start 78.000098 -336.118962)
					(mid 77.949298 -336.169762)
					(end 78.000098 -336.220562)
				)
				(arc
					(start 78.000098 -336.220562)
					(mid 83.029298 -341.249762)
					(end 78.000098 -346.278962)
				)
				(arc
					(start 78.000098 -346.278962)
					(mid 77.949298 -346.329762)
					(end 78.000098 -346.380562)
				)
			)
		)
	)
	(zone
		(layers "In2.Cu" "In3.Cu" "In4.Cu" "In5.Cu")
		(hatch none 0.5)
		(connect_pads
			(clearance 0)
		)
		(min_thickness 0.25)
		(keepout
			(tracks not_allowed)
			(vias allowed)
			(pads allowed)
			(copperpour not_allowed)
			(footprints allowed)
		)
		(placement
			(enabled no)
			(sheetname "")
		)
		(fill yes
			(thermal_gap 0.5)
			(thermal_bridge_width 0.5)
			(island_removal_mode 0)
		)
		(polygon
			(pts
				(arc
					(start 16.60017 -468.67445)
					(mid 21.62556 -473.69984)
					(end 16.60017 -478.72523)
				)
				(arc
					(start 16.60017 -478.95383)
					(mid 20.315302 -477.414972)
					(end 21.85416 -473.69984)
				)
				(arc
					(start 21.85416 -473.69984)
					(mid 20.315302 -469.984708)
					(end 16.60017 -468.44585)
				)
			)
		)
	)
	(zone
		(layers "In2.Cu" "In3.Cu" "In4.Cu" "In5.Cu")
		(hatch none 0.5)
		(connect_pads
			(clearance 0)
		)
		(min_thickness 0.25)
		(keepout
			(tracks not_allowed)
			(vias allowed)
			(pads allowed)
			(copperpour not_allowed)
			(footprints allowed)
		)
		(placement
			(enabled no)
			(sheetname "")
		)
		(fill yes
			(thermal_gap 0.5)
			(thermal_bridge_width 0.5)
			(island_removal_mode 0)
		)
		(polygon
			(pts
				(arc
					(start 78.000098 -126.330456)
					(mid 83.130898 -121.199656)
					(end 78.000098 -116.068856)
				)
				(arc
					(start 78.000098 -116.068856)
					(mid 77.949298 -116.119656)
					(end 78.000098 -116.170456)
				)
				(arc
					(start 78.000098 -116.170456)
					(mid 83.029298 -121.199656)
					(end 78.000098 -126.228856)
				)
				(arc
					(start 78.000098 -126.228856)
					(mid 77.949298 -126.279656)
					(end 78.000098 -126.330456)
				)
			)
		)
	)
	(zone
		(layers "In2.Cu" "In3.Cu" "In4.Cu" "In5.Cu")
		(hatch none 0.5)
		(connect_pads
			(clearance 0)
		)
		(min_thickness 0.25)
		(keepout
			(tracks not_allowed)
			(vias allowed)
			(pads allowed)
			(copperpour not_allowed)
			(footprints allowed)
		)
		(placement
			(enabled no)
			(sheetname "")
		)
		(fill yes
			(thermal_gap 0.5)
			(thermal_bridge_width 0.5)
			(island_removal_mode 0)
		)
		(polygon
			(pts
				(arc
					(start 16.60017 -113.07445)
					(mid 11.57478 -118.09984)
					(end 16.60017 -123.12523)
				)
				(arc
					(start 16.60017 -123.35383)
					(mid 12.885038 -121.814972)
					(end 11.34618 -118.09984)
				)
				(arc
					(start 11.34618 -118.09984)
					(mid 12.885038 -114.384708)
					(end 16.60017 -112.84585)
				)
			)
		)
	)
	(zone
		(layers "In2.Cu" "In3.Cu" "In4.Cu" "In5.Cu")
		(hatch none 0.5)
		(connect_pads
			(clearance 0)
		)
		(min_thickness 0.25)
		(keepout
			(tracks not_allowed)
			(vias allowed)
			(pads allowed)
			(copperpour not_allowed)
			(footprints allowed)
		)
		(placement
			(enabled no)
			(sheetname "")
		)
		(fill yes
			(thermal_gap 0.5)
			(thermal_bridge_width 0.5)
			(island_removal_mode 0)
		)
		(polygon
			(pts
				(arc
					(start 78.000098 -215.230456)
					(mid 72.869298 -210.099656)
					(end 78.000098 -204.968856)
				)
				(arc
					(start 78.000098 -204.968856)
					(mid 78.050898 -205.019656)
					(end 78.000098 -205.070456)
				)
				(arc
					(start 78.000098 -205.070456)
					(mid 72.970898 -210.099656)
					(end 78.000098 -215.128856)
				)
				(arc
					(start 78.000098 -215.128856)
					(mid 78.050898 -215.179656)
					(end 78.000098 -215.230456)
				)
			)
		)
	)
	(zone
		(layers "In2.Cu" "In3.Cu" "In4.Cu" "In5.Cu")
		(hatch none 0.5)
		(connect_pads
			(clearance 0)
		)
		(min_thickness 0.25)
		(keepout
			(tracks not_allowed)
			(vias allowed)
			(pads allowed)
			(copperpour not_allowed)
			(footprints allowed)
		)
		(placement
			(enabled no)
			(sheetname "")
		)
		(fill yes
			(thermal_gap 0.5)
			(thermal_bridge_width 0.5)
			(island_removal_mode 0)
		)
		(polygon
			(pts
				(arc
					(start 16.60017 -468.67445)
					(mid 11.57478 -473.69984)
					(end 16.60017 -478.72523)
				)
				(arc
					(start 16.60017 -478.95383)
					(mid 12.885038 -477.414972)
					(end 11.34618 -473.69984)
				)
				(arc
					(start 11.34618 -473.69984)
					(mid 12.885038 -469.984708)
					(end 16.60017 -468.44585)
				)
			)
		)
	)
	(zone
		(layers "In2.Cu" "In3.Cu" "In4.Cu" "In5.Cu")
		(hatch none 0.5)
		(connect_pads
			(clearance 0)
		)
		(min_thickness 0.25)
		(keepout
			(tracks not_allowed)
			(vias allowed)
			(pads allowed)
			(copperpour not_allowed)
			(footprints allowed)
		)
		(placement
			(enabled no)
			(sheetname "")
		)
		(fill yes
			(thermal_gap 0.5)
			(thermal_bridge_width 0.5)
			(island_removal_mode 0)
		)
		(polygon
			(pts
				(arc
					(start 16.60017 -113.07445)
					(mid 21.62556 -118.09984)
					(end 16.60017 -123.12523)
				)
				(arc
					(start 16.60017 -123.35383)
					(mid 20.315302 -121.814972)
					(end 21.85416 -118.09984)
				)
				(arc
					(start 21.85416 -118.09984)
					(mid 20.315302 -114.384708)
					(end 16.60017 -112.84585)
				)
			)
		)
	)
	(zone
		(layers "In2.Cu" "In3.Cu" "In4.Cu" "In5.Cu")
		(hatch none 0.5)
		(connect_pads
			(clearance 0)
		)
		(min_thickness 0.25)
		(keepout
			(tracks not_allowed)
			(vias allowed)
			(pads allowed)
			(copperpour not_allowed)
			(footprints allowed)
		)
		(placement
			(enabled no)
			(sheetname "")
		)
		(fill yes
			(thermal_gap 0.5)
			(thermal_bridge_width 0.5)
			(island_removal_mode 0)
		)
		(polygon
			(pts
				(arc
					(start 78.000098 -435.280562)
					(mid 72.869298 -430.149762)
					(end 78.000098 -425.018962)
				)
				(arc
					(start 78.000098 -425.018962)
					(mid 78.050898 -425.069762)
					(end 78.000098 -425.120562)
				)
				(arc
					(start 78.000098 -425.120562)
					(mid 72.970898 -430.149762)
					(end 78.000098 -435.178962)
				)
				(arc
					(start 78.000098 -435.178962)
					(mid 78.050898 -435.229762)
					(end 78.000098 -435.280562)
				)
			)
		)
	)
	(zone
		(layers "In2.Cu" "In3.Cu" "In4.Cu" "In5.Cu")
		(hatch none 0.5)
		(connect_pads
			(clearance 0)
		)
		(min_thickness 0.25)
		(keepout
			(tracks not_allowed)
			(vias allowed)
			(pads allowed)
			(copperpour not_allowed)
			(footprints allowed)
		)
		(placement
			(enabled no)
			(sheetname "")
		)
		(fill yes
			(thermal_gap 0.5)
			(thermal_bridge_width 0.5)
			(island_removal_mode 0)
		)
		(polygon
			(pts
				(arc
					(start 78.000098 -37.430456)
					(mid 72.869298 -32.299656)
					(end 78.000098 -27.168856)
				)
				(arc
					(start 78.000098 -27.168856)
					(mid 78.050898 -27.219656)
					(end 78.000098 -27.270456)
				)
				(arc
					(start 78.000098 -27.270456)
					(mid 72.970898 -32.299656)
					(end 78.000098 -37.328856)
				)
				(arc
					(start 78.000098 -37.328856)
					(mid 78.050898 -37.379656)
					(end 78.000098 -37.430456)
				)
			)
		)
	)
	(zone
		(layers "In2.Cu" "In3.Cu" "In4.Cu" "In5.Cu")
		(hatch none 0.5)
		(connect_pads
			(clearance 0)
		)
		(min_thickness 0.25)
		(keepout
			(tracks not_allowed)
			(vias allowed)
			(pads allowed)
			(copperpour not_allowed)
			(footprints allowed)
		)
		(placement
			(enabled no)
			(sheetname "")
		)
		(fill yes
			(thermal_gap 0.5)
			(thermal_bridge_width 0.5)
			(island_removal_mode 0)
		)
		(polygon
			(pts
				(arc
					(start 16.60017 -290.87445)
					(mid 21.62556 -295.89984)
					(end 16.60017 -300.92523)
				)
				(arc
					(start 16.60017 -301.15383)
					(mid 20.315302 -299.614972)
					(end 21.85416 -295.89984)
				)
				(arc
					(start 21.85416 -295.89984)
					(mid 20.315302 -292.184708)
					(end 16.60017 -290.64585)
				)
			)
		)
	)
)
